FILE_TYPE = MULTI_PHYS_TABLE;

PART 'Q_CAP'

{========================================================================================}
:VALUE      | VOLTAGE | TOLERANCE | PACK_TYPE   | MATERIAL  | PART_NUMBER        = STANDARD        | LIFECYCLE          | ASS_PART | PART_NUMBER       | JEDEC_TYPE                | ALT_SYMBOLS                                                          | VALUE      | RATED_VOLTAGE | TOL      | CLASS      | DESCRIPTION                                                    | COMPONENT_TYPE | LEAD_LENGTH | LPID | DATE       ;
{========================================================================================}
 '1UF'      | '25V'   | '10%'     | '0603'      | 'COG'     | 'TMP_QCH5104K9906'(!) = 'End of Design' | 'Comp-Release Qty' | ''       | 'CH5104K9906'     |'C0603'| '(SMC0603AW)'                                                        | '1UF'      | '25V'         | '10%'    | 'DISCRETE' | 'CHIP0603'                                                     | 'CHIP0603'     | ''          | ''   | ''        
 '1UF'      | '25V'   | '10%'     | '0603'      | 'EMPTY'   | 'TMP_QCH5104K9906'(!) = 'End of Design' | 'Comp-Release Qty' | ''       | 'CH5104K9906'     |'C0603'| '(SMC0603AW)'                                                        | 'NA'       | '25V'         | '10%'    | 'IO'       | 'CHIP0603'                                                     | 'CHIP0603'     | ''          | ''   | ''        
 '0.1UF'    | '25V'   | '10%'     | '0603'      | 'X7R'     | 'TMP_QCH41004K910'(!) = 'End of Design' | 'Comp-Approve'     | ''       | 'CH41004K910'     |'C0603'| '(SMC0603AW)'                                                        | '0.1UF'    | '25V'         | '10%'    | 'DISCRETE' | 'CHIP0603'                                                     | 'CHIP0603'     | ''          | ''   | ''        
 '0.1UF'    | '25V'   | '10%'     | '0603'      | 'EMPTY'   | 'TMP_QCH41004K910'(!) = 'End of Design' | 'Comp-Approve'     | ''       | 'CH41004K910'     |'C0603'| '(SMC0603AW)'                                                        | 'NA'       | '25V'         | '10%'    | 'IO'       | 'CHIP0603'                                                     | 'CHIP0603'     | ''          | ''   | ''        
 '15PF'     | '50V'   | '5%'      | '0603'      | 'X7R'     | 'TMP_QCH0156J0910'(!) = 'End of Design' | 'Comp-Approve'     | ''       | 'CH0156J0910'     |'C0603'| '(SMC0603AW)'                                                        | '15PF'     | '50V'         | '5%'     | 'DISCRETE' | 'CHIP0603'                                                     | 'CHIP0603'     | ''          | ''   | ''        
 '15PF'     | '50V'   | '5%'      | '0603'      | 'EMPTY'   | 'TMP_QCH0156J0910'(!) = 'End of Design' | 'Comp-Approve'     | ''       | 'CH0156J0910'     |'C0603'| '(SMC0603AW)'                                                        | 'NA'       | '50V'         | '5%'     | 'IO'       | 'CHIP0603'                                                     | 'CHIP0603'     | ''          | ''   | ''        
 '3300PF'   | '50V'   | '10%'     | '0402'      | 'X7R'     | 'TMP_QCH2336K1B12'(!) = ''              | ''                 | ''       | 'CH2336K1B12'     |'C0402'| '(C0402-0201)'                                                       | '3300PF'   | '50V'         | '10%'    | 'DISCRETE' | 'CHIP0402'                                                     | 'CHIP0402'     | ''          | ''   | ''        
 '3300PF'   | '50V'   | '10%'     | '0402'      | 'EMPTY'   | 'TMP_QCH2336K1B12'(!) = ''              | ''                 | ''       | 'CH2336K1B12'     |'C0402'| '(C0402-0201)'                                                       | 'NA'       | '50V'         | '10%'    | 'IO'       | 'CHIP0402'                                                     | 'CHIP0402'     | ''          | ''   | ''        
 '10UF'     | '25V'   | '20%'     | '1206'      | 'X6S'     | 'TMP_QCH61004M2E8'(!) = 'End of Design' | 'Comp-Approve'     | ''       | 'CH61004M2E8'     |'C1206_H76'| '(SMC1206AW)'                                                        | '10UF'     | '25V'         | '20%'    | 'DISCRETE' | 'CHIP1206'                                                     | 'CHIP1206'     | ''          | ''   | ''        
 '10UF'     | '25V'   | '20%'     | '1206'      | 'EMPTY'   | 'TMP_QCH61004M2E8'(!) = 'End of Design' | 'Comp-Approve'     | ''       | 'CH61004M2E8'     |'C1206_H76'| '(SMC1206AW)'                                                        | 'NA'       | '25V'         | '20%'    | 'IO'       | 'CHIP1206'                                                     | 'CHIP1206'     | ''          | ''   | ''        
 '1UF'      | '16V'   | '10%'     | '0402'      | 'X5R'     | 'TMP_QCH5103K9B00'(!) = 'End of Design' | 'Comp-Approve'     | ''       | 'CH5103K9B00'     |'C0402'| '(C0402-0201)'                                                       | '1UF'      | '16V'         | '10%'    | 'DISCRETE' | 'CHIP0402'                                                     | 'CHIP0402'     | ''          | ''   | ''        
 '1UF'      | '16V'   | '10%'     | '0402'      | 'EMPTY'   | 'TMP_QCH5103K9B00'(!) = 'End of Design' | 'Comp-Approve'     | ''       | 'CH5103K9B00'     |'C0402'| '(C0402-0201)'                                                       | 'NA'       | '16V'         | '10%'    | 'IO'       | 'CHIP0402'                                                     | 'CHIP0402'     | ''          | ''   | ''        
 '1UF'      | '25V'   | '10%'     | '0805'      | 'X7R'     | 'TMP_QCH51004KE12'(!) = 'End of Design' | 'Comp-Approve'     | ''       | 'CH51004KE12'     |'C0805_H61'| '(SMC0805AW)'                                                        | '1UF'      | '25V'         | '10%'    | 'DISCRETE' | 'CHIP0805'                                                     | 'CHIP0805'     | ''          | ''   | ''        
 '1UF'      | '25V'   | '10%'     | '0805'      | 'EMPTY'   | 'TMP_QCH51004KE12'(!) = 'End of Design' | 'Comp-Approve'     | ''       | 'CH51004KE12'     |'C0805_H61'| '(SMC0805AW)'                                                        | 'NA'       | '25V'         | '10%'    | 'IO'       | 'CHIP0805'                                                     | 'CHIP0805'     | ''          | ''   | ''        
 '1UF'      | '50V'   | '10%'     | '1206'      | 'X7R'     | 'TMP_QCH5106K1200'(!) = 'End of Design' | 'Comp-Approve'     | ''       | 'CH5106K1200'     |'C1206_H56'| '(SMC1206AW)'                                                        | '1UF'      | '50V'         | '10%'    | 'DISCRETE' | 'CHIP1206'                                                     | 'CHIP1206'     | ''          | ''   | ''        
 '1UF'      | '50V'   | '10%'     | '1206'      | 'EMPTY'   | 'TMP_QCH5106K1200'(!) = 'End of Design' | 'Comp-Approve'     | ''       | 'CH5106K1200'     |'C1206_H56'| '(SMC1206AW)'                                                        | 'NA'       | '50V'         | '10%'    | 'IO'       | 'CHIP1206'                                                     | 'CHIP1206'     | ''          | ''   | ''        
 '0.47UF'   | '25V'   | '10%'     | '0805'      | 'X7R'     | 'TMP_QCH44704KE14'(!) = ''              | ''                 | ''       | 'CH44704KE14'     |'C0805_H61'| '(SMC0805AW)'                                                        | '0.47UF'   | '25V'         | '10%'    | 'DISCRETE' | 'CHIP0805'                                                     | 'CHIP0805'     | ''          | ''   | ''        
 '0.47UF'   | '25V'   | '10%'     | '0805'      | 'EMPTY'   | 'TMP_QCH44704KE14'(!) = ''              | ''                 | ''       | 'CH44704KE14'     |'C0805_H61'| '(SMC0805AW)'                                                        | 'NA'       | '25V'         | '10%'    | 'IO'       | 'CHIP0805'                                                     | 'CHIP0805'     | ''          | ''   | ''        
 '0.22UF'   | '25V'   | '20%'     | '0805'      | 'X7R'     | 'TMP_QCH42204ME13'(!) = 'End of Design' | 'Comp-Approve'     | ''       | 'CH5106K1200'     |'C0805_H43'| '(SMC0805AW)'                                                        | '0.22UF'   | '25V'         | '20%'    | 'DISCRETE' | 'CHIP0805'                                                     | 'CHIP0805'     | ''          | ''   | ''        
 '0.22UF'   | '25V'   | '20%'     | '0805'      | 'EMPTY'   | 'TMP_QCH42204ME13'(!) = 'End of Design' | 'Comp-Approve'     | ''       | 'CH5106K1200'     |'C0805_H43'| '(SMC0805AW)'                                                        | 'NA'       | '25V'         | '20%'    | 'IO'       | 'CHIP0805'                                                     | 'CHIP0805'     | ''          | ''   | ''        
 '100PF'    | '50V'   | '10%'     | '0402'      | 'X7R'     | 'TMP_QCH1106K1B00'(!) = 'End of Design' | 'Comp-Approve'     | ''       | 'CH1106K1B00'     |'C0402'| '(C0402-0201)'                                                       | '100PF'    | '50V'         | '10%'    | 'DISCRETE' | 'CHIP0402'                                                     | 'CHIP0402'     | ''          | ''   | ''        
 '100PF'    | '50V'   | '10%'     | '0402'      | 'EMPTY'   | 'TMP_QCH1106K1B00'(!) = 'End of Design' | 'Comp-Approve'     | ''       | 'CH1106K1B00'     |'C0402'| '(C0402-0201)'                                                       | 'NA'       | '50V'         | '10%'    | 'IO'       | 'CHIP0402'                                                     | 'CHIP0402'     | ''          | ''   | ''        
 '150PF'    | '50V'   | '5%'      | '0402'      | 'NPO'     | 'TMP_QCH11506JB08'(!) = ''              | ''                 | ''       | 'CH11506JB08'     |'C0402'| '(C0402-0201)'                                                       | '150PF'    | '50V'         | '5%'     | 'DISCRETE' | 'CHIP0402'                                                     | 'CHIP0402'     | ''          | ''   | ''        
 '150PF'    | '50V'   | '5%'      | '0402'      | 'EMPTY'   | 'TMP_QCH11506JB08'(!) = ''              | ''                 | ''       | 'CH11506JB08'     |'C0402'| '(C0402-0201)'                                                       | 'NA'       | '50V'         | '5%'     | 'IO'       | 'CHIP0402'                                                     | 'CHIP0402'     | ''          | ''   | ''        
 '100PF'    | '50V'   | '5%'      | '0603'      | 'NPO'     | 'TMP_QCH11006J901'(!) = 'End of Design' | 'Comp-Approve'     | ''       | 'CH11006J901'     |'C0603'| '(SMC0603AW)'                                                        | '100PF'    | '50V'         | '5%'     | 'DISCRETE' | 'CHIP0603'                                                     | 'CHIP0603'     | ''          | ''   | ''        
 '100PF'    | '50V'   | '5%'      | '0603'      | 'EMPTY'   | 'TMP_QCH11006J901'(!) = 'End of Design' | 'Comp-Approve'     | ''       | 'CH11006J901'     |'C0603'| '(SMC0603AW)'                                                        | 'NA'       | '50V'         | '5%'     | 'IO'       | 'CHIP0603'                                                     | 'CHIP0603'     | ''          | ''   | ''        
 '220PF'    | '50V'   | '5%'      | '0603'      | 'NPO'     | 'TMP_QCH12206J901'(!) = 'End of Design' | 'Comp-Approve'     | ''       | 'CH12206J901'     |'C0603'| '(SMC0603AW)'                                                        | '220PF'    | '50V'         | '5%'     | 'DISCRETE' | 'CHIP0603'                                                     | 'CHIP0603'     | ''          | ''   | ''        
 '220PF'    | '50V'   | '5%'      | '0603'      | 'EMPTY'   | 'TMP_QCH12206J901'(!) = 'End of Design' | 'Comp-Approve'     | ''       | 'CH12206J901'     |'C0603'| '(SMC0603AW)'                                                        | 'NA'       | '50V'         | '5%'     | 'IO'       | 'CHIP0603'                                                     | 'CHIP0603'     | ''          | ''   | ''        
 '470PF'    | '50V'   | '5%'      | '0603'      | 'NPO'     | 'TMP_QCH14706J904'(!) = 'End of Design' | 'Comp-Release Qty' | ''       | 'CH14706J904'     |'C0603'| '(SMC0603AW)'                                                        | '470PF'    | '50V'         | '5%'     | 'DISCRETE' | 'CHIP0603'                                                     | 'CHIP0603'     | ''          | ''   | ''        
 '470PF'    | '50V'   | '5%'      | '0603'      | 'EMPTY'   | 'TMP_QCH14706J904'(!) = 'End of Design' | 'Comp-Release Qty' | ''       | 'CH14706J904'     |'C0603'| '(SMC0603AW)'                                                        | 'NA'       | '50V'         | '5%'     | 'IO'       | 'CHIP0603'                                                     | 'CHIP0603'     | ''          | ''   | ''        
 '680PF'    | '50V'   | '10%'     | '0603'      | 'X7R'     | 'TMP_QCH16806K918'(!) = ''              | ''                 | ''       | 'CH16806K918'     |'C0603'| '(SMC0603AW)'                                                        | '680PF'    | '50V'         | '10%'    | 'DISCRETE' | 'CHIP0603'                                                     | 'CHIP0603'     | ''          | ''   | ''        
 '680PF'    | '50V'   | '10%'     | '0603'      | 'EMPTY'   | 'TMP_QCH16806K918'(!) = ''              | ''                 | ''       | 'CH16806K918'     |'C0603'| '(SMC0603AW)'                                                        | 'NA'       | '50V'         | '10%'    | 'IO'       | 'CHIP0603'                                                     | 'CHIP0603'     | ''          | ''   | ''        
 '0.022UF'  | '25V'   | '10%'     | '0603'      | 'X7R'     | 'TMP_QCH32204K918'(!) = 'End of Design' | 'Comp-Approve'     | ''       | 'CH32204K918'     |'C0603'| '(SMC0603AW)'                                                        | '0.022UF'  | '25V'         | '10%'    | 'DISCRETE' | 'CHIP0603'                                                     | 'CHIP0603'     | ''          | ''   | ''        
 '0.022UF'  | '25V'   | '10%'     | '0603'      | 'EMPTY'   | 'TMP_QCH32204K918'(!) = 'End of Design' | 'Comp-Approve'     | ''       | 'CH32204K918'     |'C0603'| '(SMC0603AW)'                                                        | 'NA'       | '25V'         | '10%'    | 'IO'       | 'CHIP0603'                                                     | 'CHIP0603'     | ''          | ''   | ''        
 '0.22UF'   | '25V'   | '10%'     | '0603'      | 'X7R'     | 'TMP_QCH4224K1900'(!) = 'End of Design' | 'Comp-Release Qty' | ''       | 'CH4224K1900'     |'C0603'| '(SMC0603AW)'                                                        | '0.22UF'   | '25V'         | '10%'    | 'DISCRETE' | 'CHIP0603'                                                     | 'CHIP0603'     | ''          | ''   | ''        
 '0.22UF'   | '25V'   | '10%'     | '0603'      | 'EMPTY'   | 'TMP_QCH4224K1900'(!) = 'End of Design' | 'Comp-Release Qty' | ''       | 'CH4224K1900'     |'C0603'| '(SMC0603AW)'                                                        | 'NA'       | '25V'         | '10%'    | 'IO'       | 'CHIP0603'                                                     | 'CHIP0603'     | ''          | ''   | ''        
 '10UF'     | '10V'   | '10%'     | '0805'      | 'X7R'     | 'TMP_QCH6102K1A00'(!) = ''              | ''                 | ''       | 'CH6102K1A00'     |'C0805_H61'| '(SMC0805AW)'                                                        | '10UFF'    | '10V'         | '10%'    | 'DISCRETE' | 'CHIP0805'                                                     | 'CHIP0805'     | ''          | ''   | ''        
 '10UF'     | '10V'   | '10%'     | '0805'      | 'EMPTY'   | 'TMP_QCH6102K1A00'(!) = ''              | ''                 | ''       | 'CH6102K1A00'     |'C0805_H61'| '(SMC0805AW)'                                                        | 'NA'       | '10V'         | '10%'    | 'IO'       | 'CHIP0805'                                                     | 'CHIP0805'     | ''          | ''   | ''        
 '10UF'     | '10V'   | '10%'     | '1206'      | 'X5R'     | 'TMP_QCH61002K297'(!) = 'End of Design' | 'Comp-Approve'     | ''       | 'CH61002K297'     |'C1206_H76'| '(SMC1206AW)'                                                        | '10UF'     | '10V'         | '10%'    | 'DISCRETE' | 'CHIP1206'                                                     | 'CHIP1206'     | ''          | ''   | ''        
 '10UF'     | '10V'   | '10%'     | '1206'      | 'EMPTY'   | 'TMP_QCH61002K297'(!) = 'End of Design' | 'Comp-Approve'     | ''       | 'CH61002K297'     |'C1206_H76'| '(SMC1206AW)'                                                        | 'NA'       | '10V'         | '10%'    | 'IO'       | 'CHIP1206'                                                     | 'CHIP1206'     | ''          | ''   | ''        
 '1UF'      | '10V'   | '10%'     | '0603'      | 'X7R'     | 'TMP_QCH5102K1906'(!) = 'End of Design' | 'Comp-Approve'     | ''       | 'CH5102K1906'     |'C0603'| '(SMC0603AW)'                                                        | '1UF'      | '10V'         | '10%'    | 'DISCRETE' | 'CHIP0603'                                                     | 'CHIP0603'     | ''          | ''   | ''        
 '1UF'      | '10V'   | '10%'     | '0603'      | 'EMPTY'   | 'TMP_QCH5102K1906'(!) = 'End of Design' | 'Comp-Approve'     | ''       | 'CH5102K1906'     |'C0603'| '(SMC0603AW)'                                                        | 'NA'       | '10V'         | '10%'    | 'IO'       | 'CHIP0603'                                                     | 'CHIP0603'     | ''          | ''   | ''        
 '47UF'     | '4V'    | '20%'     | '1206'      | 'X6S'     | 'TMP_QCH647KME200'(!) = 'End of Design' | 'Comp-Approve'     | ''       | 'CH647KME200'     |'C1206_H66'| '(SMC1206AW)'                                                        | '47UF'     | '4V'          | '20%'    | 'DISCRETE' | 'CHIP1206'                                                     | 'CHIP1206'     | ''          | ''   | ''        
 '47UF'     | '4V'    | '20%'     | '1206'      | 'EMPTY'   | 'TMP_QCH647KME200'(!) = 'End of Design' | 'Comp-Approve'     | ''       | 'CH647KME200'     |'C1206_H66'| '(SMC1206AW)'                                                        | 'NA'       | '4V'          | '20%'    | 'IO'       | 'CHIP1206'                                                     | 'CHIP1206'     | ''          | ''   | ''        
 '22UF'     | '6.3V'  | '20%'     | '0805'      | 'X5R'     | 'TMP_QCH6221M9A02'(!) = 'End of Design' | 'End of Life'      | ''       | 'CH6221M9A02'     |'C0805_H61_EOL'| '(SMC0805AW)'                                                        | '22UF'     | '6.3V'        | '20%'    | 'DISCRETE' | 'CHIP0805'                                                     | 'CHIP0805'     | ''          | ''   | ''        
 '22UF'     | '6.3V'  | '20%'     | '0805'      | 'EMPTY'   | 'TMP_QCH6221M9A02'(!) = 'End of Design' | 'End of Life'      | ''       | 'CH6221M9A02'     |'C0805_H61_EOL'| '(SMC0805AW)'                                                        | 'NA'       | '6.3V'        | '20%'    | 'IO'       | 'CHIP0805'                                                     | 'CHIP0805'     | ''          | ''   | ''        
 '22UF'     | '6.3V'  | '20%'     | '1206'      | 'X7R'     | 'TMP_QCH6221M1203'(!) = 'End of Design' | 'Comp-Approve'     | ''       | 'CH6221M1203'     |'C1206_H76'| '(SMC1206AW)'                                                        | '22UF'     | '6.3V'        | '20%'    | 'DISCRETE' | 'CHIP1206'                                                     | 'CHIP1206'     | ''          | ''   | ''        
 '22UF'     | '6.3V'  | '20%'     | '1206'      | 'EMPTY'   | 'TMP_QCH6221M1203'(!) = 'End of Design' | 'Comp-Approve'     | ''       | 'CH6221M1203'     |'C1206_H76'| '(SMC1206AW)'                                                        | 'NA'       | '6.3V'        | '20%'    | 'IO'       | 'CHIP1206'                                                     | 'CHIP1206'     | ''          | ''   | ''        
 '22UF'     | '4V'    | '20%'     | '0805'      | 'X6S'     | 'TMP_QCH622KMEA01'(!) = 'End of Design' | 'Comp-Approve'     | ''       | 'CH622KMEA01'     |'C0805_H61'| '(SMC0805AW)'                                                        | '22UF'     | '4V'          | '20%'    | 'DISCRETE' | 'CHIP0805'                                                     | 'CHIP0805'     | ''          | ''   | ''        
 '22UF'     | '4V'    | '20%'     | '0805'      | 'EMPTY'   | 'TMP_QCH622KMEA01'(!) = 'End of Design' | 'Comp-Approve'     | ''       | 'CH622KMEA01'     |'C0805_H61'| '(SMC0805AW)'                                                        | 'NA'       | '4V'          | '20%'    | 'IO'       | 'CHIP0805'                                                     | 'CHIP0805'     | ''          | ''   | ''        
 '0.22UF'   | '16V'   | '10%'     | '0603'      | 'X7R'     | 'TMP_QCH4223K1909'(!) = 'End of Design' | 'Comp-Approve'     | ''       | 'CH4223K1909'     |'C0603'| '(SMC0603AW)'                                                        | '0.22UF'   | '16V'         | '10%'    | 'DISCRETE' | 'CHIP0603'                                                     | 'CHIP0603'     | ''          | ''   | ''        
 '0.22UF'   | '16V'   | '10%'     | '0603'      | 'EMPTY'   | 'TMP_QCH4223K1909'(!) = 'End of Design' | 'Comp-Approve'     | ''       | 'CH4223K1909'     |'C0603'| '(SMC0603AW)'                                                        | 'NA'       | '16V'         | '10%'    | 'IO'       | 'CHIP0603'                                                     | 'CHIP0603'     | ''          | ''   | ''        
 '0.47UF'   | '16V'   | '10%'     | '0603'      | 'X7R'     | 'TMP_QCH4473K1902'(!) = 'End of Design' | 'Comp-Approve'     | ''       | 'CH4473K1902'     |'C0603'| '(SMC0603AW)'                                                        | '0.47UF'   | '16V'         | '10%'    | 'DISCRETE' | 'CHIP0603'                                                     | 'CHIP0603'     | ''          | ''   | ''        
 '0.47UF'   | '16V'   | '10%'     | '0603'      | 'EMPTY'   | 'TMP_QCH4473K1902'(!) = 'End of Design' | 'Comp-Approve'     | ''       | 'CH4473K1902'     |'C0603'| '(SMC0603AW)'                                                        | 'NA'       | '16V'         | '10%'    | 'IO'       | 'CHIP0603'                                                     | 'CHIP0603'     | ''          | ''   | ''        
 '10UF'     | '16V'   | '10%'     | '1206'      | 'X7R'     | 'TMP_QCH6103K1201'(!) = 'End of Design' | 'Comp-Approve'     | ''       | 'CH6103K1201'     |'C1206_H66'| '(SMC1206AW)'                                                        | '10UF'     | '16V'         | '10%'    | 'DISCRETE' | 'CHIP1206'                                                     | 'CHIP1206'     | ''          | ''   | ''        
 '10UF'     | '16V'   | '10%'     | '1206'      | 'EMPTY'   | 'TMP_QCH6103K1201'(!) = 'End of Design' | 'Comp-Approve'     | ''       | 'CH6103K1201'     |'C1206_H66'| '(SMC1206AW)'                                                        | 'NA'       | '16V'         | '10%'    | 'IO'       | 'CHIP1206'                                                     | 'CHIP1206'     | ''          | ''   | ''        
 '2.2UF'    | '16V'   | '10%'     | '0603'      | 'X5R'     | 'TMP_QCH5223K9901'(!) = 'End of Design' | 'Comp-Release Qty' | ''       | 'CH5223K9901'     |'C0603'| '(SMC0603AW)'                                                        | '2.2UF'    | '16V'         | '10%'    | 'DISCRETE' | 'CHIP0603'                                                     | 'CHIP0603'     | ''          | ''   | ''        
 '2.2UF'    | '16V'   | '10%'     | '0603'      | 'EMPTY'   | 'TMP_QCH5223K9901'(!) = 'End of Design' | 'Comp-Release Qty' | ''       | 'CH5223K9901'     |'C0603'| '(SMC0603AW)'                                                        | 'NA'       | '16V'         | '10%'    | 'IO'       | 'CHIP0603'                                                     | 'CHIP0603'     | ''          | ''   | ''        
 '0.22UF'   | '10V'   | '10%'     | '0402'      | 'X5R'     | 'TMP_QCH4222K9B04'(!) = 'End of Design' | 'Comp-Release Qty' | ''       | 'CH4222K9B04'     |'C0402'| '(C0402-0201)'                                                       | '0.22UF'   | '10V'         | '10%'    | 'DISCRETE' | 'CHIP0402'                                                     | 'CHIP0402'     | ''          | ''   | ''        
 '0.22UF'   | '10V'   | '10%'     | '0402'      | 'EMPTY'   | 'TMP_QCH4222K9B04'(!) = 'End of Design' | 'Comp-Release Qty' | ''       | 'CH4222K9B04'     |'C0402'| '(C0402-0201)'                                                       | 'NA'       | '10V'         | '10%'    | 'IO'       | 'CHIP0402'                                                     | 'CHIP0402'     | ''          | ''   | ''        
 '1800PF'   | '50V'   | '10%'     | '0603'      | 'X7R'     | 'TMP_QCH21806K916'(!) = 'End of Design' | 'Comp-Approve'     | ''       | 'CH21806K916'     |'C0603'| '(SMC0603AW)'                                                        | '1800PF'   | '50V'         | '10%'    | 'DISCRETE' | 'CHIP0603'                                                     | 'CHIP0603'     | ''          | ''   | ''        
 '1800PF'   | '50V'   | '10%'     | '0603'      | 'EMPTY'   | 'TMP_QCH21806K916'(!) = 'End of Design' | 'Comp-Approve'     | ''       | 'CH21806K916'     |'C0603'| '(SMC0603AW)'                                                        | 'NA'       | '50V'         | '10%'    | 'IO'       | 'CHIP0603'                                                     | 'CHIP0603'     | ''          | ''   | ''        
 '10PF'     | '50V'   | '1%'      | '0402'      | 'NPO'     | 'TMP_QCH0106F0B00'(!) = ''              | ''                 | ''       | 'CH0106F0B00'     |'C0402'| '(C0402-0201)'                                                       | '10PF'     | '50V'         | '1%'     | 'DISCRETE' | 'CHIP0402'                                                     | 'CHIP0402'     | ''          | ''   | ''        
 '10PF'     | '50V'   | '1%'      | '0402'      | 'EMPTY'   | 'TMP_QCH0106F0B00'(!) = ''              | ''                 | ''       | 'CH0106F0B00'     |'C0402'| '(C0402-0201)'                                                       | 'NA'       | '50V'         | '1%'     | 'IO'       | 'CHIP0402'                                                     | 'CHIP0402'     | ''          | ''   | ''        
 '1000PF'   | '16V'   | '10%'     | '0402'      | 'X7R'     | 'TMP_QCH2103K1B04'(!) = ''              | ''                 | ''       | 'CH2103K1B04'     |'C0402'| '(C0402-0201,C0402_OCTAGONXA)'                                       | '1000PF'   | '16V'         | '10%'    | 'DISCRETE' | 'CHIP0402'                                                     | 'CHIP0402'     | ''          | ''   | ''        
 '1000PF'   | '16V'   | '10%'     | '0402'      | 'EMPTY'   | 'TMP_QCH2103K1B04'(!) = ''              | ''                 | ''       | 'CH2103K1B04'     |'C0402'| '(C0402-0201,C0402_OCTAGONXA)'                                       | 'NA'       | '16V'         | '10%'    | 'IO'       | 'CHIP0402'                                                     | 'CHIP0402'     | ''          | ''   | ''        
 '0.01UF'   | '16V'   | '10%'     | '0402'      | 'X7R'     | 'TMP_QCH31003KB11'(!) = 'End of Design' | 'Comp-Approve'     | ''       | 'CH31003KB11'     |'C0402'| '(C0402-0201)'                                                       | '0.01UF'   | '16V'         | '10%'    | 'DISCRETE' | 'CHIP0402'                                                     | 'CHIP0402'     | ''          | ''   | ''        
 '0.01UF'   | '16V'   | '10%'     | '0402'      | 'EMPTY'   | 'TMP_QCH31003KB11'(!) = 'End of Design' | 'Comp-Approve'     | ''       | 'CH31003KB11'     |'C0402'| '(C0402-0201)'                                                       | 'NA'       | '16V'         | '10%'    | 'IO'       | 'CHIP0402'                                                     | 'CHIP0402'     | ''          | ''   | ''        
 '4.7UF'    | '16V'   | '20%'     | '0805'      | 'X7R'     | 'TMP_QCH5473M1A00'(!) = 'End of Design' | 'Comp-Approve'     | ''       | 'CH5473M1A00'     |'C0805_H61'| '(SMC0805AW)'                                                        | '4.7UF'    | '16V'         | '20%'    | 'DISCRETE' | 'CHIP0805'                                                     | 'CHIP0805'     | ''          | ''   | ''        
 '4.7UF'    | '16V'   | '20%'     | '0805'      | 'EMPTY'   | 'TMP_QCH5473M1A00'(!) = 'End of Design' | 'Comp-Approve'     | ''       | 'CH5473M1A00'     |'C0805_H61'| '(SMC0805AW)'                                                        | 'NA'       | '16V'         | '20%'    | 'IO'       | 'CHIP0805'                                                     | 'CHIP0805'     | ''          | ''   | ''        
 '470PF'    | '50V'   | '10%'     | '0402'      | 'X7R'     | 'TMP_QCH14706KB18'(!) = ''              | ''                 | ''       | 'CH14706KB18'     |'C0402'| '(C0402-0201)'                                                       | '470PF'    | '50V'         | '10%'    | 'DISCRETE' | 'CHIP0402'                                                     | 'CHIP0402'     | ''          | ''   | ''        
 '470PF'    | '50V'   | '10%'     | '0402'      | 'EMPTY'   | 'TMP_QCH14706KB18'(!) = ''              | ''                 | ''       | 'CH14706KB18'     |'C0402'| '(C0402-0201)'                                                       | 'NA'       | '50V'         | '10%'    | 'IO'       | 'CHIP0402'                                                     | 'CHIP0402'     | ''          | ''   | ''        
 '1500PF'   | '50V'   | '10%'     | '0402'      | 'X7R'     | 'TMP_QCH21506KB14'(!) = ''              | ''                 | ''       | 'CH21506KB14'     |'C0402'| '(C0402-0201)'                                                       | '1500PF'   | '50V'         | '10%'    | 'DISCRETE' | 'CHIP0402'                                                     | 'CHIP0402'     | ''          | ''   | ''        
 '1500PF'   | '50V'   | '10%'     | '0402'      | 'EMPTY'   | 'TMP_QCH21506KB14'(!) = ''              | ''                 | ''       | 'CH21506KB14'     |'C0402'| '(C0402-0201)'                                                       | 'NA'       | '50V'         | '10%'    | 'IO'       | 'CHIP0402'                                                     | 'CHIP0402'     | ''          | ''   | ''        
 '22PF'     | '50V'   | '5%'      | '0402'      | 'NPO'     | 'TMP_QCH02206JB08'(!) = ''              | ''                 | ''       | 'CH02206JB08'     |'C0402'| '(C0402-0201)'                                                       | '22PF'     | '50V'         | '5%'     | 'DISCRETE' | 'CHIP0402'                                                     | 'CHIP0402'     | ''          | ''   | ''        
 '22PF'     | '50V'   | '5%'      | '0402'      | 'EMPTY'   | 'TMP_QCH02206JB08'(!) = ''              | ''                 | ''       | 'CH02206JB08'     |'C0402'| '(C0402-0201)'                                                       | 'NA'       | '50V'         | '5%'     | 'IO'       | 'CHIP0402'                                                     | 'CHIP0402'     | ''          | ''   | ''        
 '33PF'     | '50V'   | '5%'      | '0402'      | 'NPO'     | 'TMP_QCH03306JB04'(!) = ''              | ''                 | ''       | 'CH03306JB04'     |'C0402'| '(C0402-0201)'                                                       | '33PF'     | '50V'         | '15%'    | 'DISCRETE' | 'CHIP0402'                                                     | 'CHIP0402'     | ''          | ''   | ''        
 '33PF'     | '50V'   | '5%'      | '0402'      | 'EMPTY'   | 'TMP_QCH03306JB04'(!) = ''              | ''                 | ''       | 'CH03306JB04'     |'C0402'| '(C0402-0201)'                                                       | 'NA'       | '50V'         | '5%'     | 'IO'       | 'CHIP0402'                                                     | 'CHIP0402'     | ''          | ''   | ''        
 '47PF'     | '50V'   | '5%'      | '0402'      | 'NPO'     | 'TMP_QCH04706JB01'(!) = ''              | ''                 | ''       | 'CH04706JB01'     |'C0402'| '(C0402-0201)'                                                       | '47PF'     | '50V'         | '5%'     | 'DISCRETE' | 'CHIP0402'                                                     | 'CHIP0402'     | ''          | ''   | ''        
 '47PF'     | '50V'   | '5%'      | '0402'      | 'EMPTY'   | 'TMP_QCH04706JB01'(!) = ''              | ''                 | ''       | 'CH04706JB01'     |'C0402'| '(C0402-0201)'                                                       | 'NA'       | '50V'         | '5%'     | 'IO'       | 'CHIP0402'                                                     | 'CHIP0402'     | ''          | ''   | ''        
 '680PF'    | '50V'   | '10%'     | '0402'      | 'X7R'     | 'TMP_QCH16806KB17'(!) = ''              | ''                 | ''       | 'CH16806KB17'     |'C0402'| '(C0402-0201)'                                                       | '680PF'    | '50V'         | '10%'    | 'DISCRETE' | 'CAP CHIP 680P 50V(+-10%,X7R,0402)'                            | 'CHIP0402'     | ''          | ''   | ''        
 '680PF'    | '50V'   | '10%'     | '0402'      | 'EMPTY'   | 'TMP_QCH16806KB17'(!) = ''              | ''                 | ''       | 'CH16806KB17'     |'C0402'| '(C0402-0201)'                                                       | 'NA'       | '50V'         | '10%'    | 'IO'       | 'CAP CHIP 680P 50V(+-10%,X7R,0402)'                            | 'CHIP0402'     | ''          | ''   | ''        
 '1UF'      | '10V'   | '10%'     | '0603'      | 'X5R'     | 'TMP_QCH51002K996'(!) = 'End of Design' | 'Comp-Approve'     | ''       | 'CH51002K996'     |'C0603'| '(SMC0603AW)'                                                        | '1UF'      | '10V'         | '10%'    | 'DISCRETE' | 'CHIP0603'                                                     | 'CHIP0603'     | ''          | ''   | ''        
 '1UF'      | '10V'   | '10%'     | '0603'      | 'EMPTY'   | 'TMP_QCH51002K996'(!) = 'End of Design' | 'Comp-Approve'     | ''       | 'CH51002K996'     |'C0603'| '(SMC0603AW)'                                                        | 'NA'       | '10V'         | '10%'    | 'IO'       | 'CHIP0603'                                                     | 'CHIP0603'     | ''          | ''   | ''        
 '10UF'     | '6.3V'  | '10%'     | '0805'      | 'X5R'     | 'TMP_QCH61001ME96'(!) = 'End of Design' | 'Comp-Approve'     | ''       | 'CH61001ME96'     |'C0805_H64'| '(SMC0805AW)'                                                        | '10UF'     | '6.3V'        | '10%'    | 'DISCRETE' | 'CHIP0805'                                                     | 'CHIP0805'     | ''          | ''   | ''        
 '10UF'     | '6.3V'  | '10%'     | '0805'      | 'EMPTY'   | 'TMP_QCH61001ME96'(!) = 'End of Design' | 'Comp-Approve'     | ''       | 'CH61001ME96'     |'C0805_H64'| '(SMC0805AW)'                                                        | 'NA'       | '6.3V'        | '10%'    | 'IO'       | 'CHIP0805'                                                     | 'CHIP0805'     | ''          | ''   | ''        
 '10UF'     | '10V'   | '20%'     | '0805'      | 'X5R'     | 'TMP_QCH6102M9A01'(!) = 'End of Design' | 'Comp-Approve'     | ''       | 'CH6102M9A01'     |'C0805_H64'| '(SMC0805AW)'                                                        | '10UF'     | '10V'         | '20%'    | 'DISCRETE' | 'CAP CHIP 10U,10V(+-20%,X5R,0805)'                             | 'CHIP0805'     | ''          | ''   | ''        
 '10UF'     | '10V'   | '20%'     | '0805'      | 'EMPTY'   | 'TMP_QCH6102M9A01'(!) = 'End of Design' | 'Comp-Approve'     | ''       | 'CH6102M9A01'     |'C0805_H64'| '(SMC0805AW)'                                                        | 'NA'       | '10V'         | '20%'    | 'IO'       | 'CAP CHIP 10U,10V(+-20%,X5R,0805)'                             | 'CHIP0805'     | ''          | ''   | ''        
 '0.1UF'    | '10V'   | '10%'     | '0402'      | 'X5R'     | 'TMP_QCH41002KB93'(!) = 'End of Design' | 'Comp-Approve'     | ''       | 'CH41002KB93'     |'C0402'| '(C0402-0201)'                                                       | '0.1UF'    | '10V'         | '10%'    | 'DISCRETE' | 'CAP CHIP 0.1U 10V(+-10%,X5R,0402)'                            | 'CHIP0402'     | ''          | ''   | ''        
 '0.1UF'    | '10V'   | '10%'     | '0402'      | 'EMPTY'   | 'TMP_QCH41002KB93'(!) = 'End of Design' | 'Comp-Approve'     | ''       | 'CH41002KB93'     |'C0402'| '(C0402-0201)'                                                       | 'NA'       | '10V'         | '10%'    | 'IO'       | 'CAP CHIP 0.1U 10V(+-10%,X5R,0402)'                            | 'CHIP0402'     | ''          | ''   | ''        
 '4.7UF'    | '10V'   | '10%'     | '0805'      | 'X5R'     | 'TMP_QCH5472K9A02'(!) = 'End of Design' | 'Comp-Approve'     | ''       | 'CH5472K9A02'     |'C0805_H61'| '(SMC0805AW)'                                                        | '4.7UF'    | '10V'         | '10%'    | 'DISCRETE' | 'CAP CHIP 4.7U 10V(+-10%,X5R,0805)'                            | 'CHIP0805'     | ''          | ''   | ''        
 '4.7UF'    | '10V'   | '10%'     | '0805'      | 'EMPTY'   | 'TMP_QCH5472K9A02'(!) = 'End of Design' | 'Comp-Approve'     | ''       | 'CH5472K9A02'     |'C0805_H61'| '(SMC0805AW)'                                                        | 'NA'       | '10V'         | '10%'    | 'IO'       | 'CAP CHIP 4.7U 10V(+-10%,X5R,0805)'                            | 'CHIP0805'     | ''          | ''   | ''        
 '6800PF'   | '25V'   | '10%'     | '0402'      | 'X7R'     | 'TMP_QCH26804KB18'(!) = 'End of Design' | 'Comp-Approve'     | ''       | 'CH26804KB18'     |'C0402'| '(C0402-0201)'                                                       | '6800PF'   | '25V'         | '10%'    | 'DISCRETE' | 'CAP CHIP 6800P 25V(+-10% X7R 0402)'                           | 'CHIP0402'     | ''          | ''   | ''        
 '6800PF'   | '25V'   | '10%'     | '0402'      | 'EMPTY'   | 'TMP_QCH26804KB18'(!) = 'End of Design' | 'Comp-Approve'     | ''       | 'CH26804KB18'     |'C0402'| '(C0402-0201)'                                                       | 'NA'       | '25V'         | '10%'    | 'IO'       | 'CAP CHIP 6800P 25V(+-10% X7R 0402)'                           | 'CHIP0402'     | ''          | ''   | ''        
 '4.7UF'    | '4V'    | '20%'     | '0402'      | 'X5R'     | 'TMP_QCH547KM9B00'(!) = 'End of Design' | 'Comp-Approve'     | ''       | 'CH547KM9B00'     |'C0402'| '(C0402-0201)'                                                       | '4.7UF'    | '4V'          | '20%'    | 'DISCRETE' | 'CAP CHIP 4.7U 4V(+-20%,X5R,0402)HF'                           | 'CHIP0402'     | ''          | ''   | ''        
 '4.7UF'    | '4V'    | '20%'     | '0402'      | 'EMPTY'   | 'TMP_QCH547KM9B00'(!) = 'End of Design' | 'Comp-Approve'     | ''       | 'CH547KM9B00'     |'C0402'| '(C0402-0201)'                                                       | 'NA'       | '4V'          | '20%'    | 'IO'       | 'CAP CHIP 4.7U 4V(+-20%,X5R,0402)HF'                           | 'CHIP0402'     | ''          | ''   | ''        
 '2PF'      | '50V'   | '.25PF'   | '0402'      | 'COG'     | 'TMP_QCH-206C0B01'(!) = ''              | ''                 | ''       | 'CH-206C0B01'     |'C0402'| '(C0402-0201)'                                                       | '2PF'      | '50V'         | '.25PF'  | 'DISCRETE' | 'CAP CHIP 2P 50V(+-0.25PF,COG,0402)HI-Q'                       | 'CHIP0402'     | ''          | ''   | ''        
 '2PF'      | '50V'   | '.25PF'   | '0402'      | 'EMPTY'   | 'TMP_QCH-206C0B01'(!) = ''              | ''                 | ''       | 'CH-206C0B01'     |'C0402'| '(C0402-0201)'                                                       | 'NA'       | '50V'         | '.25PF'  | 'IO'       | 'CAP CHIP 2P 50V(+-0.25PF,COG,0402)HI-Q'                       | 'CHIP0402'     | ''          | ''   | ''        
 '5.0PF'    | '50V'   | '.25PF'   | '0402'      | 'COG'     | 'TMP_QCH-5006TB09'(!) = ''              | ''                 | ''       | 'CH-5006TB09'     |'C0402'| '(C0402-0201)'                                                       | '5.0PF'    | '50V'         | '.25PF'  | 'DISCRETE' | 'CAP CHIP 5.0P 50V(+-0.25P,COG,0402)EP'                        | 'CHIP0402'     | ''          | ''   | ''        
 '5.0PF'    | '50V'   | '.25PF'   | '0402'      | 'EMPTY'   | 'TMP_QCH-5006TB09'(!) = ''              | ''                 | ''       | 'CH-5006TB09'     |'C0402'| '(C0402-0201)'                                                       | 'NA'       | '50V'         | '.25PF'  | 'IO'       | 'CAP CHIP 5.0P 50V(+-0.25P,COG,0402)EP'                        | 'CHIP0402'     | ''          | ''   | ''        
 '0.022UF'  | '16V'   | '10%'     | '0402'      | 'X7R'     | 'TMP_QCH32203KB11'(!) = ''              | ''                 | ''       | 'CH32203KB11'     |'C0402'| '(C0402-0201,C0402_OCTAGONXA)'                                       | '0.022UF'  | '16V'         | '10%'    | 'DISCRETE' | 'CAP CHIP 0.022U 16V(+-10%,X7R,0402)'                          | 'CHIP0402'     | ''          | ''   | ''        
 '0.022UF'  | '16V'   | '10%'     | '0402'      | 'EMPTY'   | 'TMP_QCH32203KB11'(!) = ''              | ''                 | ''       | 'CH32203KB11'     |'C0402'| '(C0402-0201,C0402_OCTAGONXA)'                                       | 'NA'       | '16V'         | '10%'    | 'IO'       | 'CAP CHIP 0.022U 16V(+-10%,X7R,0402)'                          | 'CHIP0402'     | ''          | ''   | ''        
 '2.2UF'    | '10V'   | '20%'     | '0402'      | 'X5R'     | 'TMP_QCH5222M9B07'(!) = 'End of Design' | 'Comp-Approve'     | ''       | 'CH5222M9B07'     |'C0402'| '(C0402-0201)'                                                       | '2.2UF'    | '10V'         | '20%'    | 'DISCRETE' | 'CAP CHIP 2.2UF 10V(+-20%,X5R,0402)'                           | 'CHIP0402'     | ''          | ''   | ''        
 '2.2UF'    | '10V'   | '20%'     | '0402'      | 'EMPTY'   | 'TMP_QCH5222M9B07'(!) = 'End of Design' | 'Comp-Approve'     | ''       | 'CH5222M9B07'     |'C0402'| '(C0402-0201)'                                                       | 'NA'       | '10V'         | '20%'    | 'IO'       | 'CAP CHIP 2.2UF 10V(+-20%,X5R,0402)'                           | 'CHIP0402'     | ''          | ''   | ''        
 '10UF'     | '10V'   | '10%'     | '0805'      | 'X5R'     | 'TMP_QCH6102K9A01'(!) = 'End of Design' | 'Comp-Release Qty' | ''       | 'CH6102K9A01'     |'C0805_H61'| '(SMC0805AW)'                                                        | '10UF'     | '10V'         | '10%'    | 'DISCRETE' | 'CAP CHIP 10U 10V(+-10%,X5R,0805)'                             | 'CHIP0805'     | ''          | ''   | ''        
 '10UF'     | '10V'   | '10%'     | '0805'      | 'EMPTY'   | 'TMP_QCH6102K9A01'(!) = 'End of Design' | 'Comp-Release Qty' | ''       | 'CH6102K9A01'     |'C0805_H61'| '(SMC0805AW)'                                                        | 'NA'       | '10V'         | '10%'    | 'IO'       | 'CAP CHIP 10U 10V(+-10%,X5R,0805)'                             | 'CHIP0805'     | ''          | ''   | ''        
 '6.8PF'    | '50V'   | '0.5P'    | '0402'      | 'NPO'     | 'TMP_QCH-6806TB01'(!) = ''              | ''                 | ''       | 'CH-6806TB01'     |'C0402'| '(C0402-0201)'                                                       | '6.8PF'    | '50V'         | '0.5P'   | 'DISCRETE' | 'CAP CHIP 6.8P 50V(+-0.5P 0402 NPO)'                           | 'CHIP0402'     | ''          | ''   | ''        
 '6.8PF'    | '50V'   | '0.5P'    | '0402'      | 'EMPTY'   | 'TMP_QCH-6806TB01'(!) = ''              | ''                 | ''       | 'CH-6806TB01'     |'C0402'| '(C0402-0201)'                                                       | 'NA'       | '50V'         | '0.5P'   | 'IO'       | 'CAP CHIP 6.8P 50V(+-0.5P 0402 NPO)'                           | 'CHIP0402'     | ''          | ''   | ''        
 '4700PF'   | '50V'   | '10%'     | '0402'      | 'X7R'     | 'TMP_QCH2476K1B00'(!) = ''              | ''                 | ''       | 'CH2476K1B00'     |'C0402'| '(C0402-0201,C0402_OCTAGONXA)'                                       | '4700PF'   | '50V'         | '10%'    | 'DISCRETE' | 'CAP CHIP 4700PF 50V(10%,X7R,0402)'                            | 'CHIP0402'     | ''          | ''   | ''        
 '4700PF'   | '50V'   | '10%'     | '0402'      | 'EMPTY'   | 'TMP_QCH2476K1B00'(!) = ''              | ''                 | ''       | 'CH2476K1B00'     |'C0402'| '(C0402-0201,C0402_OCTAGONXA)'                                       | 'NA'       | '50V'         | '10%'    | 'IO'       | 'CAP CHIP 4700PF 50V(10%,X7R,0402)'                            | 'CHIP0402'     | ''          | ''   | ''        
 '1200PF'   | '50V'   | '10%'     | '0402'      | 'X7R'     | 'TMP_QCH21206KB13'(!) = 'End of Design' | 'End of Life'      | ''       | 'CH21206KB13'     |'C0402_EOL'| '(C0402-0201)'                                                       | '1200PF'   | '50V'         | '10%'    | 'DISCRETE' | 'CAP CHIP 1200P 50V(+-10%,X7R,0402)'                           | 'CHIP0402'     | ''          | ''   | ''        
 '1200PF'   | '50V'   | '10%'     | '0402'      | 'EMPTY'   | 'TMP_QCH21206KB13'(!) = 'End of Design' | 'End of Life'      | ''       | 'CH21206KB13'     |'C0402_EOL'| '(C0402-0201)'                                                       | 'NA'       | '50V'         | '10%'    | 'IO'       | 'CAP CHIP 1200P 50V(+-10%,X7R,0402)'                           | 'CHIP0402'     | ''          | ''   | ''        
 '2.2UF'    | '6.3V'  | '10%'     | '0603'      | 'X7R'     | 'TMP_QCH5221K1900'(!) = 'End of Design' | 'Comp-Approve'     | ''       | 'CH5221K1900'     |'C0603'| '(SMC0603AW)'                                                        | '2.2UF'    | '6.3V'        | '10%'    | 'DISCRETE' | 'CAP CHIP 2.2UF 6.3V(+-10%,X7R,0603)'                          | 'CHIP0603'     | ''          | ''   | ''        
 '2.2UF'    | '6.3V'  | '10%'     | '0603'      | 'EMPTY'   | 'TMP_QCH5221K1900'(!) = 'End of Design' | 'Comp-Approve'     | ''       | 'CH5221K1900'     |'C0603'| '(SMC0603AW)'                                                        | 'NA'       | '6.3V'        | '10%'    | 'IO'       | 'CAP CHIP 2.2UF 6.3V(+-10%,X7R,0603)'                          | 'CHIP0603'     | ''          | ''   | ''        
 '10UF'     | '25V'   | '10%'     | '1206'      | 'X7R'     | 'TMP_QCH6104K1206'(!) = 'End of Design' | 'Comp-Approve'     | ''       | 'CH6104K1206'     |'C1206_H76'| '(SMC1206AW)'                                                        | '10UF'     | '25V'         | '10%'    | 'DISCRETE' | 'CAP CHIP 10U,25V(+-10%,X7R,1206)H1.6'                         | 'CHIP1206'     | ''          | ''   | ''        
 '10UF'     | '25V'   | '10%'     | '1206'      | 'EMPTY'   | 'TMP_QCH6104K1206'(!) = 'End of Design' | 'Comp-Approve'     | ''       | 'CH6104K1206'     |'C1206_H76'| '(SMC1206AW)'                                                        | 'NA'       | '25V'         | '10%'    | 'IO'       | 'CAP CHIP 10U,25V(+-10%,X7R,1206)H1.6'                         | 'CHIP1206'     | ''          | ''   | ''        
 '2700PF'   | '50V'   | '10%'     | '0402'      | 'X7R'     | 'TMP_QCH22706KB14'(!) = ''              | ''                 | ''       | 'CH22706KB14'     |'C0402'| '(C0402-0201)'                                                       | '2700PF'   | '50V'         | '10%'    | 'DISCRETE' | 'CAP CHIP 2700P 50V(+-10%,X7R,0402)'                           | 'CHIP0402'     | ''          | ''   | ''        
 '2700PF'   | '50V'   | '10%'     | '0402'      | 'EMPTY'   | 'TMP_QCH22706KB14'(!) = ''              | ''                 | ''       | 'CH22706KB14'     |'C0402'| '(C0402-0201)'                                                       | 'NA'       | '50V'         | '10%'    | 'IO'       | 'CAP CHIP 2700P 50V(+-10%,X7R,0402)'                           | 'CHIP0402'     | ''          | ''   | ''        
 '4.7UF'    | '6.3V'  | '10%'     | '0603'      | 'X6S'     | 'TMP_QCH5471KE901'(!) = 'End of Design' | 'Comp-Approve'     | ''       | 'CH5471KE901'     |'C0603'| '(SMC0603AW)'                                                        | '4.7UF'    | '6.3V'        | '10%'    | 'DISCRETE' | 'CAP CHIP 4.7U 6.3V(+-10%,X6S,0603)'                           | 'CHIP0603'     | ''          | ''   | ''        
 '4.7UF'    | '6.3V'  | '10%'     | '0603'      | 'EMPTY'   | 'TMP_QCH5471KE901'(!) = 'End of Design' | 'Comp-Approve'     | ''       | 'CH5471KE901'     |'C0603'| '(SMC0603AW)'                                                        | 'NA'       | '6.3V'        | '10%'    | 'IO'       | 'CAP CHIP 4.7U 6.3V(+-10%,X6S,0603)'                           | 'CHIP0603'     | ''          | ''   | ''        
 '4.7UF'    | '6.3V'  | '10%'     | '0805'      | 'X7R'     | 'TMP_QCH5471K1A00'(!) = 'End of Design' | 'Comp-Approve'     | ''       | 'CH5471K1A00'     |'C0805_H61'| '(SMC0805AW)'                                                        | '4.7UF'    | '6.3V'        | '10%'    | 'DISCRETE' | 'CAP CHIP 4.7UF 6.3V(+-10%,X7R,0805)H1.25'                     | 'CHIP0805'     | ''          | ''   | ''        
 '4.7UF'    | '6.3V'  | '10%'     | '0805'      | 'EMPTY'   | 'TMP_QCH5471K1A00'(!) = 'End of Design' | 'Comp-Approve'     | ''       | 'CH5471K1A00'     |'C0805_H61'| '(SMC0805AW)'                                                        | 'NA'       | '6.3V'        | '10%'    | 'IO'       | 'CAP CHIP 4.7UF 6.3V(+-10%,X7R,0805)H1.25'                     | 'CHIP0805'     | ''          | ''   | ''        
 '10UF'     | '25V'   | '10%'     | '0805'      | 'X5R'     | 'TMP_QCH6104K9A00'(!) = 'End of Design' | 'Comp-Release Qty' | ''       | 'CH6104K9A00'     |'C0805_H61'| '(SMC0805AW)'                                                        | '10UF'     | '25V'         | '10%'    | 'DISCRETE' | 'CAP CHIP 10U 25V(+-10%,X5R,0805,H1.25)'                       | 'CHIP0805'     | ''          | ''   | ''        
 '10UF'     | '25V'   | '10%'     | '0805'      | 'EMPTY'   | 'TMP_QCH6104K9A00'(!) = 'End of Design' | 'Comp-Release Qty' | ''       | 'CH6104K9A00'     |'C0805_H61'| '(SMC0805AW)'                                                        | 'NA'       | '25V'         | '10%'    | 'IO'       | 'CAP CHIP 10U 25V(+-10%,X5R,0805,H1.25)'                       | 'CHIP0805'     | ''          | ''   | ''        
 '56PF'     | '50V'   | '5%'      | '0402'      | 'NPO'     | 'TMP_QCH05606JB01'(!) = ''              | ''                 | ''       | 'CH05606JB01'     |'C0402'| '(C0402-0201)'                                                       | '56PF'     | '50V'         | '5%'     | 'DISCRETE' | 'CAP CHIP 56P 50V(+-5%,NPO,0402)'                              | 'CHIP0402'     | ''          | ''   | ''        
 '56PF'     | '50V'   | '5%'      | '0402'      | 'EMPTY'   | 'TMP_QCH05606JB01'(!) = ''              | ''                 | ''       | 'CH05606JB01'     |'C0402'| '(C0402-0201)'                                                       | 'NA'       | '50V'         | '5%'     | 'IO'       | 'CAP CHIP 56P 50V(+-5%,NPO,0402)'                              | 'CHIP0402'     | ''          | ''   | ''        
 '220PF'    | '50V'   | '10%'     | '0402'      | 'X7R'     | 'TMP_QCH12206KB14'(!) = ''              | ''                 | ''       | 'CH12206KB14'     |'C0402'| '(C0402-0201)'                                                       | '220PF'    | '50V'         | '10%'    | 'DISCRETE' | 'CAP CHIP 220P 50V(+-10%,X7R,0402)'                            | 'CHIP0402'     | ''          | ''   | ''        
 '220PF'    | '50V'   | '10%'     | '0402'      | 'EMPTY'   | 'TMP_QCH12206KB14'(!) = ''              | ''                 | ''       | 'CH12206KB14'     |'C0402'| '(C0402-0201)'                                                       | 'NA'       | '50V'         | '10%'    | 'IO'       | 'CAP CHIP 220P 50V(+-10%,X7R,0402)'                            | 'CHIP0402'     | ''          | ''   | ''        
 '2200PF'   | '50V'   | '10%'     | '0402'      | 'X7R'     | 'TMP_QCH22206KB16'(!) = ''              | ''                 | ''       | 'CH22206KB16'     |'C0402'| '(C0402-0201)'                                                       | '2200PF'   | '50V'         | '10%'    | 'DISCRETE' | 'CAP CHIP 2200P 50V(+-10%,X7R,0402)'                           | 'CHIP0402'     | ''          | ''   | ''        
 '2200PF'   | '50V'   | '10%'     | '0402'      | 'EMPTY'   | 'TMP_QCH22206KB16'(!) = ''              | ''                 | ''       | 'CH22206KB16'     |'C0402'| '(C0402-0201)'                                                       | 'NA'       | '50V'         | '10%'    | 'IO'       | 'CAP CHIP 2200P 50V(+-10%,X7R,0402)'                           | 'CHIP0402'     | ''          | ''   | ''        
 '4700PF'   | '25V'   | '10%'     | '0402'      | 'X7R'     | 'TMP_QCH24704KB19'(!) = ''              | ''                 | ''       | 'CH24704KB19'     |'C0402'| '(C0402-0201)'                                                       | '4700PF'   | '25V'         | '10%'    | 'DISCRETE' | 'CAP CHIP 4700P 25V(+-10%,X7R,0402)'                           | 'CHIP0402'     | ''          | ''   | ''        
 '4700PF'   | '25V'   | '10%'     | '0402'      | 'EMPTY'   | 'TMP_QCH24704KB19'(!) = ''              | ''                 | ''       | 'CH24704KB19'     |'C0402'| '(C0402-0201)'                                                       | 'NA'       | '25V'         | '10%'    | 'IO'       | 'CAP CHIP 4700P 25V(+-10%,X7R,0402)'                           | 'CHIP0402'     | ''          | ''   | ''        
 '0.47UF'   | '6.3V'  | '10%'     | '0402'      | 'X5R'     | 'TMP_QCH4471K9B03'(!) = 'End of Design' | 'Comp-Release Qty' | ''       | 'CH4471K9B03'     |'C0402'| '(C0402-0201)'                                                       | '0.47UF'   | '6.3V'        | '10%'    | 'DISCRETE' | 'CAP CHIP 0.47U 6.3V(+-10%,X5R,0402)'                          | 'CHIP0402'     | ''          | ''   | ''        
 '0.47UF'   | '6.3V'  | '10%'     | '0402'      | 'EMPTY'   | 'TMP_QCH4471K9B03'(!) = 'End of Design' | 'Comp-Release Qty' | ''       | 'CH4471K9B03'     |'C0402'| '(C0402-0201)'                                                       | 'NA'       | '6.3V'        | '10%'    | 'IO'       | 'CAP CHIP 0.47U 6.3V(+-10%,X5R,0402)'                          | 'CHIP0402'     | ''          | ''   | ''        
 '0.47UF'   | '10V'   | '10%'     | '0402'      | 'X5R'     | 'TMP_QCH4472K9B00'(!) = ''              | ''                 | ''       | 'CH4472K9B00'     |'C0402'| '(C0402-0201)'                                                       | '0.47UF'   | '10V'         | '10%'    | 'DISCRETE' | 'CAP CHIP 0.47UF 10V(+-10%,X5R,0402)'                          | 'CHIP0402'     | ''          | ''   | ''        
 '0.47UF'   | '10V'   | '10%'     | '0402'      | 'EMPTY'   | 'TMP_QCH4472K9B00'(!) = ''              | ''                 | ''       | 'CH4472K9B00'     |'C0402'| '(C0402-0201)'                                                       | 'NA'       | '10V'         | '10%'    | 'IO'       | 'CAP CHIP 0.47UF 10V(+-10%,X5R,0402)'                          | 'CHIP0402'     | ''          | ''   | ''        
 '4.7UF'    | '6.3V'  | '20%'     | '0603'      | 'X5R'     | 'TMP_QCH5471M9907'(!) = 'End of Design' | 'Comp-Approve'     | ''       | 'CH5471M9907'     |'C0603'| '(SMC0603AW)'                                                        | '4.7UF'    | '6.3V'        | '20%'    | 'DISCRETE' | 'CAP CHIP 4.7U 6.3V(+-20%,X5R,0603)'                           | 'CHIP0603'     | ''          | ''   | ''        
 '4.7UF'    | '6.3V'  | '20%'     | '0603'      | 'EMPTY'   | 'TMP_QCH5471M9907'(!) = 'End of Design' | 'Comp-Approve'     | ''       | 'CH5471M9907'     |'C0603'| '(SMC0603AW)'                                                        | 'NA'       | '6.3V'        | '20%'    | 'IO'       | 'CAP CHIP 4.7U 6.3V(+-20%,X5R,0603)'                           | 'CHIP0603'     | ''          | ''   | ''        
 '10UF'     | '4V'    | '20%'     | '0603'      | 'X5R'     | 'TMP_QCH610KM9905'(!) = 'End of Design' | 'Comp-Approve'     | ''       | 'CH610KM9905'     |'C0603'| '(SMC0603AW)'                                                        | '10UF'     | '4V'          | '20%'    | 'DISCRETE' | 'CAP CHIP 10U,4V(+-20%,X5R,0603)'                              | 'CHIP0603'     | ''          | ''   | ''        
 '10UF'     | '4V'    | '20%'     | '0603'      | 'EMPTY'   | 'TMP_QCH610KM9905'(!) = 'End of Design' | 'Comp-Approve'     | ''       | 'CH610KM9905'     |'C0603'| '(SMC0603AW)'                                                        | 'NA'       | '4V'          | '20%'    | 'IO'       | 'CAP CHIP 10U,4V(+-20%,X5R,0603)'                              | 'CHIP0603'     | ''          | ''   | ''        
 '0.33UF'   | '16V'   | '10%'     | '0603'      | 'X7R'     | 'TMP_QCH4333K1905'(!) = 'End of Design' | 'Comp-Approve'     | ''       | 'CH4333K1905'     |'C0603'| '(SMC0603AW)'                                                        | '0.33UF'   | '16V'         | '10%'    | 'DISCRETE' | 'CAP CHIP 0.33UF 16V(+-10%,X7R,0603)'                          | 'CHIP0603'     | ''          | ''   | ''        
 '0.33UF'   | '16V'   | '10%'     | '0603'      | 'EMPTY'   | 'TMP_QCH4333K1905'(!) = 'End of Design' | 'Comp-Approve'     | ''       | 'CH4333K1905'     |'C0603'| '(SMC0603AW)'                                                        | 'NA'       | '16V'         | '10%'    | 'IO'       | 'CAP CHIP 0.33UF 16V(+-10%,X7R,0603)'                          | 'CHIP0603'     | ''          | ''   | ''        
 '0.1UF'    | '10V'   | '10%'     | '0402'      | 'X7R'     | 'TMP_QCH4102K1B03'(!) = 'End of Design' | 'Comp-Approve'     | ''       | 'CH4102K1B03'     |'C0402'| '(C0402-0201)'                                                       | '0.1UF'    | '10V'         | '10%'    | 'DISCRETE' | 'CAP CHIP 0.1U 10V(+-10%,X7R,0402)'                            | 'CHIP0402'     | ''          | ''   | ''        
 '0.1UF'    | '10V'   | '10%'     | '0402'      | 'EMPTY'   | 'TMP_QCH4102K1B03'(!) = 'End of Design' | 'Comp-Approve'     | ''       | 'CH4102K1B03'     |'C0402'| '(C0402-0201)'                                                       | 'NA'       | '10V'         | '10%'    | 'IO'       | 'CAP CHIP 0.1U 10V(+-10%,X7R,0402)'                            | 'CHIP0402'     | ''          | ''   | ''        
 '1UF'      | '6.3V'  | '20%'     | '0402'      | 'X5R'     | 'TMP_QCH5101M9B02'(!) = 'End of Design' | 'Comp-Approve'     | ''       | 'CH5101M9B02'     |'C0402'| '(C0402-0201)'                                                       | '1UF'      | '6.3V'        | '20%'    | 'DISCRETE' | 'CAP CHIP 1U 6.3V(+-20%,X5R,0402)'                             | 'CHIP0402'     | ''          | ''   | ''        
 '1UF'      | '6.3V'  | '20%'     | '0402'      | 'EMPTY'   | 'TMP_QCH5101M9B02'(!) = 'End of Design' | 'Comp-Approve'     | ''       | 'CH5101M9B02'     |'C0402'| '(C0402-0201)'                                                       | 'NA'       | '6.3V'        | '20%'    | 'IO'       | 'CAP CHIP 1U 6.3V(+-20%,X5R,0402)'                             | 'CHIP0402'     | ''          | ''   | ''        
 '0.1UF'    | '25V'   | '10%'     | '0402'      | 'X5R'     | 'TMP_QCH4104K9B03'(!) = 'End of Design' | 'Comp-Approve'     | ''       | 'CH4104K9B03'     |'C0402'| '(C0402-0201)'                                                       | '0.1UF'    | '25V'         | '10%'    | 'DISCRETE' | 'CAP CHIP 0.1U 25V(10%,X5R,0402)'                              | 'CHIP0402'     | ''          | ''   | ''        
 '0.1UF'    | '25V'   | '10%'     | '0402'      | 'EMPTY'   | 'TMP_QCH4104K9B03'(!) = 'End of Design' | 'Comp-Approve'     | ''       | 'CH4104K9B03'     |'C0402'| '(C0402-0201)'                                                       | 'NA'       | '25V'         | '10%'    | 'IO'       | 'CAP CHIP 0.1U 25V(10%,X5R,0402)'                              | 'CHIP0402'     | ''          | ''   | ''        
 '47UF'     | '4V'    | '20%'     | '0805'      | 'X5R'     | 'TMP_QCH647KM9A00'(!) = 'End of Design' | 'Comp-Approve'     | ''       | 'CH647KM9A00'     |'C0805_H61'| '(SMC0805AW)'                                                        | '47UF'     | '4V'          | '20%'    | 'DISCRETE' | 'CAP CHIP 47U 4V(+-20%,X5R,0805)H1.25'                         | 'CHIP0805'     | ''          | ''   | ''        
 '47UF'     | '4V'    | '20%'     | '0805'      | 'EMPTY'   | 'TMP_QCH647KM9A00'(!) = 'End of Design' | 'Comp-Approve'     | ''       | 'CH647KM9A00'     |'C0805_H61'| '(SMC0805AW)'                                                        | 'NA'       | '4V'          | '20%'    | 'IO'       | 'CAP CHIP 47U 4V(+-20%,X5R,0805)H1.25'                         | 'CHIP0805'     | ''          | ''   | ''        
 '47UF'     | '4V'    | '20%'     | '0805_FAC'  | 'X5R'     | 'CH647KM9A00'(!)   = 'End of Design' | 'Comp-Approve'     | ''       | 'CH647KM9A00'     |'C0805_H61'| '(SMC0805AW)'                                                        | '47UF'     | '4V'          | '20%'    | 'DISCRETE' | 'CAP CHIP 47U 4V(+-20%,X5R,0805)H1.25_FOR FAC ONLY'            | 'CHIP0805'     | ''          | ''   | '20100813'
 '47UF'     | '4V'    | '20%'     | '0805_FAC'  | 'EMPTY'   | 'CH647KM9A00'(!)   = 'End of Design' | 'Comp-Approve'     | ''       | 'CH647KM9A00'     |'C0805_H61'| '(SMC0805AW)'                                                        | 'NA'       | '4V'          | '20%'    | 'IO'       | 'CAP CHIP 47U 4V(+-20%,X5R,0805)H1.25_FOR FAC ONLY'            | 'CHIP0805'     | ''          | ''   | '20100813'
 '100UF'    | '6.3V'  | '20%'     | '1206'      | 'X5R'     | 'TMP_QCH7101M9200'(!) = 'End of Design' | 'Comp-Release Qty' | ''       | 'CH7101M9200'     |'C1206_H66'| '(SMC1206AW)'                                                        | '100UF'    | '6.3V'        | '20%'    | 'DISCRETE' | 'CAP CHIP 100U 6.3V(+-20%,X5R,1206)H1.6'                       | 'CHIP1206'     | ''          | ''   | ''        
 '100UF'    | '6.3V'  | '20%'     | '1206'      | 'EMPTY'   | 'TMP_QCH7101M9200'(!) = 'End of Design' | 'Comp-Release Qty' | ''       | 'CH7101M9200'     |'C1206_H66'| '(SMC1206AW)'                                                        | 'NA'       | '6.3V'        | '20%'    | 'IO'       | 'CAP CHIP 100U 6.3V(+-20%,X5R,1206)H1.6'                       | 'CHIP1206'     | ''          | ''   | ''        
 '47UF'     | '6.3V'  | '20%'     | '1206'      | 'X5R'     | 'TMP_QCH6471M9208'(!) = 'End of Design' | 'Comp-Approve'     | ''       | 'CH6471M9208'     |'C1206_H66'| '(SMC1206AW)'                                                        | '47UF'     | '6.3V'        | '20%'    | 'DISCRETE' | 'CAP CHIP 47U 6.3V(+-20%,X5R,1206)'                            | 'CHIP1206'     | ''          | ''   | ''        
 '47UF'     | '6.3V'  | '20%'     | '1206'      | 'EMPTY'   | 'TMP_QCH6471M9208'(!) = 'End of Design' | 'Comp-Approve'     | ''       | 'CH6471M9208'     |'C1206_H66'| '(SMC1206AW)'                                                        | 'NA'       | '6.3V'        | '20%'    | 'IO'       | 'CAP CHIP 47U 6.3V(+-20%,X5R,1206)'                            | 'CHIP1206'     | ''          | ''   | ''        
 '1UF'      | '10V'   | '10%'     | '0402'      | 'X7R'     | 'TMP_QCH5102K1B05'(!) = 'End of Design' | 'Comp-Approve'     | ''       | 'CH5102K1B05'     |'C0402'| '(C0402-0201)'                                                       | '1UF'      | '10V'         | '10%'    | 'DISCRETE' | 'CAP CHIP 1U,10V(+-10%,X7R,0402)'                              | 'CHIP0402'     | ''          | ''   | ''        
 '1UF'      | '10V'   | '10%'     | '0402'      | 'EMPTY'   | 'TMP_QCH5102K1B05'(!) = 'End of Design' | 'Comp-Approve'     | ''       | 'CH5102K1B05'     |'C0402'| '(C0402-0201)'                                                       | 'NA'       | '10V'         | '10%'    | 'IO'       | 'CAP CHIP 1U,10V(+-10%,X7R,0402)'                              | 'CHIP0402'     | ''          | ''   | ''        
 '0.047UF'  | '16V'   | '10%'     | '0603'      | 'X7R'     | 'TMP_QCH34703K916'(!) = ''              | ''                 | ''       | 'CH34703K916'     |'C0603'| '(SMC0603AW)'                                                        | '0.047UF'  | '16V'         | '10%'    | 'DISCRETE' | 'CAP CHIP 0.047UF 16V(+-10%,X7R,0603)'                         | 'CHIP0603'     | ''          | ''   | ''        
 '0.047UF'  | '16V'   | '10%'     | '0603'      | 'EMPTY'   | 'TMP_QCH34703K916'(!) = ''              | ''                 | ''       | 'CH34703K916'     |'C0603'| '(SMC0603AW)'                                                        | 'NA'       | '16V'         | '10%'    | 'IO'       | 'CAP CHIP 0.047UF 16V(+-10%,X7R,0603)'                         | 'CHIP0603'     | ''          | ''   | ''        
 '1UF'      | '10V'   | '20%'     | '0402'      | 'X5R'     | 'TMP_QCH5102M9B07'(!) = 'End of Design' | 'Comp-Approve'     | ''       | 'CH5102M9B07'     |'C0402'| '(C0402-0201)'                                                       | '1UF'      | '10V'         | '20%'    | 'DISCRETE' | 'CAP CHIP 1U 10V(+-20%,X5R,0402)H:0.5'                         | 'CHIP0402'     | ''          | ''   | ''        
 '1UF'      | '10V'   | '20%'     | '0402'      | 'EMPTY'   | 'TMP_QCH5102M9B07'(!) = 'End of Design' | 'Comp-Approve'     | ''       | 'CH5102M9B07'     |'C0402'| '(C0402-0201)'                                                       | 'NA'       | '10V'         | '20%'    | 'IO'       | 'CAP CHIP 1U 10V(+-20%,X5R,0402)H:0.5'                         | 'CHIP0402'     | ''          | ''   | ''        
 '22UF'     | '10V'   | '20%'     | '0805'      | 'X5R'     | 'TMP_QCH6222M9A01'(!) = ''              | 'End of Life'      | ''       | 'CH6222M9A01'     |'C0805_H61_EOL'| '(SMC0805AW)'                                                        | '22UF'     | '10V'         | '20%'    | 'DISCRETE' | 'CAP CHIP 22U 10V(+-20%,X5R,0805)'                             | 'CHIP0805'     | ''          | ''   | '20100527'
 '22UF'     | '10V'   | '20%'     | '0805'      | 'EMPTY'   | 'TMP_QCH6222M9A01'(!) = ''              | 'End of Life'      | ''       | 'CH6222M9A01'     |'C0805_H61_EOL'| '(SMC0805AW)'                                                        | 'NA'       | '10V'         | '20%'    | 'IO'       | 'CAP CHIP 22U 10V(+-20%,X5R,0805)'                             | 'CHIP0805'     | ''          | ''   | '20100527'
 '47UF'     | '6.3V'  | '20%'     | '0805'      | 'X5R'     | 'TMP_QCH6471M9A00'(!) = ''              | ''                 | ''       | 'CH6471M9A00'     |'C0805_H61'| '(SMC0805AW)'                                                        | '47UF'     | '6.3V'        | '20%'    | 'DISCRETE' | 'CAP CHIP 47U 6.3V(+-20%,X5R,0805)'                            | 'CHIP0805'     | ''          | ''   | '20100527'
 '47UF'     | '6.3V'  | '20%'     | '0805'      | 'EMPTY'   | 'TMP_QCH6471M9A00'(!) = ''              | ''                 | ''       | 'CH6471M9A00'     |'C0805_H61'| '(SMC0805AW)'                                                        | 'NA'       | '6.3V'        | '20%'    | 'IO'       | 'CAP CHIP 47U 6.3V(+-20%,X5R,0805)'                            | 'CHIP0805'     | ''          | ''   | '20100527'
 '1000PF'   | '50V'   | '10%'     | '0603'      | 'X7R'     | 'TMP_QCH21006K917'(!) = 'End of Design' | 'Comp-Approve'     | ''       | 'CH21006K917'     |'C0603'| '(SMC0603AW)'                                                        | '1000PF'   | '50V'         | '10%'    | 'DISCRETE' | 'CAP CHIP 1000P 50V(+-10%,X7R,0603)'                           | 'CHIP0603'     | ''          | ''   | '20100528'
 '1000PF'   | '50V'   | '10%'     | '0603'      | 'EMPTY'   | 'TMP_QCH21006K917'(!) = 'End of Design' | 'Comp-Approve'     | ''       | 'CH21006K917'     |'C0603'| '(SMC0603AW)'                                                        | 'NA'       | '50V'         | '10%'    | 'IO'       | 'CAP CHIP 1000P 50V(+-10%,X7R,0603)'                           | 'CHIP0603'     | ''          | ''   | '20100528'
 '0.047UF'  | '25V'   | '10%'     | '0603'      | 'X7R'     | 'TMP_QCH3474K1901'(!) = ''              | ''                 | 'SELASS' | 'CH3474K1901'     |'C0603'| '(SMC0603AW)'                                                        | '0.047UF'  | '25V'         | '10%'    | 'DISCRETE' | 'CAP CHIP 0.047UF 25V(10%,X7R,0603)SELASS'                     | 'CHIP0603'     | ''          | ''   | '20100528'
 '0.047UF'  | '25V'   | '10%'     | '0603'      | 'EMPTY'   | 'TMP_QCH3474K1901'(!) = ''              | ''                 | 'SELASS' | 'CH3474K1901'     |'C0603'| '(SMC0603AW)'                                                        | 'NA'       | '25V'         | '10%'    | 'IO'       | 'CAP CHIP 0.047UF 25V(10%,X7R,0603)SELASS'                     | 'CHIP0603'     | ''          | ''   | '20100528'
 '0.047UF'  | '16V'   | '10%'     | '0603'      | 'X7R'     | 'TMP_QCH3473K1919'(!) = 'End of Design' | 'Comp-Approve'     | ''       | 'CH3473K1919'     |'C0603'| '(SMC0603AW)'                                                        | '0.047UF'  | '16V'         | '10%'    | 'DISCRETE' | 'CAP CHIP 0.047U 16V(+-10%,X7R,0603)'                          | 'CHIP0603'     | ''          | ''   | '20100528'
 '0.047UF'  | '16V'   | '10%'     | '0603'      | 'EMPTY'   | 'TMP_QCH3473K1919'(!) = 'End of Design' | 'Comp-Approve'     | ''       | 'CH3473K1919'     |'C0603'| '(SMC0603AW)'                                                        | 'NA'       | '16V'         | '10%'    | 'IO'       | 'CAP CHIP 0.047U 16V(+-10%,X7R,0603)'                          | 'CHIP0603'     | ''          | ''   | '20100528'
 '0.1UF'    | '50V'   | '10%'     | '0603'      | 'X7R'     | 'TMP_QCH4106K1905'(!) = 'End of Design' | 'Comp-Approve'     | 'SELASS' | 'CH4106K1905'     |'C0603'| '(SMC0603AW)'                                                        | '0.1UF'    | '50V'         | '10%'    | 'DISCRETE' | 'CAP CHIP 0.1U 50V(+-10%,X7R,0603)SEL-ASS'                     | 'CHIP0603'     | ''          | ''   | '20100528'
 '0.1UF'    | '50V'   | '10%'     | '0603'      | 'EMPTY'   | 'TMP_QCH4106K1905'(!) = 'End of Design' | 'Comp-Approve'     | 'SELASS' | 'CH4106K1905'     |'C0603'| '(SMC0603AW)'                                                        | 'NA'       | '50V'         | '10%'    | 'IO'       | 'CAP CHIP 0.1U 50V(+-10%,X7R,0603)SEL-ASS'                     | 'CHIP0603'     | ''          | ''   | '20100528'
 '1UF'      | '25V'   | '10%'     | '0603'      | 'X7R'     | 'TMP_QCH5104K1901'(!) = 'End of Design' | 'Comp-Approve'     | 'SELASS' | 'CH5104K1901'     |'C0603'| '(SMC0603AW)'                                                        | '1UF'      | '25V'         | '10%'    | 'DISCRETE' | 'CAP CHIP 1U 25V(+-10%,X7R,0603)SELASS'                        | 'CHIP0603'     | ''          | ''   | '20100528'
 '1UF'      | '25V'   | '10%'     | '0603'      | 'EMPTY'   | 'TMP_QCH5104K1901'(!) = 'End of Design' | 'Comp-Approve'     | 'SELASS' | 'CH5104K1901'     |'C0603'| '(SMC0603AW)'                                                        | 'NA'       | '25V'         | '10%'    | 'IO'       | 'CAP CHIP 1U 25V(+-10%,X7R,0603)SELASS'                        | 'CHIP0603'     | ''          | ''   | '20100528'
 '2.2UF'    | '10V'   | '10%'     | '0603'      | 'X7R'     | 'TMP_QCH5222K1902'(!) = ''              | ''                 | 'SELASS' | 'CH5222K1902'     |'C0603'| '(SMC0603AW)'                                                        | '2.2UF'    | '10V'         | '10%'    | 'DISCRETE' | 'CAP CHIP 2.2UF 10V(+-10%,X7R,0603)SELASS'                     | 'CHIP0603'     | ''          | ''   | '20100528'
 '2.2UF'    | '10V'   | '10%'     | '0603'      | 'EMPTY'   | 'TMP_QCH5222K1902'(!) = ''              | ''                 | 'SELASS' | 'CH5222K1902'     |'C0603'| '(SMC0603AW)'                                                        | 'NA'       | '10V'         | '10%'    | 'IO'       | 'CAP CHIP 2.2UF 10V(+-10%,X7R,0603)SELASS'                     | 'CHIP0603'     | ''          | ''   | '20100528'
 '0.047UF'  | '25V'   | '10%'     | '0603'      | 'X7R'     | 'TMP_QCH3474K1905'(!) = 'End of Design' | 'Comp-Approve'     | ''       | 'CH3474K1905'     |'C0603'| '(SMC0603AW)'                                                        | '0.047UF'  | '25V'         | '10%'    | 'DISCRETE' | 'CAP CHIP 0.047UF 25V(+-10%,X7R,0603)'                         | 'CHIP0603'     | ''          | ''   | '20100528'
 '0.047UF'  | '25V'   | '10%'     | '0603'      | 'EMPTY'   | 'TMP_QCH3474K1905'(!) = 'End of Design' | 'Comp-Approve'     | ''       | 'CH3474K1905'     |'C0603'| '(SMC0603AW)'                                                        | 'NA'       | '25V'         | '10%'    | 'IO'       | 'CAP CHIP 0.047UF 25V(+-10%,X7R,0603)'                         | 'CHIP0603'     | ''          | ''   | '20100528'
 '1000PF'   | '50V'   | '5%'      | '0402'      | 'X7R'     | 'TMP_QCH21006JB10'(!) = ''              | ''                 | ''       | 'CH21006JB10'     |'C0402'| '(C0402-0201,C0402_OCTAGONXA)'                                       | '1000PF'   | '50V'         | '5%'     | 'DISCRETE' | 'CAP CHIP 1000P 50V(+-5%,X7R,0402)'                            | 'CHIP0402'     | ''          | ''   | '20100528'
 '1000PF'   | '50V'   | '5%'      | '0402'      | 'EMPTY'   | 'TMP_QCH21006JB10'(!) = ''              | ''                 | ''       | 'CH21006JB10'     |'C0402'| '(C0402-0201,C0402_OCTAGONXA)'                                       | 'NA'       | '50V'         | '5%'     | 'IO'       | 'CAP CHIP 1000P 50V(+-5%,X7R,0402)'                            | 'CHIP0402'     | ''          | ''   | '20100528'
 '0.01UF'   | '25V'   | '10%'     | '0402'      | 'X7R'     | 'TMP_QCH31004KB17'(!) = 'End of Design' | 'Comp-Release Qty' | ''       | 'CH31004KB17'     |'C0402'| '(C0402-0201,C0402_OCTAGONXA)'                                       | '0.01UF'   | '25V'         | '10%'    | 'DISCRETE' | 'CAP CHIP 0.01U 25V(+-10%,X7R,0402)'                           | 'CHIP0402'     | ''          | ''   | '20100528'
 '0.01UF'   | '25V'   | '10%'     | '0402'      | 'EMPTY'   | 'TMP_QCH31004KB17'(!) = 'End of Design' | 'Comp-Release Qty' | ''       | 'CH31004KB17'     |'C0402'| '(C0402-0201,C0402_OCTAGONXA)'                                       | 'NA'       | '25V'         | '10%'    | 'IO'       | 'CAP CHIP 0.01U 25V(+-10%,X7R,0402)'                           | 'CHIP0402'     | ''          | ''   | '20100528'
 '1UF'      | '10V'   | '10%'     | '0402'      | 'X5R'     | 'TMP_QCH5102K9B06'(!) = ''              | ''                 | ''       | 'CH5102K9B06'     |'C0402'| '(C0402-0201)'                                                       | '1UF'      | '10V'         | '10%'    | 'DISCRETE' | 'CAP CHIP 1UF 10V (+-10%,X5R,0402)'                            | 'CHIP0402'     | ''          | ''   | '20100528'
 '1UF'      | '10V'   | '10%'     | '0402'      | 'EMPTY'   | 'TMP_QCH5102K9B06'(!) = ''              | ''                 | ''       | 'CH5102K9B06'     |'C0402'| '(C0402-0201)'                                                       | 'NA'       | '10V'         | '10%'    | 'IO'       | 'CAP CHIP 1UF 10V (+-10%,X5R,0402)'                            | 'CHIP0402'     | ''          | ''   | '20100528'
 '10UF'     | '10V'   | '10%'     | '0805'      | 'X7R'     | 'TMP_QCH6102K1A01'(!) = ''              | ''                 | 'SELASS' | 'CH6102K1A01'     |'C0805_H61'| '(SMC0805AW)'                                                        | '10UF'     | '10V'         | '10%'    | 'DISCRETE' | 'CAP CHIP10UF 10V(+-10%,X7R,0805)SELASS'                       | 'CHIP0805'     | ''          | ''   | '20100528'
 '10UF'     | '10V'   | '10%'     | '0805'      | 'EMPTY'   | 'TMP_QCH6102K1A01'(!) = ''              | ''                 | 'SELASS' | 'CH6102K1A01'     |'C0805_H61'| '(SMC0805AW)'                                                        | 'NA'       | '10V'         | '10%'    | 'IO'       | 'CAP CHIP10UF 10V(+-10%,X7R,0805)SELASS'                       | 'CHIP0805'     | ''          | ''   | '20100528'
 '22UF'     | '6.3V'  | '20%'     | '0805'      | 'X5R'     | 'TMP_QCH6221M9A16'(!) = ''              | ''                 | 'SELASS' | 'CH6221M9A16'     |'C0805_H61'| '(SMC0805AW)'                                                        | '22UF'     | '6.3V'        | '20%'    | 'DISCRETE' | 'CAP CHIP 22U 6.3V(+-20%,X5R,0805)SELASS'                      | 'CHIP0805'     | ''          | ''   | '20100528'
 '22UF'     | '6.3V'  | '20%'     | '0805'      | 'EMPTY'   | 'TMP_QCH6221M9A16'(!) = ''              | ''                 | 'SELASS' | 'CH6221M9A16'     |'C0805_H61'| '(SMC0805AW)'                                                        | 'NA'       | '6.3V'        | '20%'    | 'IO'       | 'CAP CHIP 22U 6.3V(+-20%,X5R,0805)SELASS'                      | 'CHIP0805'     | ''          | ''   | '20100528'
 '10UF'     | '25V'   | '10%'     | '1206'      | 'X7R'     | 'TMP_QCH6104K1200'(!) = 'End of Design' | 'Comp-Release Qty' | 'SELASS' | 'CH6104K1200'     |'C1206_H76'| '(SMC1206AW)'                                                        | '10UF'     | '25V'         | '10%'    | 'DISCRETE' | 'CAP CHIP 10U 25V(+-10%,X7R,1206)SEL-ASS'                      | 'CHIP1206'     | ''          | ''   | '20100528'
 '10UF'     | '25V'   | '10%'     | '1206'      | 'EMPTY'   | 'TMP_QCH6104K1200'(!) = 'End of Design' | 'Comp-Release Qty' | 'SELASS' | 'CH6104K1200'     |'C1206_H76'| '(SMC1206AW)'                                                        | 'NA'       | '25V'         | '10%'    | 'IO'       | 'CAP CHIP 10U 25V(+-10%,X7R,1206)SEL-ASS'                      | 'CHIP1206'     | ''          | ''   | '20100528'
 '1000PF'   | '50V'   | '5%'      | '0603'      | 'NPO'     | 'TMP_QCH2106J0903'(!) = ''              | ''                 | 'SELASS' | 'CH2106J0903'     |'C0603'| '(SMC0603AW)'                                                        | '1000PF'   | '50V'         | '5%'     | 'DISCRETE' | 'CAP CHIP 1000P 50V(+-5%,NPO,0603)SELASS'                      | 'CHIP0603'     | ''          | ''   | '2010603' 
 '1000PF'   | '50V'   | '5%'      | '0603'      | 'EMPTY'   | 'TMP_QCH2106J0903'(!) = ''              | ''                 | 'SELASS' | 'CH2106J0903'     |'C0603'| '(SMC0603AW)'                                                        | 'NA'       | '50V'         | '5%'     | 'IO'       | 'CAP CHIP 1000P 50V(+-5%,NPO,0603)SELASS'                      | 'CHIP0603'     | ''          | ''   | '2010603' 
 '1800PF'   | '50V'   | '10%'     | '0603'      | 'X7R'     | 'TMP_QCH2186K1900'(!) = ''              | ''                 | 'SELASS' | 'CH2186K1900'     |'C0603'| '(SMC0603AW)'                                                        | '1800PF'   | '50V'         | '10%'    | 'DISCRETE' | 'CAP CHIP 1800P 50V(+-10%,X7R,0603)SELASS'                     | 'CHIP0603'     | ''          | ''   | '2010603' 
 '1800PF'   | '50V'   | '10%'     | '0603'      | 'EMPTY'   | 'TMP_QCH2186K1900'(!) = ''              | ''                 | 'SELASS' | 'CH2186K1900'     |'C0603'| '(SMC0603AW)'                                                        | 'NA'       | '50V'         | '10%'    | 'IO'       | 'CAP CHIP 1800P 50V(+-10%,X7R,0603)SELASS'                     | 'CHIP0603'     | ''          | ''   | '2010603' 
 '270PF'    | '50V'   | '5%'      | '0402'      | 'NPO'     | 'CH1276J0B02'(!)   = 'End of Design' | 'Comp-Approve'     | ''       | 'CH1276J0B02'     |'C0402'| '(C0402-0201)'                                                       | '270PF'    | '50V'         | '5%'     | 'DISCRETE' | 'CAP CHIP 270P 50V(+-5%,NPO,0402)'                             | 'CHIP0402'     | ''          | ''   | '20100609'
 '270PF'    | '50V'   | '5%'      | '0402'      | 'EMPTY'   | 'CH1276J0B02'(!)   = 'End of Design' | 'Comp-Approve'     | ''       | 'CH1276J0B02'     |'C0402'| '(C0402-0201)'                                                       | 'NA'       | '50V'         | '5%'     | 'IO'       | 'CAP CHIP 270P 50V(+-5%,NPO,0402)'                             | 'CHIP0402'     | ''          | ''   | '20100609'
 '1000PF'   | '50V'   | '5%'      | '0402'      | 'X7R'     | 'CH2106J1B03'(!)   = ''              | ''                 | 'SELASS' | 'CH2106J1B03'     |'C0402'| '(C0402-0201)'                                                       | '1000PF'   | '50V'         | '5%'     | 'DISCRETE' | 'CAP CHIP 1000P 50V(+-5%,X7R,0402)SELASS'                      | 'CHIP0402'     | ''          | ''   | '20100617'
 '1000PF'   | '50V'   | '5%'      | '0402'      | 'EMPTY'   | 'CH2106J1B03'(!)   = ''              | ''                 | 'SELASS' | 'CH2106J1B03'     |'C0402'| '(C0402-0201)'                                                       | 'NA'       | '50V'         | '5%'     | 'IO'       | 'CAP CHIP 1000P 50V(+-5%,X7R,0402)SELASS'                      | 'CHIP0402'     | ''          | ''   | '20100617'
 '100PF'    | '50V'   | '5%'      | '0402'      | 'NPO'     | 'CH11006JB00'(!)   = ''              | ''                 | ''       | 'CH11006JB00'     |'C0402'| '(C0402-0201)'                                                       | '100PF'    | '50V'         | '5%'     | 'DISCRETE' | 'CAP CHIP 100P 50V(+-5%,NPO,0402)'                             | 'CHIP0402'     | ''          | ''   | '20100618'
 '100PF'    | '50V'   | '5%'      | '0402'      | 'EMPTY'   | 'CH11006JB00'(!)   = ''              | ''                 | ''       | 'CH11006JB00'     |'C0402'| '(C0402-0201)'                                                       | 'NA'       | '50V'         | '5%'     | 'IO'       | 'CAP CHIP 100P 50V(+-5%,NPO,0402)'                             | 'CHIP0402'     | ''          | ''   | '20100618'
 '220PF'    | '50V'   | '10%'     | '0402'      | 'X7R'     | 'CH1226K1B06'(!)   = ''              | ''                 | 'SELASS' | 'CH1226K1B06'     |'C0402'| '(C0402-0201)'                                                       | '220PF'    | '50V'         | '10%'    | 'DISCRETE' | 'CAP CHIP 220PF 50V(+-10%,X7R,0402)SELASS'                     | 'CHIP0402'     | ''          | ''   | '20100618'
 '220PF'    | '50V'   | '10%'     | '0402'      | 'EMPTY'   | 'CH1226K1B06'(!)   = ''              | ''                 | 'SELASS' | 'CH1226K1B06'     |'C0402'| '(C0402-0201)'                                                       | 'NA'       | '50V'         | '10%'    | 'IO'       | 'CAP CHIP 220PF 50V(+-10%,X7R,0402)SELASS'                     | 'CHIP0402'     | ''          | ''   | '20100618'
 '1500PF'   | '50V'   | '10%'     | '0402'      | 'X7R'     | 'CH2156K1B03'(!)   = ''              | ''                 | 'SELASS' | 'CH2156K1B03'     |'C0402'| '(C0402-0201)'                                                       | '1500PF'   | '50V'         | '10%'    | 'DISCRETE' | 'CAP CHIP1500PF 50V(+-10%,X7R,0402)SELASS '                    | 'CHIP0402'     | ''          | ''   | '20100618'
 '1500PF'   | '50V'   | '10%'     | '0402'      | 'EMPTY'   | 'CH2156K1B03'(!)   = ''              | ''                 | 'SELASS' | 'CH2156K1B03'     |'C0402'| '(C0402-0201)'                                                       | 'NA'       | '50V'         | '10%'    | 'IO'       | 'CAP CHIP1500PF 50V(+-10%,X7R,0402)SELASS'                     | 'CHIP0402'     | ''          | ''   | '20100618'
 '10UF'     | '25V'   | '10%'     | '1206'      | 'X6S'     | 'CH6104KE203'(!)   = ''              | ''                 | 'SELASS' | 'CH6104KE203'     |'C1206_H76'| '(SMC1206AW)'                                                        | '10UF'     | '25V'         | '10%'    | 'DISCRETE' | 'CAP CHIP 10U 25V(+-10%,X6S,1206)SELASS'                       | 'CHIP1206'     | ''          | ''   | '20100618'
 '10UF'     | '25V'   | '10%'     | '1206'      | 'EMPTY'   | 'CH6104KE203'(!)   = ''              | ''                 | 'SELASS' | 'CH6104KE203'     |'C1206_H76'| '(SMC1206AW)'                                                        | 'NA'       | '25V'         | '10%'    | 'IO'       | 'CAP CHIP 10U 25V(+-10%,X6S,1206)SELASS'                       | 'CHIP1206'     | ''          | ''   | '20100618'
 '5600PF'   | '25V'   | '10%'     | '0402'      | 'X7R'     | 'CH25604KB18'(!)   = 'End of Design' | 'Comp-Approve'     | ''       | 'CH25604KB18'     |'C0402'| '(C0402-0201)'                                                       | '5600PF'   | '25V'         | '10%'    | 'DISCRETE' | 'CAP CHIP 5600P 25V(X7R,+-10%,0402)'                           | 'CHIP0402'     | ''          | ''   | '20100621'
 '5600PF'   | '25V'   | '10%'     | '0402'      | 'EMPTY'   | 'CH25604KB18'(!)   = 'End of Design' | 'Comp-Approve'     | ''       | 'CH25604KB18'     |'C0402'| '(C0402-0201)'                                                       | 'NA'       | '25V'         | '10%'    | 'IO'       | 'CAP CHIP 5600P 25V(X7R,+-10%,0402)'                           | 'CHIP0402'     | ''          | ''   | '20100621'
 '330PF'    | '50V'   | '10%'     | '0402'      | 'X7R'     | 'CH1336K1B02'(!)   = ''              | ''                 | ''       | 'CH1336K1B02'     |'C0402'| '(C0402-0201)'                                                       | '330PF'    | '50V'         | '10%'    | 'DISCRETE' | 'CAP CHIP 330P 50V(+-10%,X7R,0402)'                            | 'CHIP0402'     | ''          | ''   | '20100623'
 '330PF'    | '50V'   | '10%'     | '0402'      | 'EMPTY'   | 'CH1336K1B02'(!)   = ''              | ''                 | ''       | 'CH1336K1B02'     |'C0402'| '(C0402-0201)'                                                       | 'NA'       | '50V'         | '10%'    | 'IO'       | 'CAP CHIP 330P 50V(+-10%,X7R,0402)'                            | 'CHIP0402'     | ''          | ''   | '20100623'
 '0.068UF'  | '16V'   | '10%'     | '0402'      | 'X7R'     | 'CH3683K1B09'(!)   = ''              | ''                 | ''       | 'CH3683K1B09'     |'C0402'| '(C0402-0201)'                                                       | '0.068UF'  | '16V'         | '10%'    | 'DISCRETE' | 'CAP CHIP 0.068UF 16V(+-10%,X7R 0402)'                         | 'CHIP0402'     | ''          | ''   | '20100630'
 '0.068UF'  | '16V'   | '10%'     | '0402'      | 'EMPTY'   | 'CH3683K1B09'(!)   = ''              | ''                 | ''       | 'CH3683K1B09'     |'C0402'| '(C0402-0201)'                                                       | 'NA'       | '16V'         | '10%'    | 'IO'       | 'CAP CHIP 0.068UF 16V(+-10%,X7R 0402)'                         | 'CHIP0402'     | ''          | ''   | '20100630'
 '2200PF'   | '50V'   | '10%'     | '0603'      | 'X7R'     | 'CH22206K917'(!)   = 'End of Design' | 'Comp-Approve'     | ''       | 'CH22206K917'     |'C0603'| '(SMC0603AW)'                                                        | '2200PF'   | '50V'         | '10%'    | 'DISCRETE' | 'CAP CHIP 2200P 50V(+-10%,X7R,0603)'                           | 'CHIP0603'     | ''          | ''   | '2010702' 
 '2200PF'   | '50V'   | '10%'     | '0603'      | 'EMPTY'   | 'CH22206K917'(!)   = 'End of Design' | 'Comp-Approve'     | ''       | 'CH22206K917'     |'C0603'| '(SMC0603AW)'                                                        | 'NA'       | '50V'         | '10%'    | 'IO'       | 'CAP CHIP 2200P 50V(+-10%,X7R,0603)'                           | 'CHIP0603'     | ''          | ''   | '2010702' 
 '0.1UF'    | '16V'   | '20%'     | '0402'      | 'Y5V'     | 'CH41003ZB35'(!)   = 'End of Design' | 'Comp-Approve'     | ''       | 'CH41003ZB35'     |'C0402'| '(C0402-0201)'                                                       | '0.1UF'    | '16V'         | '20%'    | 'DISCRETE' | 'CAP CHIP 0.1U 16V(+80%-20%,Y5V,0402)'                         | 'CHIP0402'     | ''          | ''   | '2010709' 
 '0.1UF'    | '16V'   | '20%'     | '0402'      | 'EMPTY'   | 'CH41003ZB35'(!)   = 'End of Design' | 'Comp-Approve'     | ''       | 'CH41003ZB35'     |'C0402'| '(C0402-0201)'                                                       | 'NA'       | '16V'         | '20%'    | 'IO'       | 'CAP CHIP 0.1U 16V(+80%-20%,Y5V,0402)'                         | 'CHIP0402'     | ''          | ''   | '2010709' 
 '0.1UF'    | '50V'   | '10%'     | '0603'      | 'X7R'     | 'CH41006K911'(!)   = 'End of Design' | 'Comp-Approve'     | ''       | 'CH41006K911'     |'C0603'| '(SMC0603AW)'                                                        | '0.1UF'    | '50V'         | '10%'    | 'DISCRETE' | 'CAP CHIP 0.1U 50V(+-10%,X7R,0603)'                            | 'CHIP0603'     | ''          | ''   | '2010709' 
 '0.1UF'    | '50V'   | '10%'     | '0603'      | 'EMPTY'   | 'CH41006K911'(!)   = 'End of Design' | 'Comp-Approve'     | ''       | 'CH41006K911'     |'C0603'| '(SMC0603AW)'                                                        | 'NA'       | '50V'         | '10%'    | 'IO'       | 'CAP CHIP 0.1U 50V(+-10%,X7R,0603)'                            | 'CHIP0603'     | ''          | ''   | '2010709' 
 '0.1UF'    | '16V'   | '10%'     | '0402'      | 'X5R'     | 'CH4103K9B09'(!)   = 'End of Design' | 'Comp-Approve'     | ''       | 'CH4103K9B09'     |'C0402'| '(C0402-0201)'                                                       | '0.1UF'    | '16V'         | '10%'    | 'DISCRETE' | 'CAP CHIP 0.1U 16V(+-10%,X5R,0402) '                           | 'CHIP0402'     | ''          | ''   | '2010709' 
 '0.1UF'    | '16V'   | '10%'     | '0402'      | 'EMPTY'   | 'CH4103K9B09'(!)   = 'End of Design' | 'Comp-Approve'     | ''       | 'CH4103K9B09'     |'C0402'| '(C0402-0201)'                                                       | 'NA'       | '16V'         | '10%'    | 'IO'       | 'CAP CHIP 0.1U 16V(+-10%,X5R,0402) '                           | 'CHIP0402'     | ''          | ''   | '2010709' 
 '0.1UF'    | '25V'   | '20%'     | '0402'      | 'Y5V'     | 'CH4104Z3B07'(!)   = 'End of Design' | 'Comp-Approve'     | ''       | 'CH4104Z3B07'     |'C0402'| '(C0402-0201)'                                                       | '0.1UF'    | '25V'         | '20%'    | 'DISCRETE' | 'CAP CHIP 0.1U 25V(+80%-20%,Y5V,0402)'                         | 'CHIP0402'     | ''          | ''   | '2010709' 
 '0.1UF'    | '25V'   | '20%'     | '0402'      | 'EMPTY'   | 'CH4104Z3B07'(!)   = 'End of Design' | 'Comp-Approve'     | ''       | 'CH4104Z3B07'     |'C0402'| '(C0402-0201)'                                                       | 'NA'       | '25V'         | '20%'    | 'IO'       | 'CAP CHIP 0.1U 25V(+80%-20%,Y5V,0402)'                         | 'CHIP0402'     | ''          | ''   | '2010709' 
 '4.7UF'    | '25V'   | '10%'     | '0805'      | 'X6S'     | 'CH5474KEA06'(!)   = 'End of Design' | 'Comp-Approve'     | ''       | 'CH5474KEA06'     |'C0805_H61'| '(SMC0805AW)'                                                        | '4.7UF'    | '25V'         | '10%'    | 'DISCRETE' | 'CAP CHIP 4.7U 25V(+-10%,X6S,0805) EP'                         | 'CHIP0805'     | ''          | ''   | '2010709' 
 '4.7UF'    | '25V'   | '10%'     | '0805'      | 'EMPTY'   | 'CH5474KEA06'(!)   = 'End of Design' | 'Comp-Approve'     | ''       | 'CH5474KEA06'     |'C0805_H61'| '(SMC0805AW)'                                                        | 'NA'       | '25V'         | '10%'    | 'IO'       | 'CAP CHIP 4.7U 25V(+-10%,X6S,0805) EP'                         | 'CHIP0805'     | ''          | ''   | '2010709' 
 '22UF'     | '16V'   | '20%'     | '1206'      | 'X5R'     | 'CH6223M9200'(!)   = 'End of Design' | 'Comp-Approve'     | ''       | 'CH6223M9200'     |'C1206_H66'| '(SMC1206AW)'                                                        | '22UF'     | '16V'         | '20%'    | 'DISCRETE' | 'CAP CHIP 22UF 16V(+-20%,X5R,1206)'                            | 'CHIP1206'     | ''          | ''   | '2010709' 
 '22UF'     | '16V'   | '20%'     | '1206'      | 'EMPTY'   | 'CH6223M9200'(!)   = 'End of Design' | 'Comp-Approve'     | ''       | 'CH6223M9200'     |'C1206_H66'| '(SMC1206AW)'                                                        | 'NA'       | '16V'         | '20%'    | 'IO'       | 'CAP CHIP 22UF 16V(+-20%,X5R,1206)'                            | 'CHIP1206'     | ''          | ''   | '2010709' 
 '1UF'      | '10V'   | '20%'     | '0603'      | 'Y5V'     | 'CH5102Z3919'(!)   = 'End of Design' | 'Comp-Approve'     | ''       | 'CH5102Z3919'     |'C0603'| '(SMC0603AW)'                                                        | '1UF'      | '10V'         | '20%'    | 'DISCRETE' | 'CAP CHIP 1U 10V(+80%-20%,Y5V,0603)EP'                         | 'CHIP0603'     | ''          | ''   | '20107015'
 '1UF'      | '10V'   | '20%'     | '0603'      | 'EMPTY'   | 'CH5102Z3919'(!)   = 'End of Design' | 'Comp-Approve'     | ''       | 'CH5102Z3919'     |'C0603'| '(SMC0603AW)'                                                        | 'NA'       | '10V'         | '20%'    | 'IO'       | 'CAP CHIP 1U 10V(+80%-20%,Y5V,0603)EP'                         | 'CHIP0603'     | ''          | ''   | '20107015'
 '22PF '    | '50V'   | '5% '     | '0603'      | 'NPO'     | 'CH0226J0911'(!)   = ''              | 'End of Life'      | ''       | 'CH0226J0911'     |'C0603_EOL'| '(SMC0603AW)'                                                        | '22PF'     | '50V'         | '5% '    | 'DISCRETE' | 'CAP CHIP 22P 50V(+-5%,NPO,0603)    '                          | 'CHIP0603'     | ''          | ''   | '20107018'
 '22PF '    | '50V'   | '5% '     | '0603'      | 'EMPTY'   | 'CH0226J0911'(!)   = ''              | 'End of Life'      | ''       | 'CH0226J0911'     |'C0603_EOL'| '(SMC0603AW)'                                                        | 'NA'       | '50V'         | '5% '    | 'IO'       | 'CAP CHIP 22P 50V(+-5%,NPO,0603)    '                          | 'CHIP0603'     | ''          | ''   | '20107018'
 '0.1UF'    | '25V'   | '20%'     | '0603'      | 'Y5V'     | 'CH4104Z3916'(!)   = 'End of Design' | 'Comp-Approve'     | ''       | 'CH4104Z3916'     |'C0603'| '(SMC0603AW)'                                                        | '0.1UF'    | '25V'         | '20%'    | 'DISCRETE' | 'CAP CHIP 0.1U,25V(+80-20%,Y5V,0603)'                          | 'CHIP0603'     | ''          | ''   | '20107018'
 '0.1UF'    | '25V'   | '20%'     | '0603'      | 'EMPTY'   | 'CH4104Z3916'(!)   = 'End of Design' | 'Comp-Approve'     | ''       | 'CH4104Z3916'     |'C0603'| '(SMC0603AW)'                                                        | 'NA'       | '25V'         | '20%'    | 'IO'       | 'CAP CHIP 0.1U,25V(+80-20%,Y5V,0603)'                          | 'CHIP0603'     | ''          | ''   | '20107018'
 '10UF '    | '10V'   | '20%'     | '0603'      | 'X7R'     | 'CH6102M1909'(!)   = 'End of Design' | 'Comp-Approve'     | ''       | 'CH6102M1909'     |'C0603'| '(SMC0603AW)'                                                        | '10UF'     | '10V'         | '20%'    | 'DISCRETE' | 'CAP CHIP 10U,10V(+-20%,X7R,0603)   '                          | 'CHIP0603'     | ''          | ''   | '20107018'
 '10UF '    | '10V'   | '20%'     | '0603'      | 'EMPTY'   | 'CH6102M1909'(!)   = 'End of Design' | 'Comp-Approve'     | ''       | 'CH6102M1909'     |'C0603'| '(SMC0603AW)'                                                        | 'NA'       | '10V'         | '20%'    | 'IO'       | 'CAP CHIP 10U,10V(+-20%,X7R,0603)   '                          | 'CHIP0603'     | ''          | ''   | '20107018'
 '47UF '    | '10V'   | '20%'     | '1206'      | 'X5R'     | 'CH6472M9200'(!)   = 'End of Design' | 'Comp-Approve'     | ''       | 'CH6472M9200'     |'C1206_H76'| '(SMC1206AW)'                                                        | '47UF '    | '10V'         | '20%'    | 'DISCRETE' | 'CAP CHIP 47U 10V(+-20%,X5R,1206)  '                           | 'CHIP1206'     | ''          | ''   | '20107030'
 '47UF '    | '10V'   | '20%'     | '1206'      | 'EMPTY'   | 'CH6472M9200'(!)   = 'End of Design' | 'Comp-Approve'     | ''       | 'CH6472M9200'     |'C1206_H76'| '(SMC1206AW)'                                                        | 'NA'       | '10V'         | '20%'    | 'IO'       | 'CAP CHIP 47U 10V(+-20%,X5R,1206)  '                           | 'CHIP1206'     | ''          | ''   | '20107030'
 '27PF'     | '50V'   | '5%'      | '0402'      | 'NPO'     | 'CH02706JB06'(!)   = ''              | ''                 | ''       | 'CH02706JB06'     |'C0402'| '(C0402-0201)'                                                       | '27PF'     | '50V'         | '5%'     | 'DISCRETE' | 'CAP CHIP 27P 50V(+-5% NPO 0402)'                              | 'CHIP0402'     | ''          | ''   | '20100811'
 '27PF'     | '50V'   | '5%'      | '0402'      | 'EMPTY'   | 'CH02706JB06'(!)   = ''              | ''                 | ''       | 'CH02706JB06'     |'C0402'| '(C0402-0201)'                                                       | 'NA'       | '50V'         | '5%'     | 'IO'       | 'CAP CHIP 27P 50V(+-5% NPO 0402)'                              | 'CHIP0402'     | ''          | ''   | '20100811'
 '1NF'      | '50V'   | '10%'     | '0402'      | 'X7R'     | 'CH21006KB16'(!)   = ''              | ''                 | ''       | 'CH21006KB16'     |'C0402'| '(C0402-0201)'                                                       | '1NF'      | '50V'         | '10%'    | 'DISCRETE' | 'CAP CHIP 1N 50V(+-10%,X7R,0402)EP'                            | 'CHIP0402'     | ''          | ''   | '20100811'
 '1NF'      | '50V'   | '10%'     | '0402'      | 'EMPTY'   | 'CH21006KB16'(!)   = ''              | ''                 | ''       | 'CH21006KB16'     |'C0402'| '(C0402-0201)'                                                       | 'NA'       | '50V'         | '10%'    | 'IO'       | 'CAP CHIP 1N 50V(+-10%,X7R,0402)EP'                            | 'CHIP0402'     | ''          | ''   | '20100811'
 '0.1UF '   | '10V '  | '10%'     | '0402'      | 'X7R'     | 'CH4102K1B04'(!)   = ''              | ''                 | 'SELASS' | 'CH4102K1B04'     |'C0402'| '(C0402-0201)'                                                       | '0.1UF'    | '10V'         | '10%'    | 'DISCRETE' | 'CAP CHIP 0.1U 10V(+-10%,X7R,0402)SELASS  '                    | 'CHIP0402'     | ''          | ''   | '20100811'
 '0.1UF '   | '10V '  | '10%'     | '0402'      | 'EMPTY'   | 'CH4102K1B04'(!)   = ''              | ''                 | 'SELASS' | 'CH4102K1B04'     |'C0402'| '(C0402-0201)'                                                       | 'NA'       | '10V'         | '10%'    | 'IO'       | 'CAP CHIP 0.1U 10V(+-10%,X7R,0402)SELASS  '                    | 'CHIP0402'     | ''          | ''   | '20100811'
 '2.2UF '   | '6.3V'  | '20%'     | '0402'      | 'X5R'     | 'CH5221M9B02'(!)   = 'End of Design' | 'Comp-Release Qty' | ''       | 'CH5221M9B02'     |'C0402'| '(C0402-0201)'                                                       | '2.2UF'    | '6.3V'        | '20%'    | 'DISCRETE' | 'CAP CHIP 2.2U 6.3V(+-20%,X5R,0402)       '                    | 'CHIP0402'     | ''          | ''   | '20100811'
 '2.2UF '   | '6.3V'  | '20%'     | '0402'      | 'EMPTY'   | 'CH5221M9B02'(!)   = 'End of Design' | 'Comp-Release Qty' | ''       | 'CH5221M9B02'     |'C0402'| '(C0402-0201)'                                                       | 'NA'       | '6.3V'        | '20%'    | 'IO'       | 'CAP CHIP 2.2U 6.3V(+-20%,X5R,0402)       '                    | 'CHIP0402'     | ''          | ''   | '20100811'
 '2.2UF '   | '6.3V'  | '10%'     | '0603'      | 'X5R'     | 'CH5221K9911'(!)   = 'End of Design' | 'Comp-Approve'     | ''       | 'CH5221K9911'     |'C0603'| '(SMC0603AW)'                                                        | '2.2UF'    | '6.3V'        | '10%'    | 'DISCRETE' | 'CAP CHIP 2.2U 6.3V(10%,X5R,0603,H0.5)    '                    | 'CHIP0603'     | ''          | ''   | '20100811'
 '2.2UF '   | '6.3V'  | '10%'     | '0603'      | 'EMPTY'   | 'CH5221K9911'(!)   = 'End of Design' | 'Comp-Approve'     | ''       | 'CH5221K9911'     |'C0603'| '(SMC0603AW)'                                                        | 'NA'       | '6.3V'        | '10%'    | 'IO'       | 'CAP CHIP 2.2U 6.3V(10%,X5R,0603,H0.5)    '                    | 'CHIP0603'     | ''          | ''   | '20100811'
 '22UF  '   | '6.3V'  | '20%'     | '0805'      | 'X5R'     | 'CH6221M9A07'(!)   = 'End of Design' | 'Comp-Release Qty' | ''       | 'CH6221M9A07'     |'C0805_H61'| '(SMC0805AW)'                                                        | '22UF'     | '6.3V'        | '20%'    | 'DISCRETE' | 'CAP CHIP 22U 6.3V(+-20%,X5R,0805)        '                    | 'CHIP0805'     | ''          | ''   | '20100811'
 '22UF  '   | '6.3V'  | '20%'     | '0805'      | 'EMPTY'   | 'CH6221M9A07'(!)   = 'End of Design' | 'Comp-Release Qty' | ''       | 'CH6221M9A07'     |'C0805_H61'| '(SMC0805AW)'                                                        | 'NA'       | '6.3V'        | '20%'    | 'IO'       | 'CAP CHIP 22U 6.3V(+-20%,X5R,0805)        '                    | 'CHIP0805'     | ''          | ''   | '20100811'
 '1UF   '   | '25V '  | '10%'     | '0805'      | 'X5R'     | 'CH5104K9A08'(!)   = 'End of Design' | 'Comp-Approve'     | ''       | 'CH5104K9A08'     |'C0805_H43'| '(SMC0805AW)'                                                        | '1UF'      | '25V'         | '10%'    | 'DISCRETE' | 'CAP CHIP 1U 25V(+-10%,X5R,0805)H0.85     '                    | 'CHIP1206'     | ''          | ''   | '20107030'
 '1UF   '   | '25V '  | '10%'     | '0805'      | 'EMPTY'   | 'CH5104K9A08'(!)   = 'End of Design' | 'Comp-Approve'     | ''       | 'CH5104K9A08'     |'C0805_H43'| '(SMC0805AW)'                                                        | 'NA'       | '25V'         | '10%'    | 'IO'       | 'CAP CHIP 1U 25V(+-10%,X5R,0805)H0.85     '                    | 'CHIP1206'     | ''          | ''   | '20107030'
 '0.01UF '  | '25V'   | '10%'     | '0402'      | 'X7R'     | 'CH3104K1B08'(!)   = ''              | ''                 | 'SELASS' | 'CH3104K1B08'     |'C0402'| '(C0402-0201)'                                                       | '0.01UF'   | '25V'         | '10%'    | 'DISCRETE' | 'CAP CHIP 0.01U 25V(+-10%,X7R,0402)SELASS'                     | 'CHIP0402'     | ''          | ''   | '20100827'
 '0.01UF '  | '25V'   | '10%'     | '0402'      | 'EMPTY'   | 'CH3104K1B08'(!)   = ''              | ''                 | 'SELASS' | 'CH3104K1B08'     |'C0402'| '(C0402-0201)'                                                       | 'NA'       | '25V'         | '10%'    | 'IO'       | 'CAP CHIP 0.01U 25V(+-10%,X7R,0402)SELASS'                     | 'CHIP0402'     | ''          | ''   | '20100827'
 '20PF '    | '50V'   | '5% '     | '0603'      | 'NPO'     | 'CH02006J901'(!)   = ''              | ''                 | ''       | 'CH02006J901'     |'C0603'| '(SMC0603AW)'                                                        | '20PF'     | '50V'         | '5% '    | 'DISCRETE' | 'CAPACITOR CHIP 20P 50V(+-5%,NPO,0603)'                        | 'CHIP0603'     | ''          | ''   | '20100831'
 '20PF '    | '50V'   | '5% '     | '0603'      | 'EMPTY'   | 'CH02006J901'(!)   = ''              | ''                 | ''       | 'CH02006J901'     |'C0603'| '(SMC0603AW)'                                                        | 'NA'       | '50V'         | '5% '    | 'IO'       | 'CAPACITOR CHIP 20P 50V(+-5%,NPO,0603)'                        | 'CHIP0603'     | ''          | ''   | '20100831'
 '0.47UF'   | '10V'   | '10%'     | '0603'      | 'X7R'     | 'CH44702K912'(!)   = 'End of Design' | 'Comp-Approve'     | ''       | 'CH44702K912'     |'C0603'| '(SMC0603AW)'                                                        | '0.47UF'   | '10V'         | '10%'    | 'DISCRETE' | 'CAP CHIP 0.47U 10V(+-10%,X7R,0603)'                           | 'CHIP0603'     | ''          | ''   | ''        
 '0.47UF'   | '10V'   | '10%'     | '0603'      | 'EMPTY'   | 'CH44702K912'(!)   = 'End of Design' | 'Comp-Approve'     | ''       | 'CH44702K912'     |'C0603'| '(SMC0603AW)'                                                        | 'NA'       | '10V'         | '10%'    | 'IO'       | 'CAP CHIP 0.47U 10V(+-10%,X7R,0603)'                           | 'CHIP0603'     | ''          | ''   | ''        
 '1UF'      | '16V'   | '10%'     | '0603'      | 'X5R'     | 'CH5103K9901'(!)   = 'End of Design' | 'Comp-Approve'     | ''       | 'CH5103K9901'     |'C0603'| '(SMC0603AW)'                                                        | '1UF'      | '16V'         | '10%'    | 'DISCRETE' | 'CAP CHIP 1U 16V(+-10%,X5R,0603)'                              | 'CHIP0603'     | ''          | ''   | '20100914'
 '1UF'      | '16V'   | '10%'     | '0603'      | 'EMPTY'   | 'CH5103K9901'(!)   = 'End of Design' | 'Comp-Approve'     | ''       | 'CH5103K9901'     |'C0603'| '(SMC0603AW)'                                                        | 'NA'       | '16V'         | '10%'    | 'IO'       | 'CAP CHIP 1U 16V(+-10%,X5R,0603)'                              | 'CHIP0603'     | ''          | ''   | '20100914'
 '0.015UF'  | '50V'   | '10%'     | '0603'      | 'X7R'     | 'CH31506K917'(!)   = 'End of Design' | 'Comp-Approve'     | ''       | 'CH31506K917'     |'C0603'| '(SMC0603AW)'                                                        | '0.015UF'  | '50V'         | '10%'    | 'DISCRETE' | 'CAP CHIP 0.015U 50V(+-10%,X7R,0603)EP'                        | 'CHIP0603'     | ''          | ''   | '20100915'
 '0.015UF'  | '50V'   | '10%'     | '0603'      | 'EMPTY'   | 'CH31506K917'(!)   = 'End of Design' | 'Comp-Approve'     | ''       | 'CH31506K917'     |'C0603'| '(SMC0603AW)'                                                        | 'NA'       | '50V'         | '10%'    | 'IO'       | 'CAP CHIP 0.015U 50V(+-10%,X7R,0603)EP'                        | 'CHIP0603'     | ''          | ''   | '20100915'
 '0.22UF'   | '16V'   | '10%'     | '0402'      | 'X7R'     | 'CH4223K1B00'(!)   = 'End of Design' | 'Comp-Approve'     | ''       | 'CH4223K1B00'     |'C0402'| '(C0402_OCTAGONXA,C0402-0201)'                                       | '0.22UF'   | '16V'         | '10%'    | 'DISCRETE' | 'CAP CHIP 0.22U 16V(10%,X7R,0402)'                             | 'CHIP0402'     | ''          | ''   | '20100916'
 '0.22UF'   | '16V'   | '10%'     | '0402'      | 'EMPTY'   | 'CH4223K1B00'(!)   = 'End of Design' | 'Comp-Approve'     | ''       | 'CH4223K1B00'     |'C0402'| '(C0402_OCTAGONXA,C0402-0201)'                                       | 'NA'       | '16V'         | '10%'    | 'IO'       | 'CAP CHIP 0.22U 16V(10%,X7R,0402)'                             | 'CHIP0402'     | ''          | ''   | '20100916'
 '0.01UF'   | '16V'   | '10%'     | '0201'      | 'X7R'     | 'CH3103K1E00'(!)   = ''              | ''                 | ''       | 'CH3103K1E00'     |'C0201'| '(SMC0201AW)'                                                        | '0.01UF'   | '16V'         | '10%'    | 'DISCRETE' | 'CAP CHIP 0.01U 16V(+-10%,X7R,0201)'                           | 'CHIP0201'     | ''          | ''   | '20100923'
 '0.01UF'   | '16V'   | '10%'     | '0201'      | 'EMPTY'   | 'CH3103K1E00'(!)   = ''              | ''                 | ''       | 'CH3103K1E00'     |'C0201'| '(SMC0201AW)'                                                        | 'NA'       | '16V'         | '10%'    | 'IO'       | 'CAP CHIP 0.01U 16V(+-10%,X7R,0201)'                           | 'CHIP0201'     | ''          | ''   | '20100923'
 '18P'      | '50V'   | '5%'      | '0603'      | 'NPO'     | 'CH0186J0902'(!)   = 'End of Design' | 'Comp-Approve'     | ''       | 'CH0186J0902'     |'C0603'| '(SMC0603AW)'                                                        | '18PF'     | '50V'         | '5%'     | 'DISCRETE' | 'CAP CHIP 18P 50V(+-5%,NPO,0603)   '                           | 'CHIP0603'     | ''          | ''   | '20100923'
 '18P'      | '50V'   | '5%'      | '0603'      | 'EMPTY'   | 'CH0186J0902'(!)   = 'End of Design' | 'Comp-Approve'     | ''       | 'CH0186J0902'     |'C0603'| '(SMC0603AW)'                                                        | 'NA'       | '50V'         | '5%'     | 'IO'       | 'CAP CHIP 18P 50V(+-5%,NPO,0603)   '                           | 'CHIP0603'     | ''          | ''   | '20100923'
 '22PF'     | '50V'   | '5%'      | '0603'      | 'NPO'     | 'CH02206J909'(!)   = 'End of Design' | 'Comp-Approve'     | ''       | 'CH02206J909'     |'C0603'| '(SMC0603AW)'                                                        | '22PF'     | '50V'         | '5%'     | 'DISCRETE' | 'CAP CHIP 22P 50V(+-5%.NPO.0603)'                              | 'CHIP0603'     | ''          | ''   | '20100929'
 '22PF'     | '50V'   | '5%'      | '0603'      | 'EMPTY'   | 'CH02206J909'(!)   = 'End of Design' | 'Comp-Approve'     | ''       | 'CH02206J909'     |'C0603'| '(SMC0603AW)'                                                        | 'NA'       | '50V'         | '5%'     | 'IO'       | 'CAP CHIP 22P 50V(+-5%.NPO.0603)'                              | 'CHIP0603'     | ''          | ''   | '20100929'
 '100PF'    | '50V'   | '5%'      | '0402'      | 'X7R'     | 'CH11006JB18'(!)   = 'End of Design' | 'Comp-Approve'     | ''       | 'CH11006JB18'     |'C0402'| '(C0402-0201)'                                                       | '100PF'    | '50V'         | '5%'     | 'DISCRETE' | 'CAP CHIP 100P 50V(+-5%.X7R.0402)'                             | 'CHIP0402'     | ''          | ''   | '20100929'
 '100PF'    | '50V'   | '5%'      | '0402'      | 'EMPTY'   | 'CH11006JB18'(!)   = 'End of Design' | 'Comp-Approve'     | ''       | 'CH11006JB18'     |'C0402'| '(C0402-0201)'                                                       | 'NA'       | '50V'         | '5%'     | 'IO'       | 'CAP CHIP 100P 50V(+-5%.X7R.0402)'                             | 'CHIP0402'     | ''          | ''   | '20100929'
 '330PF'    | '50V'   | '5%'      | '0603'      | 'NPO'     | 'CH13306J907'(!)   = 'End of Design' | 'Comp-Approve'     | ''       | 'CH13306J907'     |'C0603'| '(SMC0603AW)'                                                        | '330PF'    | '50V'         | '5%'     | 'DISCRETE' | 'CAPACITOR CHIP 330P 50V(+-5%.NPO.0603)'                       | 'CHIP0603'     | ''          | ''   | '20100929'
 '330PF'    | '50V'   | '5%'      | '0603'      | 'EMPTY'   | 'CH13306J907'(!)   = 'End of Design' | 'Comp-Approve'     | ''       | 'CH13306J907'     |'C0603'| '(SMC0603AW)'                                                        | 'NA'       | '50V'         | '5%'     | 'IO'       | 'CAPACITOR CHIP 330P 50V(+-5%.NPO.0603)'                       | 'CHIP0603'     | ''          | ''   | '20100929'
 '3300PF'   | '50V'   | '10%'     | '0402'      | 'X7R'     | 'CH2336K1B01'(!)   = ''              | ''                 | 'SELASS' | 'CH2336K1B01'     |'C0402'| '(C0402-0201)'                                                       | '3300PF'   | '50V'         | '10%'    | 'DISCRETE' | 'CAP CHIP 3300P 50V(+-10%.X7R.0402)SELASS'                     | 'CHIP0402'     | ''          | ''   | '20100929'
 '3300PF'   | '50V'   | '10%'     | '0402'      | 'EMPTY'   | 'CH2336K1B01'(!)   = ''              | ''                 | 'SELASS' | 'CH2336K1B01'     |'C0402'| '(C0402-0201)'                                                       | 'NA'       | '50V'         | '10%'    | 'IO'       | 'CAP CHIP 3300P 50V(+-10%.X7R.0402)SELASS'                     | 'CHIP0402'     | ''          | ''   | '20100929'
 '1UF'      | '10V'   | '20%'     | '0603'      | 'Y5V'     | 'CH51002M930'(!)   = 'End of Design' | 'Comp-Approve'     | ''       | 'CH51002M930'     |'C0603'| '(SMC0603AW)'                                                        | '1UF'      | '10V'         | '20%'    | 'DISCRETE' | 'CAP CHIP 1U 10V(+-20%.Y5V.0603)'                              | 'CHIP0603'     | ''          | ''   | '20100929'
 '1UF'      | '10V'   | '20%'     | '0603'      | 'EMPTY'   | 'CH51002M930'(!)   = 'End of Design' | 'Comp-Approve'     | ''       | 'CH51002M930'     |'C0603'| '(SMC0603AW)'                                                        | 'NA'       | '10V'         | '20%'    | 'IO'       | 'CAP CHIP 1U 10V(+-20%.Y5V.0603)'                              | 'CHIP0603'     | ''          | ''   | '20100929'
 '3.3UF'    | '16V'   | '20%'     | '1206'      | 'Y5V'     | 'CH53303Z233'(!)   = 'End of Design' | 'Comp-Approve'     | ''       | 'CH53303Z233'     |'C1206_H56'| '(SMC1206AW)'                                                        | '3.3UF'    | '16V'         | '20%'    | 'DISCRETE' | 'CAP CHIP 3.3U.16V(+80%-20%.Y5V.1206)'                         | 'CHIP1206'     | ''          | ''   | '20100929'
 '3.3UF'    | '16V'   | '20%'     | '1206'      | 'EMPTY'   | 'CH53303Z233'(!)   = 'End of Design' | 'Comp-Approve'     | ''       | 'CH53303Z233'     |'C1206_H56'| '(SMC1206AW)'                                                        | 'NA'       | '16V'         | '20%'    | 'IO'       | 'CAP CHIP 3.3U.16V(+80%-20%.Y5V.1206)'                         | 'CHIP1206'     | ''          | ''   | '20100929'
 '10UF'     | '6.3V'  | '10%'     | '0805'      | 'X5R'     | 'CH61001KA94'(!)   = 'End of Design' | 'Comp-Approve'     | ''       | 'CH61001KA94'     |'C0805_H61'| '(SMC0805AW)'                                                        | '10UF'     | '6.3V'        | '10%'    | 'DISCRETE' | 'CAP CHIP 10UF.6.3V (+-10%.X5R.0805)'                          | 'CHIP0805'     | ''          | ''   | '20100929'
 '10UF'     | '6.3V'  | '10%'     | '0805'      | 'EMPTY'   | 'CH61001KA94'(!)   = 'End of Design' | 'Comp-Approve'     | ''       | 'CH61001KA94'     |'C0805_H61'| '(SMC0805AW)'                                                        | 'NA'       | '6.3V'        | '10%'    | 'IO'       | 'CAP CHIP 10UF.6.3V (+-10%.X5R.0805)'                          | 'CHIP0805'     | ''          | ''   | '20100929'
 '10PF'     | '50V'   | '5%'      | '0402'      | 'COG'     | 'CH01006JB08'(!)   = ''              | ''                 | ''       | 'CH01006JB08'     |'C0402'| '(C0402-0201)'                                                       | '10PF'     | '50V'         | '5%'     | 'DISCRETE' | 'CAP CHIP 10P 50V(+-5%,C0G,0402)'                              | 'CHIP0402'     | ''          | ''   | '20101013'
 '10PF'     | '50V'   | '5%'      | '0402'      | 'EMPTY'   | 'CH01006JB08'(!)   = ''              | ''                 | ''       | 'CH01006JB08'     |'C0402'| '(C0402-0201)'                                                       | 'NA'       | '50V'         | '5%'     | 'IO'       | 'CAP CHIP 10P 50V(+-5%,C0G,0402)'                              | 'CHIP0402'     | ''          | ''   | '20101013'
 '20PF'     | '50V'   | '5%'      | '0402'      | 'COG'     | 'CH0206J0B05'(!)   = ''              | ''                 | ''       | 'CH0206J0B05'     |'C0402'| '(C0402-0201)'                                                       | '20PF'     | '50V'         | '5%'     | 'DISCRETE' | 'CAP CHIP 20P 50V(+-5%,C0G,0402)'                              | 'CHIP0402'     | ''          | ''   | '20101026'
 '20PF'     | '50V'   | '5%'      | '0402'      | 'EMPTY'   | 'CH0206J0B05'(!)   = ''              | ''                 | ''       | 'CH0206J0B05'     |'C0402'| '(C0402-0201)'                                                       | 'NA'       | '50V'         | '5%'     | 'IO'       | 'CAP CHIP 20P 50V(+-5%,C0G,0402)'                              | 'CHIP0402'     | ''          | ''   | '20101026'
 '0.22UF'   | '6.3V'  | '10%'     | '0402'      | 'X5R'     | 'CH4221K9B00'(!)   = 'End of Design' | 'Comp-Approve'     | ''       | 'CH4221K9B00'     |'C0402'| '(C0402-0201)'                                                       | '0.22UF'   | '6.3V'        | '10%'    | 'DISCRETE' | 'CAP CHIP 0.22U 6.3V(+-10%,X5R,0402)'                          | 'CHIP0402'     | ''          | ''   | '20101026'
 '0.22UF'   | '6.3V'  | '10%'     | '0402'      | 'EMPTY'   | 'CH4221K9B00'(!)   = 'End of Design' | 'Comp-Approve'     | ''       | 'CH4221K9B00'     |'C0402'| '(C0402-0201)'                                                       | 'NA'       | '6.3V'        | '10%'    | 'IO'       | 'CAP CHIP 0.22U 6.3V(+-10%,X5R,0402)'                          | 'CHIP0402'     | ''          | ''   | '20101026'
 '1000PF'   | '2000V' | '10%'     | '1206'      | 'X7R'     | 'CH2100IK212'(!)   = ''              | ''                 | ''       | 'CH2100IK212'     |'C1206_H56'| '(SMC1206AW)'                                                        | '1000PF'   | '2KV'         | '10%'    | 'DISCRETE' | 'CAP CHIP 1000P 2KV(+-10%,X7R,1206)'                           | 'CHIP1206'     | ''          | ''   | '20101028'
 '1000PF'   | '2000V' | '10%'     | '1206'      | 'EMPTY'   | 'CH2100IK212'(!)   = ''              | ''                 | ''       | 'CH2100IK212'     |'C1206_H56'| '(SMC1206AW)'                                                        | 'NA'       | '2KV'         | '10%'    | 'IO'       | 'CAP CHIP 1000P 2KV(+-10%,X7R,1206)'                           | 'CHIP1206'     | ''          | ''   | '20101028'
 '18PF'     | '50V'   | '5%'      | '0402'      | 'C0G'     | 'CH01806JB07'(!)   = ''              | ''                 | ''       | 'CH01806JB07'     |'C0402'| '(C0402-0201)'                                                       | '18PF'     | '50V'         | '5%'     | 'DISCRETE' | 'CAP CHIP 18P 50V(+-5% C0G 0402)'                              | 'CHIP0402'     | ''          | ''   | '20110119'
 '18PF'     | '50V'   | '5%'      | '0402'      | 'EMPTY'   | 'CH01806JB07'(!)   = ''              | ''                 | ''       | 'CH01806JB07'     |'C0402'| '(C0402-0201)'                                                       | 'NA'       | '50V'         | '5%'     | 'IO'       | 'CAP CHIP 18P 50V(+-5% C0G 0402)'                              | 'CHIP0402'     | ''          | ''   | '20110119'
 '15PF'     | '50V'   | '5%'      | '0402'      | 'C0G'     | 'CH01506JB06'(!)   = ''              | ''                 | ''       | 'CH01506JB06'     |'C0402'| '(C0402-0201)'                                                       | '15PF'     | '50V'         | '5%'     | 'DISCRETE' | 'CAP CHIP 15P 50V(+-5% C0G 0402)'                              | 'CHIP0402'     | ''          | ''   | '20110207'
 '15PF'     | '50V'   | '5%'      | '0402'      | 'EMPTY'   | 'CH01506JB06'(!)   = ''              | ''                 | ''       | 'CH01506JB06'     |'C0402'| '(C0402-0201)'                                                       | 'NA'       | '50V'         | '5%'     | 'IO'       | 'CAP CHIP 15P 50V(+-5% C0G 0402)'                              | 'CHIP0402'     | ''          | ''   | '20110207'
 '1000PF'   | '3KV'   | '10%'     | '1808'      | 'X7R'     | 'CH2100GKI12'(!)   = ''              | ''                 | ''       | 'CH2100GKI12'     |'C1808_H86'| '(SMC1808AW)'                                                        | '1000PF'   | '3KV'         | '10%'    | 'DISCRETE' | 'CAP CHIP 1000P 3KV(+-10%.X7R.1808)'                           | 'CHIP1808'     | ''          | ''   | '20110207'
 '1000PF'   | '3KV'   | '10%'     | '1808'      | 'EMPTY'   | 'CH2100GKI12'(!)   = ''              | ''                 | ''       | 'CH2100GKI12'     |'C1808_H86'| '(SMC1808AW)'                                                        | 'NA'       | '3KV'         | '10%'    | 'IO'       | 'CAP CHIP 1000P 3KV(+-10%.X7R.1808)'                           | 'CHIP1808'     | ''          | ''   | '20110207'
 '3.3PF'    | '50V'   | '0.25P'   | '0402'      | 'C0G'     | 'CH-3306TB04'(!)   = ''              | ''                 | ''       | 'CH-3306TB04'     |'C0402'| '(C0402-0201)'                                                       | '3.3PF'    | '50V'         | '0.25P'  | 'DISCRETE' | 'CAP CHIP 3.3P 50V(+-0.25P C0G 0402)'                          | 'CHIP0402'     | ''          | ''   | '20110207'
 '3.3PF'    | '50V'   | '0.25P'   | '0402'      | 'EMPTY'   | 'CH-3306TB04'(!)   = ''              | ''                 | ''       | 'CH-3306TB04'     |'C0402'| '(C0402-0201)'                                                       | 'NA'       | '50V'         | '0.25P'  | 'IO'       | 'CAP CHIP 3.3P 50V(+-0.25P C0G 0402)'                          | 'CHIP0402'     | ''          | ''   | '20110207'
 '3PF'      | '50V'   | '0.25P'   | '0402'      | 'C0G'     | 'CH-3006TB03'(!)   = 'End of Design' | 'Comp-Approve'     | ''       | 'CH-3006TB03'     |'C0402'| '(C0402-0201)'                                                       | '3PF'      | '50V'         | '0.25P'  | 'DISCRETE' | 'CAP CHIP 3P 50V(+-0.25P,COG,0402)'                            | 'CHIP0402'     | ''          | ''   | '20110216'
 '3PF'      | '50V'   | '0.25P'   | '0402'      | 'EMPTY'   | 'CH-3006TB03'(!)   = 'End of Design' | 'Comp-Approve'     | ''       | 'CH-3006TB03'     |'C0402'| '(C0402-0201)'                                                       | 'NA'       | '50V'         | '0.25P'  | 'IO'       | 'CAP CHIP 3P 50V(+-0.25P,COG,0402)'                            | 'CHIP0402'     | ''          | ''   | '20110216'
 '10UF'     | '10V'   | '20%'     | '0603'      | 'X5R'     | 'CH6102M9900'(!)   = 'End of Design' | 'Comp-Approve'     | ''       | 'CH6102M9900'     |'C0603'| '(SMC0603AW)'                                                        | '10UF'     | '10V'         | '20%'    | 'DISCRETE' | 'CAP CHIP 10U 10V(+-20%.X5R.0603)'                             | 'CHIP0603'     | ''          | ''   | '20110223'
 '10UF'     | '10V'   | '20%'     | '0603'      | 'EMPTY'   | 'CH6102M9900'(!)   = 'End of Design' | 'Comp-Approve'     | ''       | 'CH6102M9900'     |'C0603'| '(SMC0603AW)'                                                        | 'NA'       | '10V'         | '20%'    | 'IO'       | 'CAP CHIP 10U 10V(+-20%.X5R.0603)'                             | 'CHIP0603'     | ''          | ''   | '20110223'
 '3.0PF'    | '50V'   | '0.25P'   | '0402'      | 'NPO'     | 'CH-306C0B07'(!)   = ''              | ''                 | ''       | 'CH-306C0B07'     |'C0402'| '(C0402-0201)'                                                       | '3.0PF'    | '50V'         | '0.25P'  | 'DISCRETE' | 'CAP CHIP 3P,50V(+-0.25P,NPO,0402)'                            | 'CHIP0402'     | ''          | ''   | '20110224'
 '3.0PF'    | '50V'   | '0.25P'   | '0402'      | 'EMPTY'   | 'CH-306C0B07'(!)   = ''              | ''                 | ''       | 'CH-306C0B07'     |'C0402'| '(C0402-0201)'                                                       | 'NA'       | '50V'         | '0.25P'  | 'IO'       | 'CAP CHIP 3P,50V(+-0.25P,NPO,0402)'                            | 'CHIP0402'     | ''          | ''   | '20110224'
 '6.8PF'    | '50V'   | '0.1P'    | '0402'      | 'NPO'     | 'CH-6816TB05'(!)   = 'End of Design' | 'Comp-Approve'     | ''       | 'CH-6816TB05'     |'C0402'| '(C0402-0201)'                                                       | '6.8PF'    | '50V'         | '0.1P'   | 'DISCRETE' | 'CAP CHIP 6.8P 50V (+-0.1P NPO 0402)'                          | 'CHIP0402'     | ''          | ''   | '20110224'
 '6.8PF'    | '50V'   | '0.1P'    | '0402'      | 'EMPTY'   | 'CH-6816TB05'(!)   = 'End of Design' | 'Comp-Approve'     | ''       | 'CH-6816TB05'     |'C0402'| '(C0402-0201)'                                                       | 'NA'       | '50V'         | '0.1P'   | 'IO'       | 'CAP CHIP 6.8P 50V (+-0.1P NPO 0402)'                          | 'CHIP0402'     | ''          | ''   | '20110224'
 '1UF'      | '25V'   | '10%'     | '0603'      | 'X7R'     | 'CH5104K1900'(!)   = 'End of Design' | 'Comp-Approve'     | ''       | 'CH5104K1900'     |'C0603'| '(SMC0603AW)'                                                        | '1UF'      | '25V'         | '10%'    | 'DISCRETE' | 'CAP CHIP 1U 25V(+-10%.X7R.0603)'                              | 'CHIP0603'     | ''          | ''   | '20110330'
 '1UF'      | '25V'   | '10%'     | '0603'      | 'EMPTY'   | 'CH5104K1900'(!)   = 'End of Design' | 'Comp-Approve'     | ''       | 'CH5104K1900'     |'C0603'| '(SMC0603AW)'                                                        | 'NA'       | '25V'         | '10%'    | 'IO'       | 'CAP CHIP 1U 25V(+-10%.X7R.0603)'                              | 'CHIP0603'     | ''          | ''   | '20110330'
 '0.022UF'  | '25V'   | '10%'     | '0402'      | 'X7R'     | 'CH3224K1B01'(!)   = ''              | ''                 | ''       | 'CH3224K1B01'     |'C0402'| '(C0402_OCTAGONXA,C0402-0201)'                                       | '0.022UF'  | '25V'         | '10%'    | 'DISCRETE' | 'CAP CHIP 0.022U 25V(+-10%,X7R,0402)'                          | 'CHIP0402'     | ''          | ''   | '20110413'
 '0.022UF'  | '25V'   | '10%'     | '0402'      | 'EMPTY'   | 'CH3224K1B01'(!)   = ''              | ''                 | ''       | 'CH3224K1B01'     |'C0402'| '(C0402_OCTAGONXA,C0402-0201)'                                       | 'NA'       | '25V'         | '10%'    | 'IO'       | 'CAP CHIP 0.022U 25V(+-10%,X7R,0402)'                          | 'CHIP0402'     | ''          | ''   | '20110413'
 '4.7UF'    | '4V'    | '10%'     | '0603'      | 'X6S'     | 'CH547KKE900'(!)   = 'End of Design' | 'Comp-Approve'     | ''       | 'CH547KKE900'     |'C0603'| '(SMC0603AW)'                                                        | '4.7UF'    | '4V'          | '10%'    | 'DISCRETE' | 'CAP CHIP 4.7U 4V(+-10%,X6S,0603)'                             | 'CHIP0603'     | ''          | ''   | '20110414'
 '4.7UF'    | '4V'    | '10%'     | '0603'      | 'EMPTY'   | 'CH547KKE900'(!)   = 'End of Design' | 'Comp-Approve'     | ''       | 'CH547KKE900'     |'C0603'| '(SMC0603AW)'                                                        | 'NA'       | '4V'          | '10%'    | 'IO'       | 'CAP CHIP 4.7U 4V(+-10%,X6S,0603)'                             | 'CHIP0603'     | ''          | ''   | '20110414'
 '10UF'     | '6.3V'  | '10%'     | '0805'      | 'X7R'     | 'CH6101K1A00'(!)   = 'End of Design' | 'Comp-Approve'     | ''       | 'CH6101K1A00'     |'C0805_H61'| '(SMC0805AW)'                                                        | '10UF'     | '6.3V'        | '10%'    | 'DISCRETE' | 'CAP CHIP 10UF 6.3V(+-10%,X7R,0805)H1.25'                      | 'CHIP0805'     | ''          | ''   | '20110415'
 '10UF'     | '6.3V'  | '10%'     | '0805'      | 'EMPTY'   | 'CH6101K1A00'(!)   = 'End of Design' | 'Comp-Approve'     | ''       | 'CH6101K1A00'     |'C0805_H61'| '(SMC0805AW)'                                                        | 'NA'       | '6.3V'        | '10%'    | 'IO'       | 'CAP CHIP 10UF 6.3V(+-10%,X7R,0805)H1.25'                      | 'CHIP0805'     | ''          | ''   | '20110415'
 '10UF'     | '6.3V'  | '20%'     | '0805'      | 'X6S'     | 'CH61001MEE3'(!)   = 'End of Design' | 'Comp-Approve'     | ''       | 'CH61001MEE3'     |'C0805_H61'| '(SMC0805AW)'                                                        | '10UF'     | '6.3V'        | '20%'    | 'DISCRETE' | 'CAP CHIP 10UF 6.3V(+-20%.X6S.0805)'                           | 'CHIP0805'     | ''          | ''   | '20110415'
 '10UF'     | '6.3V'  | '20%'     | '0805'      | 'EMPTY'   | 'CH61001MEE3'(!)   = 'End of Design' | 'Comp-Approve'     | ''       | 'CH61001MEE3'     |'C0805_H61'| '(SMC0805AW)'                                                        | 'NA'       | '6.3V'        | '20%'    | 'IO'       | 'CAP CHIP 10UF 6.3V(+-20%.X6S.0805)'                           | 'CHIP0805'     | ''          | ''   | '20110415'
 '10UF'     | '4V'    | '20%'     | '0805'      | 'X6S'     | 'CH6100KMEE3'(!)   = 'End of Design' | 'Comp-Approve'     | ''       | 'CH6100KMEE3'     |'C0805_H61'| '(SMC0805AW)'                                                        | '10UF'     | '4V'          | '20%'    | 'DISCRETE' | 'CAP CHIP 10U.4V(+-20%.X6S.0805) EP'                           | 'CHIP0805'     | ''          | ''   | '20110415'
 '10UF'     | '4V'    | '20%'     | '0805'      | 'EMPTY'   | 'CH6100KMEE3'(!)   = 'End of Design' | 'Comp-Approve'     | ''       | 'CH6100KMEE3'     |'C0805_H61'| '(SMC0805AW)'                                                        | 'NA'       | '4V'          | '20%'    | 'IO'       | 'CAP CHIP 10U.4V(+-20%.X6S.0805) EP'                           | 'CHIP0805'     | ''          | ''   | '20110415'
 '10UF'     | '4V'    | '20%'     | '0603'      | 'X6S'     | 'CH610KME901'(!)   = ''              | 'End of Life'      | ''       | 'CH610KME901'     |'C0603_EOL'| '(SMC0603AW)'                                                        | '10UF'     | '4V'          | '20%'    | 'DISCRETE' | 'CAP CHIP 10U 4V(+-20%,X6S,0603)'                              | 'CHIP0603'     | ''          | ''   | '20110415'
 '10UF'     | '4V'    | '20%'     | '0603'      | 'EMPTY'   | 'CH610KME901'(!)   = ''              | 'End of Life'      | ''       | 'CH610KME901'     |'C0603_EOL'| '(SMC0603AW)'                                                        | 'NA'       | '4V'          | '20%'    | 'IO'       | 'CAP CHIP 10U 4V(+-20%,X6S,0603)'                              | 'CHIP0603'     | ''          | ''   | '20110415'
 '4.7UF'    | '16V'   | '20%'     | '0805'      | 'X7R'     | 'CH5473M1A01'(!)   = 'End of Design' | 'Comp-Approve'     | ''       | 'CH5473M1A01'     |'C0805_H61'| '(SMC0805AW)'                                                        | '4.7UF'    | '16V'         | '20%'    | 'DISCRETE' | 'CAP CHIP 4.7U 16V(+-20%,X7R,0805)H1.25'                       | 'CHIP0805'     | ''          | ''   | '20110425'
 '4.7UF'    | '16V'   | '20%'     | '0805'      | 'EMPTY'   | 'CH5473M1A01'(!)   = 'End of Design' | 'Comp-Approve'     | ''       | 'CH5473M1A01'     |'C0805_H61'| '(SMC0805AW)'                                                        | 'NA'       | '16V'         | '20%'    | 'IO'       | 'CAP CHIP 4.7U 16V(+-20%,X7R,0805)H1.25'                       | 'CHIP0805'     | ''          | ''   | '20110425'
 '1500PF'   | '50V'   | '10%'     | '0603'      | 'X7R'     | 'CH21506K915'(!)   = 'End of Design' | 'Comp-Approve'     | ''       | 'CH21506K915'     |'C0603'| '(SMC0603AW)'                                                        | '1500PF'   | '50V'         | '10%'    | 'DISCRETE' | 'CAP CHIP 1500P 50V(+-10%.X7R.0603)'                           | 'CHIP0603'     | ''          | ''   | '20110624'
 '1500PF'   | '50V'   | '10%'     | '0603'      | 'EMPTY'   | 'CH21506K915'(!)   = 'End of Design' | 'Comp-Approve'     | ''       | 'CH21506K915'     |'C0603'| '(SMC0603AW)'                                                        | 'NA'       | '50V'         | '10%'    | 'IO'       | 'CAP CHIP 1500P 50V(+-10%.X7R.0603)'                           | 'CHIP0603'     | ''          | ''   | '20110624'
 '12PF'     | '50V'   | '2%'      | '0402'      | 'C0G'     | 'CH0126G0B00'(!)   = ''              | ''                 | ''       | 'CH0126G0B00'     |'C0402'| '(C0402-0201)'                                                       | '12PF'     | '50V'         | '2%'     | 'DISCRETE' | 'CAP CHIP 12P 50V(+-2%,C0G,0402)'                              | 'CHIP0402'     | ''          | ''   | '20110628'
 '12PF'     | '50V'   | '2%'      | '0402'      | 'EMPTY'   | 'CH0126G0B00'(!)   = ''              | ''                 | ''       | 'CH0126G0B00'     |'C0402'| '(C0402-0201)'                                                       | 'NA'       | '50V'         | '2%'     | 'IO'       | 'CAP CHIP 12P 50V(+-2%,C0G,0402)'                              | 'CHIP0402'     | ''          | ''   | '20110628'
 '39PF'     | '50V'   | '5%'      | '0402'      | 'NPO'     | 'CH03906JB06'(!)   = ''              | ''                 | ''       | 'CH03906JB06'     |'C0402'| '(C0402-0201)'                                                       | '39PF'     | '50V'         | '5%'     | 'DISCRETE' | 'CAP CHIP 39P 50V(+-5%.NPO.0402)'                              | 'CHIP0402'     | ''          | ''   | '20110628'
 '39PF'     | '50V'   | '5%'      | '0402'      | 'EMPTY'   | 'CH03906JB06'(!)   = ''              | ''                 | ''       | 'CH03906JB06'     |'C0402'| '(C0402-0201)'                                                       | 'NA'       | '50V'         | '5%'     | 'IO'       | 'CAP CHIP 39P 50V(+-5%.NPO.0402)'                              | 'CHIP0402'     | ''          | ''   | '20110628'
 '4.7UF'    | '10V'   | '10%'     | '0805'      | 'X7R'     | 'CH5472K1A00'(!)   = 'End of Design' | 'Comp-Approve'     | 'SELASS' | 'CH5472K1A00'     |'C0805_H61'| '(SMC0805AW)'                                                        | '4.7UF'    | '10V'         | '10%'    | 'DISCRETE' | 'CAP CHIP 4.7UF 10V(+-10%.X7R.0805)SELASS'                     | 'CHIP0805'     | ''          | ''   | '20100823'
 '4.7UF'    | '10V'   | '10%'     | '0805'      | 'EMPTY'   | 'CH5472K1A00'(!)   = 'End of Design' | 'Comp-Approve'     | 'SELASS' | 'CH5472K1A00'     |'C0805_H61'| '(SMC0805AW)'                                                        | 'NA'       | '10V'         | '10%'    | 'IO'       | 'CAP CHIP 4.7UF 10V(+-10%.X7R.0805)SELASS'                     | 'CHIP0805'     | ''          | ''   | '20100823'
 '3.3UF'    | '10V'   | '10%'     | '0603'      | 'X5R'     | 'CH5332K9900'(!)   = 'End of Design' | 'Comp-Approve'     | ''       | 'CH5332K9900'     |'C0603'| '(SMC0603AW)'                                                        | '3.3UF'    | '10V'         | '10%'    | 'DISCRETE' | 'CAP CHIP 3.3U 10V(+-10%,X5R,0603)'                            | 'CHIP0603'     | ''          | ''   | '20110720'
 '3.3UF'    | '10V'   | '10%'     | '0603'      | 'EMPTY'   | 'CH5332K9900'(!)   = 'End of Design' | 'Comp-Approve'     | ''       | 'CH5332K9900'     |'C0603'| '(SMC0603AW)'                                                        | 'NA'       | '10V'         | '10%'    | 'IO'       | 'CAP CHIP 3.3U 10V(+-10%,X5R,0603)'                            | 'CHIP0603'     | ''          | ''   | '20110720'
 '1800PF'   | '50V'   | '10%'     | '0402'      | 'X7R'     | 'CH21806KB15'(!)   = ''              | ''                 | ''       | 'CH21806KB15'     |'C0402'| '(C0402-0201)'                                                       | '1800PF'   | '50V'         | '10%'    | 'DISCRETE' | 'CAP CHIP 1800P 50V(+-10%.X7R.0402)'                           | 'CHIP0402'     | ''          | ''   | '20110826'
 '1800PF'   | '50V'   | '10%'     | '0402'      | 'EMPTY'   | 'CH21806KB15'(!)   = ''              | ''                 | ''       | 'CH21806KB15'     |'C0402'| '(C0402-0201)'                                                       | 'NA'       | '50V'         | '10%'    | 'IO'       | 'CAP CHIP 1800P 50V(+-10%.X7R.0402)'                           | 'CHIP0402'     | ''          | ''   | '20110826'
 '4700PF'   | '50V'   | '10%'     | '0603'      | 'X7R'     | 'CH2476K1929'(!)   = 'End of Design' | 'Comp-Approve'     | ''       | 'CH2476K1929'     |'C0603'| '(SMC0603AW)'                                                        | '4700PF'   | '50V'         | '10%'    | 'DISCRETE' | 'CAP CHIP 4700P,50V(+-10%,X7R,0603)'                           | 'CHIP0603'     | ''          | ''   | '20110920'
 '4700PF'   | '50V'   | '10%'     | '0603'      | 'EMPTY'   | 'CH2476K1929'(!)   = 'End of Design' | 'Comp-Approve'     | ''       | 'CH2476K1929'     |'C0603'| '(SMC0603AW)'                                                        | 'NA'       | '50V'         | '10%'    | 'IO'       | 'CAP CHIP 4700P,50V(+-10%,X7R,0603)'                           | 'CHIP0603'     | ''          | ''   | '20110920'
 '0.1UF'    | '10V'   | '10%'     | '0201'      | 'X5R'     | 'CH4102K9E00'(!)   = ''              | ''                 | ''       | 'CH4102K9E00'     |'C0201'| '(SMC0201AW)'                                                        | '0.1UF'    | '10V'         | '10%'    | 'DISCRETE' | 'CAP CHIP 0.1U 10V(+-10%.X5R.0201)'                            | 'CHIP0201'     | ''          | ''   | '20111207'
 '0.1UF'    | '10V'   | '10%'     | '0201'      | 'EMPTY'   | 'CH4102K9E00'(!)   = ''              | ''                 | ''       | 'CH4102K9E00'     |'C0201'| '(SMC0201AW)'                                                        | 'NA'       | '10V'         | '10%'    | 'IO'       | 'CAP CHIP 0.1U 10V(+-10%.X5R.0201)'                            | 'CHIP0201'     | ''          | ''   | '20111207'
 '27PF'     | '50V'   | '5%'      | '0603'      | 'NPO'     | 'CH0276J0905'(!)   = 'End of Design' | 'Comp-Approve'     | 'SELASS' | 'CH0276J0905'     |'C0603'| '(SMC0603AW)'                                                        | '27PF'     | '50V'         | '5%'     | 'DISCRETE' | 'CAP CHIP 27P 50V(+-5%.NPO.0603)SELASS'                        | 'CHIP0603'     | ''          | ''   | '20111208'
 '27PF'     | '50V'   | '5%'      | '0603'      | 'EMPTY'   | 'CH0276J0905'(!)   = 'End of Design' | 'Comp-Approve'     | 'SELASS' | 'CH0276J0905'     |'C0603'| '(SMC0603AW)'                                                        | 'NA'       | '50V'         | '5%'     | 'IO'       | 'CAP CHIP 27P 50V(+-5%.NPO.0603)SELASS'                        | 'CHIP0603'     | ''          | ''   | '20111208'
 '0.015UF'  | '16V'   | '10%'     | '0402'      | 'X7R'     | 'CH3153K1B12'(!)   = ''              | ''                 | ''       | 'CH3153K1B12'     |'C0402'| '(C0402-0201)'                                                       | '0.015UF'  | '16V'         | '10%'    | 'DISCRETE' | 'CAP CHIP 0.015U 16V(+-10%.X7R.0402)'                          | 'CHIP0402'     | ''          | ''   | '20111209'
 '0.015UF'  | '16V'   | '10%'     | '0402'      | 'EMPTY'   | 'CH3153K1B12'(!)   = ''              | ''                 | ''       | 'CH3153K1B12'     |'C0402'| '(C0402-0201)'                                                       | 'NA'       | '16V'         | '10%'    | 'IO'       | 'CAP CHIP 0.015U 16V(+-10%.X7R.0402)'                          | 'CHIP0402'     | ''          | ''   | '20111209'
 '0.047UF'  | '10V'   | '10%'     | '0402'      | 'X7R'     | 'CH34702KB10'(!)   = ''              | ''                 | ''       | 'CH34702KB10'     |'C0402'| '(C0402-0201)'                                                       | '0.047UF'  | '10V'         | '10%'    | 'DISCRETE' | 'CAP CHIP 0.047U 10V(+-10% X7R 0402)'                          | 'CHIP0402'     | ''          | ''   | '20111209'
 '0.047UF'  | '10V'   | '10%'     | '0402'      | 'EMPTY'   | 'CH34702KB10'(!)   = ''              | ''                 | ''       | 'CH34702KB10'     |'C0402'| '(C0402-0201)'                                                       | 'NA'       | '10V'         | '10%'    | 'IO'       | 'CAP CHIP 0.047U 10V(+-10% X7R 0402)'                          | 'CHIP0402'     | ''          | ''   | '20111209'
 '10PF'     | '50V'   | '0.5P'    | 'C0402'     | 'COH'     | 'CH01006JBD1'(!)   = 'End of Design' | 'Comp-Approve'     | ''       | 'CH01006JBD1'     |'C0402'| '(C0402-0201)'                                                       | '10PF'     | '50V'         | '0.5P'   | 'DISCRETE' | 'CAP CHIP 10P 50V(+-0.5P.COH.0402)'                            | 'CHIP0402'     | ''          | ''   | '20111213'
 '10PF'     | '50V'   | '0.5P'    | 'C0402'     | 'EMPTY'   | 'CH01006JBD1'(!)   = 'End of Design' | 'Comp-Approve'     | ''       | 'CH01006JBD1'     |'C0402'| '(C0402-0201)'                                                       | 'NA'       | '50V'         | '0.5P'   | 'IO'       | 'CAP CHIP 10P 50V(+-0.5P.COH.0402)'                            | 'CHIP0402'     | ''          | ''   | '20111213'
 '0.01UF'   | '50V'   | '5%'      | 'C0603'     | 'X7R'     | 'CH3106J1905'(!)   = 'End of Design' | 'Comp-Approve'     | ''       | 'CH3106J1905'     |'C0603'| '(SMC0603AW)'                                                        | '0.01UF'   | '50V'         | '5%'     | 'DISCRETE' | 'CAP CHIP 0.01U 50V(+-5%.X7R.0603)'                            | 'CHIP0603'     | ''          | ''   | '20111213'
 '0.01UF'   | '50V'   | '5%'      | 'C0603'     | 'EMPTY'   | 'CH3106J1905'(!)   = 'End of Design' | 'Comp-Approve'     | ''       | 'CH3106J1905'     |'C0603'| '(SMC0603AW)'                                                        | 'NA'       | '50V'         | '5%'     | 'IO'       | 'CAP CHIP 0.01U 50V(+-5%.X7R.0603)'                            | 'CHIP0603'     | ''          | ''   | '20111213'
 '0.1UF'    | '16V'   | '10%'     | 'C0603'     | 'X7R'     | 'CH41003K914'(!)   = 'End of Design' | 'Comp-Approve'     | ''       | 'CH41003K914'     |'C0603'| '(SMC0603AW)'                                                        | '0.1UF'    | '16V'         | '10%'    | 'DISCRETE' | 'CAP CHIP 0.1U 16V(+-10%. X7R.0603)'                           | 'CHIP0603'     | ''          | ''   | '20111213'
 '0.1UF'    | '16V'   | '10%'     | 'C0603'     | 'EMPTY'   | 'CH41003K914'(!)   = 'End of Design' | 'Comp-Approve'     | ''       | 'CH41003K914'     |'C0603'| '(SMC0603AW)'                                                        | 'NA'       | '16V'         | '10%'    | 'IO'       | 'CAP CHIP 0.1U 16V(+-10%. X7R.0603)'                           | 'CHIP0603'     | ''          | ''   | '20111213'
 '4.7UF'    | '6.3V'  | '10%'     | 'C0603'     | 'X5R'     | 'CH5471K9E07'(!)   = 'End of Design' | 'Comp-Release Qty' | ''       | 'CH5471K9E07'     |'C0603'| '(SMC0603AW)'                                                        | '4.7UF'    | '6.3V'        | '10%'    | 'DISCRETE' | 'CAP CHIP 4.7U 6.3V(+-10%.X5R.0603)'                           | 'CHIP0603'     | ''          | ''   | '20111213'
 '4.7UF'    | '6.3V'  | '10%'     | 'C0603'     | 'EMPTY'   | 'CH5471K9E07'(!)   = 'End of Design' | 'Comp-Release Qty' | ''       | 'CH5471K9E07'     |'C0603'| '(SMC0603AW)'                                                        | 'NA'       | '6.3V'        | '10%'    | 'IO'       | 'CAP CHIP 4.7U 6.3V(+-10%.X5R.0603)'                           | 'CHIP0603'     | ''          | ''   | '20111213'
 '8200PF'   | '25V'   | '10%'     | 'C0402'     | 'X7R'     | 'CH2824K1B05'(!)   = ''              | ''                 | ''       | 'CH2824K1B05'     |'C0402'| '(C0402-0201)'                                                       | '8200PF'   | '25V'         | '10%'    | 'DISCRETE' | 'CAP CHIP 8200P 25V (+-10%.X7R.0402)'                          | 'CHIP0402'     | ''          | ''   | '20111229'
 '8200PF'   | '25V'   | '10%'     | 'C0402'     | 'EMPTY'   | 'CH2824K1B05'(!)   = ''              | ''                 | ''       | 'CH2824K1B05'     |'C0402'| '(C0402-0201)'                                                       | 'NA'       | '25V'         | '10%'    | 'IO'       | 'CAP CHIP 8200P 25V (+-10%.X7R.0402)'                          | 'CHIP0402'     | ''          | ''   | '20111229'
 '100PF'    | '50V'   | '5%'      | 'C0402_SEL' | 'C0G'     | 'CH1106J0B09'(!)   = ''              | ''                 | 'SELASS' | 'CH1106J0B09'     |'C0402'| '(C0402-0201)'                                                       | '100PF'    | '50V'         | '5%'     | 'DISCRETE' | 'CAP CHIP 100P 50V(+-5%.C0G.0402)SEL ASN'                      | 'CHIP0402'     | ''          | ''   | '20111229'
 '100PF'    | '50V'   | '5%'      | 'C0402_SEL' | 'EMPTY'   | 'CH1106J0B09'(!)   = ''              | ''                 | 'SELASS' | 'CH1106J0B09'     |'C0402'| '(C0402-0201)'                                                       | 'NA'       | '50V'         | '5%'     | 'IO'       | 'CAP CHIP 100P 50V(+-5%.C0G.0402)SEL ASN'                      | 'CHIP0402'     | ''          | ''   | '20111229'
 '22UF'     | '6.3V'  | '10%'     | 'C0805_SEL' | 'X5R'     | 'CH6221M9A16'(!)   = ''              | ''                 | 'SELASS' | 'CH6221M9A16'     |'C0805_H61'| '(SMC0805AW)'                                                        | '22UF'     | '6.3V'        | '10%'    | 'DISCRETE' | 'CAP CHIP 22U 6.3V(+-20%.X5R.0805)SELASS'                      | 'CHIP0805'     | ''          | ''   | '20111229'
 '22UF'     | '6.3V'  | '10%'     | 'C0805_SEL' | 'EMPTY'   | 'CH6221M9A16'(!)   = ''              | ''                 | 'SELASS' | 'CH6221M9A16'     |'C0805_H61'| '(SMC0805AW)'                                                        | 'NA'       | '6.3V'        | '10%'    | 'IO'       | 'CAP CHIP 22U 6.3V(+-20%.X5R.0805)SELASS'                      | 'CHIP0805'     | ''          | ''   | '20111229'
 '0.033UF'  | '16V'   | '10%'     | 'C0402'     | 'X7R'     | 'CH3333K1B02'(!)   = 'End of Design' | 'Comp-Release Qty' | ''       | 'CH3333K1B02'     |'C0402'| '(C0402-0201)'                                                       | '0.033UF'  | '16V'         | '10%'    | 'DISCRETE' | 'CAP CHIP 0.033U 16V(+-10%.X7R.0402)'                          | 'CHIP0402'     | ''          | ''   | '20111230'
 '0.033UF'  | '16V'   | '10%'     | 'C0402'     | 'EMPTY'   | 'CH3333K1B02'(!)   = 'End of Design' | 'Comp-Release Qty' | ''       | 'CH3333K1B02'     |'C0402'| '(C0402-0201)'                                                       | 'NA'       | '16V'         | '10%'    | 'IO'       | 'CAP CHIP 0.033U 16V(+-10%.X7R.0402)'                          | 'CHIP0402'     | ''          | ''   | '20111230'
 '470PF'    | '50V'   | '5%'      | 'C0402'     | 'NPO'     | 'CH1476J0B08'(!)   = ''              | ''                 | ''       | 'CH1476J0B08'     |'C0402'| '(C0402-0201)'                                                       | '470PF'    | '50V'         | '5%'     | 'DISCRETE' | 'CAP CHIP 470P,50V(+-5%,NPO,0402)'                             | 'CHIP0402'     | ''          | ''   | '20120113'
 '470PF'    | '50V'   | '5%'      | 'C0402'     | 'EMPTY'   | 'CH1476J0B08'(!)   = ''              | ''                 | ''       | 'CH1476J0B08'     |'C0402'| '(C0402-0201)'                                                       | 'NA'       | '50V'         | '5%'     | 'IO'       | 'CAP CHIP 470P,50V(+-5%,NPO,0402)'                             | 'CHIP0402'     | ''          | ''   | '20120113'
 '6800PF'   | '50V'   | '10%'     | 'C0402'     | 'X7R'     | 'CH2686K1B01'(!)   = ''              | ''                 | ''       | 'CH2686K1B01'     |'C0402'| '(C0402-0201)'                                                       | '6800PF'   | '50V'         | '10%'    | 'DISCRETE' | 'CAP CHIP 6800P 50V(+-10%,X7R,0402)'                           | 'CHIP0402'     | ''          | ''   | '20120113'
 '6800PF'   | '50V'   | '10%'     | 'C0402'     | 'EMPTY'   | 'CH2686K1B01'(!)   = ''              | ''                 | ''       | 'CH2686K1B01'     |'C0402'| '(C0402-0201)'                                                       | 'NA'       | '50V'         | '10%'    | 'IO'       | 'CAP CHIP 6800P 50V(+-10%,X7R,0402)'                           | 'CHIP0402'     | ''          | ''   | '20120113'
 '0.047UF'  | '16V'   | '10%'     | 'C0402'     | 'X7R'     | 'CH3473K1B00'(!)   = ''              | ''                 | ''       | 'CH3473K1B00'     |'C0402'| '(C0402-0201)'                                                       | '0.047UF'  | '16V'         | '10%'    | 'DISCRETE' | 'CAP CHIP 0.047U 16V(+-10%,X7R,0402)'                          | 'CHIP0402'     | ''          | ''   | '20120113'
 '0.047UF'  | '16V'   | '10%'     | 'C0402'     | 'EMPTY'   | 'CH3473K1B00'(!)   = ''              | ''                 | ''       | 'CH3473K1B00'     |'C0402'| '(C0402-0201)'                                                       | 'NA'       | '16V'         | '10%'    | 'IO'       | 'CAP CHIP 0.047U 16V(+-10%,X7R,0402)'                          | 'CHIP0402'     | ''          | ''   | '20120113'
 '0.068UF'  | '25V'   | '10%'     | 'C0603'     | 'X7R'     | 'CH3684K1904'(!)   = 'End of Design' | 'Comp-Approve'     | ''       | 'CH3684K1904'     |'C0603'| '(SMC0603AW)'                                                        | '0.068UF'  | '25V'         | '10%'    | 'DISCRETE' | 'CAP CHIP 0.068UF 25V(10%,X7R,0603)'                           | 'CHIP0603'     | ''          | ''   | '20120113'
 '0.068UF'  | '25V'   | '10%'     | 'C0603'     | 'EMPTY'   | 'CH3684K1904'(!)   = 'End of Design' | 'Comp-Approve'     | ''       | 'CH3684K1904'     |'C0603'| '(SMC0603AW)'                                                        | 'NA'       | '25V'         | '10%'    | 'IO'       | 'CAP CHIP 0.068UF 25V(10%,X7R,0603)'                           | 'CHIP0603'     | ''          | ''   | '20120113'
 '0.1UF'    | '100V'  | '10%'     | 'C0805'     | 'X7R'     | 'CH4108K1A00'(!)   = 'End of Design' | 'Comp-Approve'     | ''       | 'CH4108K1A00'     |'C0805_H61'| '(SMC0805AW)'                                                        | '0.1UF'    | '100V'        | '10%'    | 'DISCRETE' | 'CAP CHIP 0.1UF 100V(+-10%,X7R,0805)H1.25'                     | 'CHIP0805'     | ''          | ''   | '20120114'
 '0.1UF'    | '100V'  | '10%'     | 'C0805'     | 'EMPTY'   | 'CH4108K1A00'(!)   = 'End of Design' | 'Comp-Approve'     | ''       | 'CH4108K1A00'     |'C0805_H61'| '(SMC0805AW)'                                                        | 'NA'       | '100V'        | '10%'    | 'IO'       | 'CAP CHIP 0.1UF 100V(+-10%,X7R,0805)H1.25'                     | 'CHIP0805'     | ''          | ''   | '20120114'
 '4.7UF'    | '16V'   | '10%'     | 'C0805'     | 'X7R'     | 'CH5473K1A00'(!)   = 'End of Design' | 'Comp-Approve'     | ''       | 'CH5473K1A00'     |'C0805_H61'| '(SMC0805AW)'                                                        | '4.7UF'    | '16V'         | '10%'    | 'DISCRETE' | 'CAP CHIP 4.7UF 16V(+-10%,X7R,0805,H1.25)'                     | 'CHIP0805'     | ''          | ''   | '20120114'
 '4.7UF'    | '16V'   | '10%'     | 'C0805'     | 'EMPTY'   | 'CH5473K1A00'(!)   = 'End of Design' | 'Comp-Approve'     | ''       | 'CH5473K1A00'     |'C0805_H61'| '(SMC0805AW)'                                                        | 'NA'       | '16V'         | '10%'    | 'IO'       | 'CAP CHIP 4.7UF 16V(+-10%,X7R,0805,H1.25)'                     | 'CHIP0805'     | ''          | ''   | '20120114'
 '0.22UF'   | '25V'   | '10%'     | 'C0603'     | 'X5R'     | 'CH4224K9904'(!)   = ''              | ''                 | ''       | 'CH4224K9904'     |'C0603'| '(SMC0603AW)'                                                        | '0.22UF'   | '25V'         | '10%'    | 'DISCRETE' | 'CAP CHIP 0.22U 25V(10%.X5R.0603)'                             | 'CHIP0603'     | ''          | ''   | '20120114'
 '0.22UF'   | '25V'   | '10%'     | 'C0603'     | 'EMPTY'   | 'CH4224K9904'(!)   = ''              | ''                 | ''       | 'CH4224K9904'     |'C0603'| '(SMC0603AW)'                                                        | 'NA'       | '25V'         | '10%'    | 'IO'       | 'CAP CHIP 0.22U 25V(10%.X5R.0603)'                             | 'CHIP0603'     | ''          | ''   | '20120114'
 '2200PF'   | '2KV'   | '10%'     | 'C1812'     | 'X7R'     | 'CH222IK1400'(!)   = ''              | ''                 | ''       | 'CH222IK1400'     |'C1812_H63'| '(SMC1812AW)'                                                        | '2200PF'   | '2KV'         | '10%'    | 'DISCRETE' | 'CAP CHIP 2200PF 2KV(+-10%.X7R.1812)H1.3'                      | 'CHIP1812'     | ''          | ''   | '20120116'
 '2200PF'   | '2KV'   | '10%'     | 'C1812'     | 'EMPTY'   | 'CH222IK1400'(!)   = ''              | ''                 | ''       | 'CH222IK1400'     |'C1812_H63'| '(SMC1812AW)'                                                        | 'NA'       | '2KV'         | '10%'    | 'IO'       | 'CAP CHIP 2200PF 2KV(+-10%.X7R.1812)H1.3'                      | 'CHIP1812'     | ''          | ''   | '20120116'
 '1UF'      | '100V'  | '10%'     | 'C1206'     | 'X7R'     | 'CH5108K1202'(!)   = 'End of Design' | 'Comp-Approve'     | ''       | 'CH5108K1202'     |'C1206_H66'| '(SMC1206AW)'                                                        | '1UF'      | '100V'        | '10%'    | 'DISCRETE' | 'CAP CHIP 1U 100V(10%.1206.X7R)'                               | 'CHIP1206'     | ''          | ''   | '20120116'
 '1UF'      | '100V'  | '10%'     | 'C1206'     | 'EMPTY'   | 'CH5108K1202'(!)   = 'End of Design' | 'Comp-Approve'     | ''       | 'CH5108K1202'     |'C1206_H66'| '(SMC1206AW)'                                                        | 'NA'       | '100V'        | '10%'    | 'IO'       | 'CAP CHIP 1U 100V(10%.1206.X7R)'                               | 'CHIP1206'     | ''          | ''   | '20120116'
 '0.15UF'   | '10V'   | '10%'     | 'C0603'     | 'X7R'     | 'CH41502K909'(!)   = ''              | ''                 | ''       | 'CH41502K909'     |'C0603'| '(SMC0603AW)'                                                        | '0.15UF'   | '10V'         | '10%'    | 'DISCRETE' | 'CAP CHIP 0.15U 10V(+-10%.X7R.0603)'                           | 'CHIP0603'     | ''          | ''   | '20120119'
 '0.15UF'   | '10V'   | '10%'     | 'C0603'     | 'EMPTY'   | 'CH41502K909'(!)   = ''              | ''                 | ''       | 'CH41502K909'     |'C0603'| '(SMC0603AW)'                                                        | 'NA'       | '10V'         | '10%'    | 'IO'       | 'CAP CHIP 0.15U 10V(+-10%.X7R.0603)'                           | 'CHIP0603'     | ''          | ''   | '20120119'
 '33PF'     | '16V'   | '5%'      | 'C0402'     | 'NP0'     | 'CH0333J0B00'(!)   = 'End of Design' | 'Comp-Approve'     | ''       | 'CH0333J0B00'     |'C0402'| '(C0402-0201)'                                                       | '33PF'     | '16V'         | '5%'     | 'DISCRETE' | 'CAP CHIP 33P 16V(+-5%,NP0,0402)'                              | 'CHIP0402'     | ''          | ''   | '20120120'
 '33PF'     | '16V'   | '5%'      | 'C0402'     | 'EMPTY'   | 'CH0333J0B00'(!)   = 'End of Design' | 'Comp-Approve'     | ''       | 'CH0333J0B00'     |'C0402'| '(C0402-0201)'                                                       | 'NA'       | '16V'         | '5%'     | 'IO'       | 'CAP CHIP 33P 16V(+-5%,NP0,0402)'                              | 'CHIP0402'     | ''          | ''   | '20120120'
 '1500PF'   | '100V'  | '10%'     | 'C0402'     | 'X7R'     | 'CH2158K1B00'(!)   = 'End of Design' | 'Comp-Approve'     | ''       | 'CH2158K1B00'     |'C0402'| '(C0402-0201)'                                                       | '1500PF'   | '100V'        | '10%'    | 'DISCRETE' | 'CAP CHIP 1500P 100V(+-10%.X7R.0402)'                          | 'CHIP0402'     | ''          | ''   | '20120120'
 '1500PF'   | '100V'  | '10%'     | 'C0402'     | 'EMPTY'   | 'CH2158K1B00'(!)   = 'End of Design' | 'Comp-Approve'     | ''       | 'CH2158K1B00'     |'C0402'| '(C0402-0201)'                                                       | 'NA'       | '100V'        | '10%'    | 'IO'       | 'CAP CHIP 1500P 100V(+-10%.X7R.0402)'                          | 'CHIP0402'     | ''          | ''   | '20120120'
 '390PF'    | '50V'   | '5%'      | 'C0402'     | 'C0G'     | 'CH1396J0B02'(!)   = ''              | ''                 | ''       | 'CH1396J0B02'     |'C0402'| '(C0402-0201)'                                                       | '390PF'    | '50V'         | '5%'     | 'DISCRETE' | 'CAP CHIP 390P 50V (+-5%,C0G,0402)'                            | 'CHIP0402'     | ''          | ''   | '20120120'
 '390PF'    | '50V'   | '5%'      | 'C0402'     | 'EMPTY'   | 'CH1396J0B02'(!)   = ''              | ''                 | ''       | 'CH1396J0B02'     |'C0402'| '(C0402-0201)'                                                       | 'NA'       | '50V'         | '5%'     | 'IO'       | 'CAP CHIP 390P 50V (+-5%,C0G,0402)'                            | 'CHIP0402'     | ''          | ''   | '20120120'
 '22UF'     | '4V'    | '20%'     | 'C0603'     | 'X5R'     | 'CH622KM9900'(!)   = 'End of Design' | 'Comp-Approve'     | ''       | 'CH622KM9900'     |'C0603'| '(SMC0603AW)'                                                        | '22UF'     | '4V'          | '20%'    | 'DISCRETE' | 'CAP CHIP 22UF 4V(+-20%,X5R,0603)H0.8'                         | 'CHIP0603'     | ''          | ''   | '20120202'
 '22UF'     | '4V'    | '20%'     | 'C0603'     | 'EMPTY'   | 'CH622KM9900'(!)   = 'End of Design' | 'Comp-Approve'     | ''       | 'CH622KM9900'     |'C0603'| '(SMC0603AW)'                                                        | 'NA'       | '4V'          | '20%'    | 'IO'       | 'CAP CHIP 22UF 4V(+-20%,X5R,0603)H0.8'                         | 'CHIP0603'     | ''          | ''   | '20120202'
 '82PF'     | '50V'   | '1%'      | 'C0402'     | 'C0G'     | 'CH0826F0B00'(!)   = ''              | ''                 | 'SELASS' | 'CH0826F0B00'     |'C0402'| '(C0402-0201)'                                                       | '82PF'     | '50V'         | '1%'     | 'DISCRETE' | 'CAP CHIP 82PF 50V(+-1%.C0G.0402)SELASS'                       | 'CHIP0402'     | ''          | ''   | '20120207'
 '82PF'     | '50V'   | '1%'      | 'C0402'     | 'EMPTY'   | 'CH0826F0B00'(!)   = ''              | ''                 | 'SELASS' | 'CH0826F0B00'     |'C0402'| '(C0402-0201)'                                                       | 'NA'       | '50V'         | '1%'     | 'IO'       | 'CAP CHIP 82PF 50V(+-1%.C0G.0402)SELASS'                       | 'CHIP0402'     | ''          | ''   | '20120207'
 '0.01UF'   | '50V'   | '10%'     | 'C0402'     | 'X7R'     | 'CH31006KB18'(!)   = ''              | ''                 | ''       | 'CH31006KB18'     |'C0402'| '(C0402_OCTAGONXA,C0402-0201)'                                       | '0.01UF'   | '50V'         | '10%'    | 'DISCRETE' | 'CAP CHIP 0.01U 50V(+-10%,X7R,0402)'                           | 'CHIP0402'     | ''          | ''   | '20120326'
 '0.01UF'   | '50V'   | '10%'     | 'C0402'     | 'EMPTY'   | 'CH31006KB18'(!)   = ''              | ''                 | ''       | 'CH31006KB18'     |'C0402'| '(C0402_OCTAGONXA,C0402-0201)'                                       | 'NA'       | '50V'         | '10%'    | 'IO'       | 'CAP CHIP 0.01U 50V(+-10%,X7R,0402)'                           | 'CHIP0402'     | ''          | ''   | '20120326'
 '120PF'    | '50V'   | '5%'      | 'C0402'     | 'NPO'     | 'CH11206JB07'(!)   = ''              | ''                 | ''       | 'CH11206JB07'     |'C0402'| '(C0402-0201)'                                                       | '120PF'    | '50V'         | '10%'    | 'DISCRETE' | 'CAP CHIP 120P 50V(+-5%,NPO,0402)'                             | 'CHIP0402'     | ''          | ''   | '20120326'
 '120PF'    | '50V'   | '5%'      | 'C0402'     | 'EMPTY'   | 'CH11206JB07'(!)   = ''              | ''                 | ''       | 'CH11206JB07'     |'C0402'| '(C0402-0201)'                                                       | 'NA'       | '50V'         | '10%'    | 'IO'       | 'CAP CHIP 120P 50V(+-5%,NPO,0402)'                             | 'CHIP0402'     | ''          | ''   | '20120326'
 '1000PF'   | '2KV'   | '10%'     | 'THLF'      | 'CERAMIC' | 'CG2100FKD00'(!)   = ''              | ''                 | ''       | 'CG2100FKD00'     |'EC315_P197_V'| '(EC315_P197_V)'                                                     | '1000PF'   | '2KV'         | '10%'    | 'DISCRETE' | 'CAP CERAMIC 1000P 2KV(+-10%,P5,DIP)'                          | 'DIP'          | ''          | ''   | '20120405'
 '1000PF'   | '2KV'   | '10%'     | 'THLF'      | 'EMPTY'   | 'CG2100FKD00'(!)   = ''              | ''                 | ''       | 'CG2100FKD00'     |'EC315_P197_V'| '(EC315_P197_V)'                                                     | 'NA'       | '2KV'         | '10%'    | 'IO'       | 'CAP CERAMIC 1000P 2KV(+-10%,P5,DIP)'                          | 'DIP'          | ''          | ''   | '20120405'
 '1000PF'   | '50V'   | '10%'     | 'C0603'     | 'NPO'     | 'CH21006K909'(!)   = 'End of Design' | 'Comp-Approve'     | ''       | 'CH21006K909'     |'C0603'| '(SMC0603AW)'                                                        | '1000PF'   | '50V'         | '10%'    | 'DISCRETE' | 'CAP CHIP 1000P 50V(+-10%,NPO,0603)'                           | 'CHIP0603'     | ''          | ''   | '20120406'
 '1000PF'   | '50V'   | '10%'     | 'C0603'     | 'EMPTY'   | 'CH21006K909'(!)   = 'End of Design' | 'Comp-Approve'     | ''       | 'CH21006K909'     |'C0603'| '(SMC0603AW)'                                                        | 'NA'       | '50V'         | '10%'    | 'IO'       | 'CAP CHIP 1000P 50V(+-10%,NPO,0603)'                           | 'CHIP0603'     | ''          | ''   | '20120406'
 '0.022UF'  | '50V'   | '10%'     | 'C0603'     | 'X7R'     | 'CH3226K1901'(!)   = 'End of Design' | 'Comp-Approve'     | ''       | 'CH3226K1901'     |'C0603'| '(SMC0603AW)'                                                        | '0.022UF'  | '50V'         | '10%'    | 'DISCRETE' | 'CAP CHIP 0.022U 50V(+-10%.X7R.0603)L-F'                       | 'CHIP0603'     | ''          | ''   | '20120416'
 '0.022UF'  | '50V'   | '10%'     | 'C0603'     | 'EMPTY'   | 'CH3226K1901'(!)   = 'End of Design' | 'Comp-Approve'     | ''       | 'CH3226K1901'     |'C0603'| '(SMC0603AW)'                                                        | 'NA'       | '50V'         | '10%'    | 'IO'       | 'CAP CHIP 0.022U 50V(+-10%.X7R.0603)L-F'                       | 'CHIP0603'     | ''          | ''   | '20120416'
 '10UF'     | '25V'   | '10%'     | 'C1206'     | 'X6S'     | 'CH6104KE201'(!)   = 'End of Design' | 'Comp-Approve'     | ''       | 'CH6104KE201'     |'C1206_H76'| '(SMC1206AW)'                                                        | '10UF'     | '25V'         | '10%'    | 'DISCRETE' | 'CAP CHIP 10U 25V(+-10%.X6S.1206)'                             | 'CHIP1206'     | ''          | ''   | '20120419'
 '10UF'     | '25V'   | '10%'     | 'C1206'     | 'EMPTY'   | 'CH6104KE201'(!)   = 'End of Design' | 'Comp-Approve'     | ''       | 'CH6104KE201'     |'C1206_H76'| '(SMC1206AW)'                                                        | 'NA'       | '25V'         | '10%'    | 'IO'       | 'CAP CHIP 10U 25V(+-10%.X6S.1206)'                             | 'CHIP1206'     | ''          | ''   | '20120419'
 '22UF'     | '2.5V'  | '20%'     | 'C0805'     | 'X6S'     | 'CH622LMEA00'(!)   = 'End of Design' | 'Comp-Approve'     | ''       | 'CH622LMEA00'     |'C0805_H36'| '(SMC0805AW)'                                                        | '22UF'     | '2.5V'        | '20%'    | 'DISCRETE' | 'CAP CHIP 22UF 2.5V(20%,X6S,0805,H0.85)'                       | 'CHIP0805'     | ''          | ''   | '20120420'
 '22UF'     | '2.5V'  | '20%'     | 'C0805'     | 'EMPTY'   | 'CH622LMEA00'(!)   = 'End of Design' | 'Comp-Approve'     | ''       | 'CH622LMEA00'     |'C0805_H36'| '(SMC0805AW)'                                                        | 'NA'       | '2.5V'        | '20%'    | 'IO'       | 'CAP CHIP 22UF 2.5V(20%,X6S,0805,H0.85)'                       | 'CHIP0805'     | ''          | ''   | '20120420'
 '22UF'     | '6.3V'  | '20%'     | 'C0805'     | 'X5R'     | 'CH6221M9A00'(!)   = 'End of Design' | 'Comp-Approve'     | ''       | 'CH6221M9A00'     |'C0805_H61'| '(SMC0805AW)'                                                        | '22UF'     | '6.3V'        | '20%'    | 'DISCRETE' | 'CAP CHIP 22U 6.3V(+-20%,X5R,0805)H1.25'                       | 'CHIP0805'     | ''          | ''   | '20120420'
 '22UF'     | '6.3V'  | '20%'     | 'C0805'     | 'EMPTY'   | 'CH6221M9A00'(!)   = 'End of Design' | 'Comp-Approve'     | ''       | 'CH6221M9A00'     |'C0805_H61'| '(SMC0805AW)'                                                        | 'NA'       | '6.3V'        | '20%'    | 'IO'       | 'CAP CHIP 22U 6.3V(+-20%,X5R,0805)H1.25'                       | 'CHIP0805'     | ''          | ''   | '20120420'
 '0.039UF'  | '16V'   | '10%'     | 'C0603'     | 'X7R'     | 'CH33903K911'(!)   = ''              | ''                 | ''       | 'CH33903K911'     |'C0603'| '(SMC0603AW)'                                                        | '0.039UF'  | '16V'         | '10%'    | 'DISCRETE' | 'CAP CHIP 0.039U 16V(+-10%.X7R.0603)'                          | 'CHIP0603'     | ''          | ''   | '20120423'
 '0.039UF'  | '16V'   | '10%'     | 'C0603'     | 'EMPTY'   | 'CH33903K911'(!)   = ''              | ''                 | ''       | 'CH33903K911'     |'C0603'| '(SMC0603AW)'                                                        | 'NA'       | '16V'         | '10%'    | 'IO'       | 'CAP CHIP 0.039U 16V(+-10%.X7R.0603)'                          | 'CHIP0603'     | ''          | ''   | '20120423'
 '0.056UF'  | '16V'   | '10%'     | 'C0402'     | 'X7R'     | 'CH3563K1B00'(!)   = ''              | ''                 | ''       | 'CH3563K1B00'     |'C0402'| '(C0402-0201)'                                                       | '0.056UF'  | '16V'         | '10%'    | 'DISCRETE' | 'CAP CHIP 0.056U 16V(+-10%,X7R,0402)'                          | 'CHIP0402'     | ''          | ''   | '20120424'
 '0.056UF'  | '16V'   | '10%'     | 'C0402'     | 'EMPTY'   | 'CH3563K1B00'(!)   = ''              | ''                 | ''       | 'CH3563K1B00'     |'C0402'| '(C0402-0201)'                                                       | 'NA'       | '16V'         | '10%'    | 'IO'       | 'CAP CHIP 0.056U 16V(+-10%,X7R,0402)'                          | 'CHIP0402'     | ''          | ''   | '20120424'
 '100UF'    | '4V'    | '20%'     | 'C0805'     | 'X5R'     | 'CH710KM9A00'(!)   = 'End of Design' | 'Comp-Approve'     | ''       | 'CH710KM9A00'     |'C0805_H61'| '(SMC0805AW)'                                                        | '100UF'    | '4V'          | '20%'    | 'DISCRETE' | 'CAP CHIP 100U 4V(+-20%,X5R,0805)H1.25'                        | 'CHIP0805'     | ''          | ''   | '20120509'
 '100UF'    | '4V'    | '20%'     | 'C0805'     | 'EMPTY'   | 'CH710KM9A00'(!)   = 'End of Design' | 'Comp-Approve'     | ''       | 'CH710KM9A00'     |'C0805_H61'| '(SMC0805AW)'                                                        | 'NA'       | '4V'          | '20%'    | 'IO'       | 'CAP CHIP 100U 4V(+-20%,X5R,0805)H1.25'                        | 'CHIP0805'     | ''          | ''   | '20120509'
 '10UF'     | '6.3V'  | '20%'     | 'C0402'     | 'X5R'     | 'CH6101M9B02'(!)   = ''              | ''                 | ''       | 'CH6101M9B02'     |'C0402'| '(C0402-0201)'                                                       | '10UF'     | '6.3V'        | '20%'    | 'DISCRETE' | 'CAP CHIP 10U 6.3V(+-20%,X5R,0402)'                            | 'CHIP0402'     | ''          | ''   | '20120521'
 '10UF'     | '6.3V'  | '20%'     | 'C0402'     | 'EMPTY'   | 'CH6101M9B02'(!)   = ''              | ''                 | ''       | 'CH6101M9B02'     |'C0402'| '(C0402-0201)'                                                       | 'NA'       | '6.3V'        | '20%'    | 'IO'       | 'CAP CHIP 10U 6.3V(+-20%,X5R,0402)'                            | 'CHIP0402'     | ''          | ''   | '20120521'
 '0.1UF'    | '6.3V'  | '10%'     | 'C0201'     | 'X5R'     | 'CH4101K9E01'(!)   = ''              | ''                 | ''       | 'CH4101K9E01'     |'C0201'| '(SMC0201AW)'                                                        | '0.1UF'    | '6.3V'        | '10%'    | 'DISCRETE' | 'CAP CHIP 0.1UF 6.3V(+-10%,X5R,0201)'                          | 'CHIP0201'     | ''          | ''   | '20120528'
 '0.1UF'    | '6.3V'  | '10%'     | 'C0201'     | 'EMPTY'   | 'CH4101K9E01'(!)   = ''              | ''                 | ''       | 'CH4101K9E01'     |'C0201'| '(SMC0201AW)'                                                        | 'NA'       | '6.3V'        | '10%'    | 'IO'       | 'CAP CHIP 0.1UF 6.3V(+-10%,X5R,0201)'                          | 'CHIP0201'     | ''          | ''   | '20120528'
 '1000PF'   | '16V'   | '10%'     | 'C0201'     | 'X7R'     | 'CH2103K1E14'(!)   = ''              | ''                 | ''       | 'CH2103K1E14'     |'C0201'| '(SMC0201AW)'                                                        | '1000PF'   | '16V'         | '10%'    | 'DISCRETE' | 'CAP CHIP 1000P 16V(10%,X7R,0201)'                             | 'CHIP0201'     | ''          | ''   | '20120528'
 '1000PF'   | '16V'   | '10%'     | 'C0201'     | 'EMPTY'   | 'CH2103K1E14'(!)   = ''              | ''                 | ''       | 'CH2103K1E14'     |'C0201'| '(SMC0201AW)'                                                        | 'NA'       | '16V'         | '10%'    | 'IO'       | 'CAP CHIP 1000P 16V(10%,X7R,0201)'                             | 'CHIP0201'     | ''          | ''   | '20120528'
 '0.22UF'   | '6.3V'  | '20%'     | 'C0201'     | 'X5R'     | 'CH4221M9E00'(!)   = 'End of Design' | 'Comp-Release Qty' | ''       | 'CH4221M9E00'     |'C0201'| '(SMC0201AW)'                                                        | '0.22UF'   | '6.3V'        | '20%'    | 'DISCRETE' | 'CAP CHIP 0.22UF 6.3V(20%,X5R,0201)'                           | 'CHIP0201'     | ''          | ''   | '20120528'
 '0.22UF'   | '6.3V'  | '20%'     | 'C0201'     | 'EMPTY'   | 'CH4221M9E00'(!)   = 'End of Design' | 'Comp-Release Qty' | ''       | 'CH4221M9E00'     |'C0201'| '(SMC0201AW)'                                                        | 'NA'       | '6.3V'        | '20%'    | 'IO'       | 'CAP CHIP 0.22UF 6.3V(20%,X5R,0201)'                           | 'CHIP0201'     | ''          | ''   | '20120528'
 '4.7UF'    | '6.3V'  | '20%'     | 'C0402'     | 'X5R'     | 'CH5471M9B00'(!)   = 'End of Design' | 'Comp-Release Qty' | ''       | 'CH5471M9B00'     |'C0402'| '(C0402-0201)'                                                       | '4.7UF'    | '6.3V'        | '20%'    | 'DISCRETE' | 'CAP CHIP 4.7U 6.3V(+-20%.X5R.0402)'                           | 'CHIP0402'     | ''          | ''   | '20120528'
 '4.7UF'    | '6.3V'  | '20%'     | 'C0402'     | 'EMPTY'   | 'CH5471M9B00'(!)   = 'End of Design' | 'Comp-Release Qty' | ''       | 'CH5471M9B00'     |'C0402'| '(C0402-0201)'                                                       | 'NA'       | '6.3V'        | '20%'    | 'IO'       | 'CAP CHIP 4.7U 6.3V(+-20%.X5R.0402)'                           | 'CHIP0402'     | ''          | ''   | '20120528'
 '22UF'     | '6.3V'  | '20%'     | 'C0603'     | 'X5R'     | 'CH6221M9900'(!)   = ''              | ''                 | ''       | 'CH6221M9900'     |'C0603'| '(SMC0603AW)'                                                        | '22UF'     | '6.3V'        | '20%'    | 'DISCRETE' | 'CAP CHIP 22U 6.3V(+-20%,X5R,0603)HF'                          | 'CHIP0603'     | ''          | ''   | '20120528'
 '22UF'     | '6.3V'  | '20%'     | 'C0603'     | 'EMPTY'   | 'CH6221M9900'(!)   = ''              | ''                 | ''       | 'CH6221M9900'     |'C0603'| '(SMC0603AW)'                                                        | 'NA'       | '6.3V'        | '20%'    | 'IO'       | 'CAP CHIP 22U 6.3V(+-20%,X5R,0603)HF'                          | 'CHIP0603'     | ''          | ''   | '20120528'
 '1UF'      | '6.3V'  | '20%'     | 'C0201'     | 'X5R'     | 'CH5101M9E02'(!)   = ''              | ''                 | ''       | 'CH5101M9E02'     |'C0201'| '(SMC0201AW)'                                                        | '1UF'      | '6.3V'        | '20%'    | 'DISCRETE' | 'CAP CHIP 1UF 6.3V(+-20%,X5R,0201)'                            | 'CHIP0201'     | ''          | ''   | '20120528'
 '1UF'      | '6.3V'  | '20%'     | 'C0201'     | 'EMPTY'   | 'CH5101M9E02'(!)   = ''              | ''                 | ''       | 'CH5101M9E02'     |'C0201'| '(SMC0201AW)'                                                        | 'NA'       | '6.3V'        | '20%'    | 'IO'       | 'CAP CHIP 1UF 6.3V(+-20%,X5R,0201)'                            | 'CHIP0201'     | ''          | ''   | '20120528'
 '5.6PF'    | '25V'   | '0.25PF'  | 'C0201'     | 'C0G'     | 'CH-564C0E00'(!)   = ''              | ''                 | ''       | 'CH-564C0E00'     |'C0201'| '(SMC0201AW)'                                                        | '5.6PF'    | '25V'         | '0.25PF' | 'DISCRETE' | 'CAP 5.6PF 25V(0.25PF,C0G,0201,HQ,ESR250)'                     | 'CHIP0201'     | ''          | ''   | '20120601'
 '5.6PF'    | '25V'   | '0.25PF'  | 'C0201'     | 'EMPTY'   | 'CH-564C0E00'(!)   = ''              | ''                 | ''       | 'CH-564C0E00'     |'C0201'| '(SMC0201AW)'                                                        | 'NA'       | '25V'         | '0.25PF' | 'IO'       | 'CAP 5.6PF 25V(0.25PF,C0G,0201,HQ,ESR250)'                     | 'CHIP0201'     | ''          | ''   | '20120601'
 '22UF'     | '6.3V'  | '20%'     | 'C0805'     | 'X5R'     | 'CH6221M9A01'(!)   = 'End of Design' | 'End of Life'      | ''       | 'CH6221M9A01'     |'C0805_H61_EOL'| '(SMC0805AW)'                                                        | '22UF'     | '6.3V'        | '20%'    | 'DISCRETE' | 'CAP CHIP 22U 6.3V(+-20%.X5R.0805)H1.25'                       | 'CHIP0805'     | ''          | ''   | '20120604'
 '22UF'     | '6.3V'  | '20%'     | 'C0805'     | 'EMPTY'   | 'CH6221M9A01'(!)   = 'End of Design' | 'End of Life'      | ''       | 'CH6221M9A01'     |'C0805_H61_EOL'| '(SMC0805AW)'                                                        | 'NA'       | '6.3V'        | '20%'    | 'IO'       | 'CAP CHIP 22U 6.3V(+-20%.X5R.0805)H1.25'                       | 'CHIP0805'     | ''          | ''   | '20120604'
 '4.7UF'    | '10V'   | '20%'     | 'C0603'     | 'X5R'     | 'CH5472M9901'(!)   = 'End of Design' | 'Comp-Approve'     | ''       | 'CH5472M9901'     |'C0603'| '(SMC0603AW)'                                                        | '4.7UF'    | '10V'         | '20%'    | 'DISCRETE' | 'CAP CHIP 4.7U,10V(+-20%,X5R,0603)'                            | 'CHIP0603'     | ''          | ''   | '20120604'
 '4.7UF'    | '10V'   | '20%'     | 'C0603'     | 'EMPTY'   | 'CH5472M9901'(!)   = 'End of Design' | 'Comp-Approve'     | ''       | 'CH5472M9901'     |'C0603'| '(SMC0603AW)'                                                        | 'NA'       | '10V'         | '20%'    | 'IO'       | 'CAP CHIP 4.7U,10V(+-20%,X5R,0603)'                            | 'CHIP0603'     | ''          | ''   | '20120604'
 '0.033UF'  | '50V'   | '10%'     | 'C0603'     | 'X7R'     | 'CH33306K915'(!)   = 'End of Design' | 'Comp-Approve'     | ''       | 'CH33306K915'     |'C0603'| '(SMC0603AW)'                                                        | '0.033UF'  | '50V'         | '10%'    | 'DISCRETE' | 'CAP CHIP 0.033U 50V(+-10%,X7R,0603)'                          | 'CHIP0603'     | ''          | ''   | '20120727'
 '0.033UF'  | '50V'   | '10%'     | 'C0603'     | 'EMPTY'   | 'CH33306K915'(!)   = 'End of Design' | 'Comp-Approve'     | ''       | 'CH33306K915'     |'C0603'| '(SMC0603AW)'                                                        | 'NA'       | '50V'         | '10%'    | 'IO'       | 'CAP CHIP 0.033U 50V(+-10%,X7R,0603)'                          | 'CHIP0603'     | ''          | ''   | '20120727'
 '4.7UF'    | '25V'   | '20%'     | 'C1206'     | 'X7R'     | 'CH5474M1200'(!)   = 'End of Design' | 'Comp-Approve'     | ''       | 'CH5474M1200'     |'C1206_H66'| '(SMC1206AW)'                                                        | '4.7UF'    | '25V'         | '20%'    | 'DISCRETE' | 'CAP CHIP 4.7U 25V(+-20%,X7R,1206)H1.6'                        | 'CHIP1206'     | ''          | ''   | '20120814'
 '4.7UF'    | '25V'   | '20%'     | 'C1206'     | 'EMPTY'   | 'CH5474M1200'(!)   = 'End of Design' | 'Comp-Approve'     | ''       | 'CH5474M1200'     |'C1206_H66'| '(SMC1206AW)'                                                        | 'NA'       | '25V'         | '20%'    | 'IO'       | 'CAP CHIP 4.7U 25V(+-20%,X7R,1206)H1.6'                        | 'CHIP1206'     | ''          | ''   | '20120814'
 '0.01UF'   | '250V'  | '10%'     | 'C0805'     | 'X7R'     | 'CH3100CKA14'(!)   = ''              | ''                 | ''       | 'CH3100CKA14'     |'C0805_H61'| '(SMC0805AW)'                                                        | '0.01UF'   | '250V'        | '10%'    | 'DISCRETE' | 'CAP CHIP 0.01U 250V(+-10%.X7R.0805)'                          | 'CHIP0805'     | ''          | ''   | '20120905'
 '0.01UF'   | '250V'  | '10%'     | 'C0805'     | 'EMPTY'   | 'CH3100CKA14'(!)   = ''              | ''                 | ''       | 'CH3100CKA14'     |'C0805_H61'| '(SMC0805AW)'                                                        | 'NA'       | '250V'        | '10%'    | 'IO'       | 'CAP CHIP 0.01U 250V(+-10%.X7R.0805)'                          | 'CHIP0805'     | ''          | ''   | '20120905'
 '0.33UF'   | '6.3V'  | '10%'     | 'C0402'     | 'X5R'     | 'CH4331K9B06'(!)   = 'End of Design' | 'Comp-Approve'     | ''       | 'CH4331K9B06'     |'C0402'| '(C0402-0201)'                                                       | '0.33UF'   | '6.3V'        | '10%'    | 'DISCRETE' | 'CAP CHIP 0.33U 6.3V(10%.X5R.0402)'                            | 'CHIP0402'     | ''          | ''   | '20120906'
 '0.33UF'   | '6.3V'  | '10%'     | 'C0402'     | 'EMPTY'   | 'CH4331K9B06'(!)   = 'End of Design' | 'Comp-Approve'     | ''       | 'CH4331K9B06'     |'C0402'| '(C0402-0201)'                                                       | 'NA'       | '6.3V'        | '10%'    | 'IO'       | 'CAP CHIP 0.33U 6.3V(10%.X5R.0402)'                            | 'CHIP0402'     | ''          | ''   | '20120906'
 '39NF'     | '16V'   | '10%'     | 'C0402'     | 'X7R'     | 'CH3393K1B00'(!)   = ''              | ''                 | ''       | 'CH3393K1B00'     |'C0402'| '(C0402-0201)'                                                       | '39NF'     | '16V'         | '10%'    | 'DISCRETE' | 'CAP CHIP 39NF 16V(+-10%,X7R,0402)'                            | 'CHIP0402'     | ''          | ''   | '20120917'
 '39NF'     | '16V'   | '10%'     | 'C0402'     | 'EMPTY'   | 'CH3393K1B00'(!)   = ''              | ''                 | ''       | 'CH3393K1B00'     |'C0402'| '(C0402-0201)'                                                       | 'NA'       | '16V'         | '10%'    | 'IO'       | 'CAP CHIP 39NF 16V(+-10%,X7R,0402)'                            | 'CHIP0402'     | ''          | ''   | '20120917'
 '1UF'      | '10V'   | '10%'     | 'C0402'     | 'X6S'     | 'CH5102KEB00'(!)   = ''              | ''                 | ''       | 'CH5102KEB00'     |'C0402'| '(C0402-0201)'                                                       | '1UF'      | '10V'         | '10%'    | 'DISCRETE' | 'CAP CHIP 1UF 10V(+-10%,X6S,0402)'                             | 'CHIP0402'     | ''          | ''   | '20120919'
 '1UF'      | '10V'   | '10%'     | 'C0402'     | 'EMPTY'   | 'CH5102KEB00'(!)   = ''              | ''                 | ''       | 'CH5102KEB00'     |'C0402'| '(C0402-0201)'                                                       | 'NA'       | '10V'         | '10%'    | 'IO'       | 'CAP CHIP 1UF 10V(+-10%,X6S,0402)'                             | 'CHIP0402'     | ''          | ''   | '20120919'
 '0.47UF'   | '10V'   | '10%'     | 'C0402'     | 'X6S'     | 'CH44702KEB0'(!)   = 'End of Design' | 'Comp-Approve'     | ''       | 'CH44702KEB0'     |'C0402'| '(C0402-0201)'                                                       | '0.47UF'   | '10V'         | '10%'    | 'DISCRETE' | 'CAP CHIP 0.47UF 10V(+-10%,X6S,0402)'                          | 'CHIP0402'     | ''          | ''   | '20121002'
 '0.47UF'   | '10V'   | '10%'     | 'C0402'     | 'EMPTY'   | 'CH44702KEB0'(!)   = 'End of Design' | 'Comp-Approve'     | ''       | 'CH44702KEB0'     |'C0402'| '(C0402-0201)'                                                       | 'NA'       | '10V'         | '10%'    | 'IO'       | 'CAP CHIP 0.47UF 10V(+-10%,X6S,0402)'                          | 'CHIP0402'     | ''          | ''   | '20121002'
 '0.33UF'   | '6.3V'  | '10%'     | 'C0402'     | 'X6S'     | 'CH4331KEB01'(!)   = 'End of Design' | 'Comp-Approve'     | ''       | 'CH4331KEB01'     |'C0402'| '(C0402-0201)'                                                       | '0.33UF'   | '6.3V'        | '10%'    | 'DISCRETE' | 'CAP CHIP 0.33UF 6.3V(10%,X6S,0402)'                           | 'CHIP0402'     | ''          | ''   | '20121009'
 '0.33UF'   | '6.3V'  | '10%'     | 'C0402'     | 'EMPTY'   | 'CH4331KEB01'(!)   = 'End of Design' | 'Comp-Approve'     | ''       | 'CH4331KEB01'     |'C0402'| '(C0402-0201)'                                                       | 'NA'       | '6.3V'        | '10%'    | 'IO'       | 'CAP CHIP 0.33UF 6.3V(10%,X6S,0402)'                           | 'CHIP0402'     | ''          | ''   | '20121009'
 '0.47UF'   | '6.3V'  | '10%'     | 'C0402'     | 'X6S'     | 'CH4471KEB01'(!)   = 'End of Design' | 'Comp-Approve'     | ''       | 'CH4471KEB01'     |'C0402'| '(C0402-0201)'                                                       | '0.47UF'   | '6.3V'        | '10%'    | 'DISCRETE' | 'CAP CHIP 0.47UF 6.3V(10%,X6S,0402)'                           | 'CHIP0402'     | ''          | ''   | '20121009'
 '0.47UF'   | '6.3V'  | '10%'     | 'C0402'     | 'EMPTY'   | 'CH4471KEB01'(!)   = 'End of Design' | 'Comp-Approve'     | ''       | 'CH4471KEB01'     |'C0402'| '(C0402-0201)'                                                       | 'NA'       | '6.3V'        | '10%'    | 'IO'       | 'CAP CHIP 0.47UF 6.3V(10%,X6S,0402)'                           | 'CHIP0402'     | ''          | ''   | '20121009'
 '22UF'     | '25V'   | '10%'     | 'C1206'     | 'X5R'     | 'CH6224K9200'(!)   = 'End of Design' | 'Comp-Approve'     | ''       | 'CH6224K9200'     |'C1206_H76'| '(SMC1206AW)'                                                        | '22UF'     | '25V'         | '10%'    | 'DISCRETE' | 'CAP CHIP 22U 25V(+-10%,X5R,1206)'                             | 'CHIP1206'     | ''          | ''   | '20121201'
 '22UF'     | '25V'   | '10%'     | 'C1206'     | 'EMPTY'   | 'CH6224K9200'(!)   = 'End of Design' | 'Comp-Approve'     | ''       | 'CH6224K9200'     |'C1206_H76'| '(SMC1206AW)'                                                        | 'NA'       | '25V'         | '10%'    | 'IO'       | 'CAP CHIP 22U 25V(+-10%,X5R,1206)'                             | 'CHIP1206'     | ''          | ''   | '20121201'
 '4.7PF'    | '50V'   | '0.1P'    | 'C0402'     | 'NPO'     | 'CH-4716TB06'(!)   = ''              | ''                 | ''       | 'CH-4716TB06'     |'C0402'| '(C0402-0201)'                                                       | '4.7PF'    | '50V'         | '0.10%'  | 'DISCRETE' | 'CAP CHIP 4.7P 50V(+-0.1P.NPO.0402)'                           | 'CHIP0402'     | ''          | ''   | '20121216'
 '4.7PF'    | '50V'   | '0.1P'    | 'C0402'     | 'EMPTY'   | 'CH-4716TB06'(!)   = ''              | ''                 | ''       | 'CH-4716TB06'     |'C0402'| '(C0402-0201)'                                                       | 'NA'       | '50V'         | '0.10%'  | 'IO'       | 'CAP CHIP 4.7P 50V(+-0.1P.NPO.0402)'                           | 'CHIP0402'     | ''          | ''   | '20121216'
 '0.47UF'   | '100V'  | '10%'     | 'C0805'     | 'X7R'     | 'CH4478K1A00'(!)   = ''              | ''                 | ''       | 'CH4478K1A00'     |'C0805_H61'| '(SMC0805AW)'                                                        | '0.47UF'   | '100V'        | '10%'    | 'DISCRETE' | 'CAP CHIP 0.47U 100V(+-10%.X7R.0805)'                          | 'CHIP0805'     | ''          | ''   | '20121219'
 '0.47UF'   | '100V'  | '10%'     | 'C0805'     | 'EMPTY'   | 'CH4478K1A00'(!)   = ''              | ''                 | ''       | 'CH4478K1A00'     |'C0805_H61'| '(SMC0805AW)'                                                        | 'NA'       | '100V'        | '10%'    | 'IO'       | 'CAP CHIP 0.47U 100V(+-10%.X7R.0805)'                          | 'CHIP0805'     | ''          | ''   | '20121219'
 '2.2UF'    | '100V'  | '10%'     | 'C1206'     | 'X7R'     | 'CH5228K1202'(!)   = 'End of Design' | 'Comp-Approve'     | ''       | 'CH5228K1202'     |'C1206_H76'| '(SMC1206AW)'                                                        | '2.2UF'    | '100V'        | '10%'    | 'DISCRETE' | 'CAP CHIP 2.2UF 100V(+-10%,X7R,1206)'                          | 'CHIP1206'     | ''          | ''   | '20121219'
 '2.2UF'    | '100V'  | '10%'     | 'C1206'     | 'EMPTY'   | 'CH5228K1202'(!)   = 'End of Design' | 'Comp-Approve'     | ''       | 'CH5228K1202'     |'C1206_H76'| '(SMC1206AW)'                                                        | 'NA'       | '100V'        | '10%'    | 'IO'       | 'CAP CHIP 2.2UF 100V(+-10%,X7R,1206)'                          | 'CHIP1206'     | ''          | ''   | '20121219'
 '0.01UF'   | '1KV'   | '10%'     | 'C1206'     | 'X7R'     | 'CH310FK1200'(!)   = ''              | ''                 | ''       | 'CH310FK1200'     |'C1206_H56'| '(SMC1206AW)'                                                        | '0.01UF'   | '1KV'         | '10%'    | 'DISCRETE' | 'CAP CHIP 0.01U 1KV(+-10%,X7R,1206)H1.25'                      | 'CHIP1206'     | ''          | ''   | '20130103'
 '0.01UF'   | '1KV'   | '10%'     | 'C1206'     | 'EMPTY'   | 'CH310FK1200'(!)   = ''              | ''                 | ''       | 'CH310FK1200'     |'C1206_H56'| '(SMC1206AW)'                                                        | 'NA'       | '1KV'         | '10%'    | 'IO'       | 'CAP CHIP 0.01U 1KV(+-10%,X7R,1206)H1.25'                      | 'CHIP1206'     | ''          | ''   | '20130103'
 '0.01UF'   | '100V'  | '10%'     | 'C0603'     | 'X7R'     | 'CH3108K1900'(!)   = ''              | ''                 | ''       | 'CH3108K1900'     |'C0603'| '(SMC0603AW)'                                                        | '0.01UF'   | '100V'        | '10%'    | 'DISCRETE' | 'CAP CHIP 0.01U 100V(+-10%.X7R.0603)'                          | 'CHIP0603'     | ''          | ''   | '20130110'
 '0.01UF'   | '100V'  | '10%'     | 'C0603'     | 'EMPTY'   | 'CH3108K1900'(!)   = ''              | ''                 | ''       | 'CH3108K1900'     |'C0603'| '(SMC0603AW)'                                                        | 'NA'       | '100V'        | '10%'    | 'IO'       | 'CAP CHIP 0.01U 100V(+-10%.X7R.0603)'                          | 'CHIP0603'     | ''          | ''   | '20130110'
 '560PF'    | '50V'   | '10%'     | 'C0402'     | 'X7R'     | 'CH1566K1B09'(!)   = ''              | ''                 | ''       | 'CH1566K1B09'     |'C0402'| '(C0402_OCTAGONXA,C0402-0201)'                                       | '560PF'    | '50V'         | '10%'    | 'DISCRETE' | 'CAP CHIP 560P 50V(+-10%,X7R,0402)'                            | 'CHIP0402'     | ''          | ''   | '20130114'
 '560PF'    | '50V'   | '10%'     | 'C0402'     | 'EMPTY'   | 'CH1566K1B09'(!)   = ''              | ''                 | ''       | 'CH1566K1B09'     |'C0402'| '(C0402_OCTAGONXA,C0402-0201)'                                       | 'NA'       | '50V'         | '10%'    | 'IO'       | 'CAP CHIP 560P 50V(+-10%,X7R,0402)'                            | 'CHIP0402'     | ''          | ''   | '20130114'
 '820PF'    | '50V'   | '10%'     | 'C0402'     | 'X7R'     | 'CH18206KB11'(!)   = ''              | ''                 | ''       | 'CH18206KB11'     |'C0402'| '(C0402-0201)'                                                       | '820PF'    | '50V'         | '10%'    | 'DISCRETE' | 'CAP CHIP 820P 50V(+-10%,X7R,0402)'                            | 'CHIP0402'     | ''          | ''   | '20130114'
 '820PF'    | '50V'   | '10%'     | 'C0402'     | 'EMPTY'   | 'CH18206KB11'(!)   = ''              | ''                 | ''       | 'CH18206KB11'     |'C0402'| '(C0402-0201)'                                                       | 'NA'       | '50V'         | '10%'    | 'IO'       | 'CAP CHIP 820P 50V(+-10%,X7R,0402)'                            | 'CHIP0402'     | ''          | ''   | '20130114'
 '2.2UF'    | '16V'   | '20%'     | 'C0805'     | 'Y5V'     | 'CH52203ZA30'(!)   = ''              | ''                 | ''       | 'CH52203ZA30'     |'C0805_H64'| '(SMC0805AW)'                                                        | '2.2UF'    | '16V'         | '20%'    | 'DISCRETE' | 'CAP CHIP 2.2U.16V(+80-20%.Y5V.0805)'                          | 'CHIP0805'     | ''          | ''   | '20130214'
 '2.2UF'    | '16V'   | '20%'     | 'C0805'     | 'EMPTY'   | 'CH52203ZA30'(!)   = ''              | ''                 | ''       | 'CH52203ZA30'     |'C0805_H64'| '(SMC0805AW)'                                                        | 'NA'       | '16V'         | '20%'    | 'IO'       | 'CAP CHIP 2.2U.16V(+80-20%.Y5V.0805)'                          | 'CHIP0805'     | ''          | ''   | '20130214'
 '22UF'     | '4V'    | '20%'     | 'C0603'     | 'X6S'     | 'CH622KME901'(!)   = ''              | ''                 | ''       | 'CH622KME901'     |'C0603'| '(SMC0603AW)'                                                        | '22UF'     | '4V'          | '20%'    | 'DISCRETE' | 'CAP CHIP 22UF 4V(+-20%,X6S,0603)'                             | 'CHIP0603'     | ''          | ''   | '20130321'
 '22UF'     | '4V'    | '20%'     | 'C0603'     | 'EMPTY'   | 'CH622KME901'(!)   = ''              | ''                 | ''       | 'CH622KME901'     |'C0603'| '(SMC0603AW)'                                                        | 'NA'       | '4V'          | '20%'    | 'IO'       | 'CAP CHIP 22UF 4V(+-20%,X6S,0603)'                             | 'CHIP0603'     | ''          | ''   | '20130321'
 '0.68UF'   | '16V'   | '80%'     | 'C0603'     | 'Y5V'     | 'CH4683Z3900'(!)   = 'End of Design' | 'Comp-Approve'     | ''       | 'CH4683Z3900'     |'C0603'| '(SMC0603AW)'                                                        | '0.68UF'   | '16V'         | '80%'    | 'DISCRETE' | 'CAP CHIP 0.68U 16V(+80%-20%,Y5V,0603)'                        | 'CHIP0603'     | ''          | ''   | '20130321'
 '0.68UF'   | '16V'   | '80%'     | 'C0603'     | 'EMPTY'   | 'CH4683Z3900'(!)   = 'End of Design' | 'Comp-Approve'     | ''       | 'CH4683Z3900'     |'C0603'| '(SMC0603AW)'                                                        | 'NA'       | '16V'         | '80%'    | 'IO'       | 'CAP CHIP 0.68U 16V(+80%-20%,Y5V,0603)'                        | 'CHIP0603'     | ''          | ''   | '20130321'
 '22UF'     | '4V'    | '20%'     | 'C0402'     | 'X5R'     | 'CH622KM9B02'(!)   = 'End of Design' | 'Comp-Approve'     | ''       | 'CH622KM9B02'     |'C0402'| '(C0402-0201)'                                                       | '22UF'     | '4V'          | '20%'    | 'DISCRETE' | 'CAP CHIP 22UF 4V (+-20%, X5R,0402)'                           | 'CHIP0402'     | ''          | ''   | '20130408'
 '22UF'     | '4V'    | '20%'     | 'C0402'     | 'EMPTY'   | 'CH622KM9B02'(!)   = 'End of Design' | 'Comp-Approve'     | ''       | 'CH622KM9B02'     |'C0402'| '(C0402-0201)'                                                       | 'NA'       | '4V'          | '20%'    | 'IO'       | 'CAP CHIP 22UF 4V (+-20%, X5R,0402)'                           | 'CHIP0402'     | ''          | ''   | '20130408'
 '180PF'    | '50V'   | '5%'      | 'C0402'     | 'NPO'     | 'CH11806JB09'(!)   = ''              | ''                 | ''       | 'CH11806JB09'     |'C0402'| '(C0402-0201)'                                                       | '180PF'    | '50V'         | '5%'     | 'DISCRETE' | 'CAP CHIP 180P 50V(+-5%.NPO.0402)'                             | 'CHIP0402'     | ''          | ''   | '20130628'
 '180PF'    | '50V'   | '5%'      | 'C0402'     | 'EMPTY'   | 'CH11806JB09'(!)   = ''              | ''                 | ''       | 'CH11806JB09'     |'C0402'| '(C0402-0201)'                                                       | 'NA'       | '50V'         | '5%'     | 'IO'       | 'CAP CHIP 180P 50V(+-5%.NPO.0402)'                             | 'CHIP0402'     | ''          | ''   | '20130628'
 '12PF'     | '50V'   | '5%'      | 'C0402'     | 'C0G'     | 'CH01206JB05'(!)   = ''              | ''                 | ''       | 'CH01206JB05'     |'C0402'| '(C0402-0201)'                                                       | '12PF'     | '50V'         | '5%'     | 'DISCRETE' | 'CAP CHIP 12P 50V(+-5%.C0G.0402)'                              | 'CHIP0402'     | ''          | ''   | '20130703'
 '12PF'     | '50V'   | '5%'      | 'C0402'     | 'EMPTY'   | 'CH01206JB05'(!)   = ''              | ''                 | ''       | 'CH01206JB05'     |'C0402'| '(C0402-0201)'                                                       | 'NA'       | '50V'         | '5%'     | 'IO'       | 'CAP CHIP 12P 50V(+-5%.C0G.0402)'                              | 'CHIP0402'     | ''          | ''   | '20130703'
 '4700PF'   | '6.3V'  | '10%'     | 'C0201'     | 'X7R'     | 'CH2471K1E01'(!)   = ''              | ''                 | ''       | 'CH2471K1E01'     |'C0201'| '(SMC0201AW)'                                                        | '4700PF'   | '6.3V'        | '10%'    | 'DISCRETE' | 'CAP CHIP 4700P 6.3V (+-10%,X7R,0201)'                         | 'CHIP0201'     | ''          | ''   | '20131017'
 '4700PF'   | '6.3V'  | '10%'     | 'C0201'     | 'EMPTY'   | 'CH2471K1E01'(!)   = ''              | ''                 | ''       | 'CH2471K1E01'     |'C0201'| '(SMC0201AW)'                                                        | 'NA'       | '6.3V'        | '10%'    | 'IO'       | 'CAP CHIP 4700P 6.3V (+-10%,X7R,0201)'                         | 'CHIP0201'     | ''          | ''   | '20131017'
 '0.1UF'    | '4V'    | '20%'     | 'C0201'     | 'X6S'     | 'CH410KMEE00'(!)   = 'End of Design' | 'Comp-Approve'     | ''       | 'CH410KMEE00'     |'C0201'| '(SMC0201AW)'                                                        | '0.1UF'    | '4V'          | '20%'    | 'DISCRETE' | 'CAP CHIP 0.1U 4V(+-20%,X6S,0201)'                             | 'CHIP0201'     | ''          | ''   | '20131017'
 '0.1UF'    | '4V'    | '20%'     | 'C0201'     | 'EMPTY'   | 'CH410KMEE00'(!)   = 'End of Design' | 'Comp-Approve'     | ''       | 'CH410KMEE00'     |'C0201'| '(SMC0201AW)'                                                        | 'NA'       | '4V'          | '20%'    | 'IO'       | 'CAP CHIP 0.1U 4V(+-20%,X6S,0201)'                             | 'CHIP0201'     | ''          | ''   | '20131017'
 '2.2UF'    | '10V'   | '10%'     | 'C0603'     | 'X5R'     | 'CH5222K9907'(!)   = 'End of Design' | 'Comp-Approve'     | ''       | 'CH5222K9907'     |'C0603'| '(SMC0603AW)'                                                        | '2.2UF'    | '10V'         | '10%'    | 'DISCRETE' | 'CAP CHIP 2.2U 10V(+-10%.X5R.0603)'                            | 'CHIP0603'     | ''          | ''   | '20140325'
 '2.2UF'    | '10V'   | '10%'     | 'C0603'     | 'EMPTY'   | 'CH5222K9907'(!)   = 'End of Design' | 'Comp-Approve'     | ''       | 'CH5222K9907'     |'C0603'| '(SMC0603AW)'                                                        | 'NA'       | '10V'         | '10%'    | 'IO'       | 'CAP CHIP 2.2U 10V(+-10%.X5R.0603)'                            | 'CHIP0603'     | ''          | ''   | '20140325'
 '0.047UF'  | '25V'   | '10%'     | 'C0402'     | 'X7R'     | 'CH3474K1B04'(!)   = ''              | ''                 | ''       | 'CH3474K1B04'     |'C0402'| '(C0402_OCTAGONXA,C0402-0201)'                                       | '0.047UF'  | '25V'         | '10%'    | 'DISCRETE' | 'CAP CHIP 0.047U 25V(+-10% X7R 0402)'                          | 'CHIP0402'     | ''          | ''   | '20140325'
 '0.047UF'  | '25V'   | '10%'     | 'C0402'     | 'EMPTY'   | 'CH3474K1B04'(!)   = ''              | ''                 | ''       | 'CH3474K1B04'     |'C0402'| '(C0402_OCTAGONXA,C0402-0201)'                                       | 'NA'       | '25V'         | '10%'    | 'IO'       | 'CAP CHIP 0.047U 25V(+-10% X7R 0402)'                          | 'CHIP0402'     | ''          | ''   | '20140325'
 '3900PF'   | '50V'   | '10%'     | 'C0402'     | 'X7R'     | 'CH23906KB14'(!)   = ''              | ''                 | ''       | 'CH23906KB14'     |'C0402'| '(C0402-0201)'                                                       | '3900PF'   | '50V'         | '10%'    | 'DISCRETE' | 'CAP CHIP 3900P 50V(+-10%,X7R,0402)'                           | 'CHIP0402'     | ''          | ''   | '20140325'
 '3900PF'   | '50V'   | '10%'     | 'C0402'     | 'EMPTY'   | 'CH23906KB14'(!)   = ''              | ''                 | ''       | 'CH23906KB14'     |'C0402'| '(C0402-0201)'                                                       | 'NA'       | '50V'         | '10%'    | 'IO'       | 'CAP CHIP 3900P 50V(+-10%,X7R,0402)'                           | 'CHIP0402'     | ''          | ''   | '20140325'
 '8.2PF'    | '50V'   | '0.1P'    | 'C0402'     | 'NP0'     | 'CH-8216TB09'(!)   = ''              | ''                 | ''       | 'CH-8216TB09'     |'C0402'| '(C0402-0201)'                                                       | '8.2PF'    | '50V'         | '0.1P'   | 'DISCRETE' | 'CAP CHIP 8.2P 50V (+-0.1P NP0 0402)'                          | 'CHIP0402'     | ''          | ''   | '20140326'
 '8.2PF'    | '50V'   | '0.1P'    | 'C0402'     | 'EMPTY'   | 'CH-8216TB09'(!)   = ''              | ''                 | ''       | 'CH-8216TB09'     |'C0402'| '(C0402-0201)'                                                       | 'NA'       | '50V'         | '0.1P'   | 'IO'       | 'CAP CHIP 8.2P 50V (+-0.1P NP0 0402)'                          | 'CHIP0402'     | ''          | ''   | '20140326'
 '220PF'    | '100V'  | '10%'     | 'C0402'     | 'X7R'     | 'CH1228K1B00'(!)   = 'End of Design' | 'Comp-Approve'     | ''       | 'CH1228K1B00'     |'C0402'| '(C0402-0201)'                                                       | '220PF'    | '100V'        | '10%'    | 'DISCRETE' | 'CAP CHIP 220PF 100V(10%,X7R,0402)'                            | 'CHIP0402'     | ''          | ''   | '20140326'
 '220PF'    | '100V'  | '10%'     | 'C0402'     | 'EMPTY'   | 'CH1228K1B00'(!)   = 'End of Design' | 'Comp-Approve'     | ''       | 'CH1228K1B00'     |'C0402'| '(C0402-0201)'                                                       | 'NA'       | '100V'        | '10%'    | 'IO'       | 'CAP CHIP 220PF 100V(10%,X7R,0402)'                            | 'CHIP0402'     | ''          | ''   | '20140326'
 '10UF'     | '25V'   | '10%'     | 'C0805'     | 'X6S'     | 'CH6104KEA00'(!)   = ''              | ''                 | ''       | 'CH6104KEA00'     |'C0805_H61'| '(SMC0805AW)'                                                        | '10UF'     | '25V'         | '10%'    | 'DISCRETE' | 'CAP CHIP 10U 25V(+-10%,X6S,0805,H1.25)'                       | 'CHIP0805'     | ''          | ''   | '20140327'
 '10UF'     | '25V'   | '10%'     | 'C0805'     | 'EMPTY'   | 'CH6104KEA00'(!)   = ''              | ''                 | ''       | 'CH6104KEA00'     |'C0805_H61'| '(SMC0805AW)'                                                        | 'NA'       | '25V'         | '10%'    | 'IO'       | 'CAP CHIP 10U 25V(+-10%,X6S,0805,H1.25)'                       | 'CHIP0805'     | ''          | ''   | '20140327'
 '1UF'      | '25V'   | '10%'     | 'C0402'     | 'X6S'     | 'CH5104KEB02'(!)   = ''              | ''                 | ''       | 'CH5104KEB02'     |'C0402'| '(C0402_OCTAGONXA,C0402-0201)'                                       | '1UF'      | '25V'         | '10%'    | 'DISCRETE' | 'CAP CHIP 1UF 25V(+-10%,X6S,0402)'                             | 'CHIP0402'     | ''          | ''   | '20140327'
 '1UF'      | '25V'   | '10%'     | 'C0402'     | 'EMPTY'   | 'CH5104KEB02'(!)   = ''              | ''                 | ''       | 'CH5104KEB02'     |'C0402'| '(C0402_OCTAGONXA,C0402-0201)'                                       | 'NA'       | '25V'         | '10%'    | 'IO'       | 'CAP CHIP 1UF 25V(+-10%,X6S,0402)'                             | 'CHIP0402'     | ''          | ''   | '20140327'
 '2.2UF'    | '16V'   | '10%'     | 'C0603'     | 'X6S'     | 'CH5223KE901'(!)   = ''              | ''                 | ''       | 'CH5223KE901'     |'C0603'| '(SMC0603AW)'                                                        | '2.2UF'    | '16V'         | '10%'    | 'DISCRETE' | 'CAP CHIP 2.2U 16V(+-10%,X6S,0603)'                            | 'CHIP0603'     | ''          | ''   | '20140327'
 '2.2UF'    | '16V'   | '10%'     | 'C0603'     | 'EMPTY'   | 'CH5223KE901'(!)   = ''              | ''                 | ''       | 'CH5223KE901'     |'C0603'| '(SMC0603AW)'                                                        | 'NA'       | '16V'         | '10%'    | 'IO'       | 'CAP CHIP 2.2U 16V(+-10%,X6S,0603)'                            | 'CHIP0603'     | ''          | ''   | '20140327'
 '22UF'     | '6.3V'  | '20%'     | 'C0603'     | 'X6S'     | 'CH6221ME900'(!)   = ''              | ''                 | ''       | 'CH6221ME900'     |'C0603'| '(SMC0603AW)'                                                        | '22UF'     | '6.3V'        | '20%'    | 'DISCRETE' | 'CAP CHIP 22U 6.3V(+-20%,X6S,0603)'                            | 'CHIP0603'     | ''          | ''   | '20140327'
 '22UF'     | '6.3V'  | '20%'     | 'C0603'     | 'EMPTY'   | 'CH6221ME900'(!)   = ''              | ''                 | ''       | 'CH6221ME900'     |'C0603'| '(SMC0603AW)'                                                        | 'NA'       | '6.3V'        | '20%'    | 'IO'       | 'CAP CHIP 22U 6.3V(+-20%,X6S,0603)'                            | 'CHIP0603'     | ''          | ''   | '20140327'
 '2.2UF'    | '10V'   | '10%'     | 'C0603'     | 'X7R'     | 'CH5222K1906'(!)   = ''              | ''                 | ''       | 'CH5222K1906'     |'C0603'| '(SMC0603AW)'                                                        | '2.2UF'    | '10V'         | '10%'    | 'DISCRETE' | 'CAP CHIP 2.2UF 10V(+-10%.X7R.0603)'                           | 'CHIP0603'     | ''          | ''   | '20140327'
 '2.2UF'    | '10V'   | '10%'     | 'C0603'     | 'EMPTY'   | 'CH5222K1906'(!)   = ''              | ''                 | ''       | 'CH5222K1906'     |'C0603'| '(SMC0603AW)'                                                        | 'NA'       | '10V'         | '10%'    | 'IO'       | 'CAP CHIP 2.2UF 10V(+-10%.X7R.0603)'                           | 'CHIP0603'     | ''          | ''   | '20140327'
 '0.47UF'   | '25V'   | '10%'     | 'C0603'     | 'X7R'     | 'CH4474K1907'(!)   = 'End of Design' | 'Comp-Approve'     | ''       | 'CH4474K1907'     |'C0603'| '(SMC0603AW)'                                                        | '0.47UF'   | '25V'         | '10%'    | 'DISCRETE' | 'CAP CHIP 0.47UF 25V(+-10%,X7R,0603)'                          | 'CHIP0603'     | ''          | ''   | '20140328'
 '0.47UF'   | '25V'   | '10%'     | 'C0603'     | 'EMPTY'   | 'CH4474K1907'(!)   = 'End of Design' | 'Comp-Approve'     | ''       | 'CH4474K1907'     |'C0603'| '(SMC0603AW)'                                                        | 'NA'       | '25V'         | '10%'    | 'IO'       | 'CAP CHIP 0.47UF 25V(+-10%,X7R,0603)'                          | 'CHIP0603'     | ''          | ''   | '20140328'
 '1000PF'   | '50V'   | '5%'      | 'C0603'     | 'NPO'     | 'CH21006J902'(!)   = 'End of Design' | 'Comp-Approve'     | ''       | 'CH21006J902'     |'C0603'| '(SMC0603AW)'                                                        | '1000PF'   | '50V'         | '5%'     | 'DISCRETE' | 'CAP CHIP 1000P 50V(+-5%.NPO.0603)EP'                          | 'CHIP0603'     | ''          | ''   | '20140328'
 '1000PF'   | '50V'   | '5%'      | 'C0603'     | 'EMPTY'   | 'CH21006J902'(!)   = 'End of Design' | 'Comp-Approve'     | ''       | 'CH21006J902'     |'C0603'| '(SMC0603AW)'                                                        | 'NA'       | '50V'         | '5%'     | 'IO'       | 'CAP CHIP 1000P 50V(+-5%.NPO.0603)EP'                          | 'CHIP0603'     | ''          | ''   | '20140328'
 '0.047UF'  | '50V'   | '10%'     | 'C0603'     | 'X7R'     | 'CH34706K912'(!)   = 'End of Design' | 'Comp-Approve'     | ''       | 'CH34706K912'     |'C0603'| '(SMC0603AW)'                                                        | '0.047UF'  | '50V'         | '10%'    | 'DISCRETE' | 'CAP. CHIP 0.047UF 50V(+-10%,X7R,0603)'                        | 'CHIP0603'     | ''          | ''   | '20140328'
 '0.047UF'  | '50V'   | '10%'     | 'C0603'     | 'EMPTY'   | 'CH34706K912'(!)   = 'End of Design' | 'Comp-Approve'     | ''       | 'CH34706K912'     |'C0603'| '(SMC0603AW)'                                                        | 'NA'       | '50V'         | '10%'    | 'IO'       | 'CAP. CHIP 0.047UF 50V(+-10%,X7R,0603)'                        | 'CHIP0603'     | ''          | ''   | '20140328'
 '10UF'     | '25V'   | '20%'     | 'C0603'     | 'X5R'     | 'CH6104M9901'(!)   = ''              | ''                 | ''       | 'CH6104M9901'     |'C0603'| '(SMC0603AW)'                                                        | '10UF'     | '25V'         | '20%'    | 'DISCRETE' | 'CAP CHIP 10UF 25V(+-20%,X5R,0603)'                            | 'CHIP0603'     | ''          | ''   | '20140331'
 '10UF'     | '25V'   | '20%'     | 'C0603'     | 'EMPTY'   | 'CH6104M9901'(!)   = ''              | ''                 | ''       | 'CH6104M9901'     |'C0603'| '(SMC0603AW)'                                                        | 'NA'       | '25V'         | '20%'    | 'IO'       | 'CAP CHIP 10UF 25V(+-20%,X5R,0603)'                            | 'CHIP0603'     | ''          | ''   | '20140331'
 '10UF'     | '16V'   | '10%'     | 'C0805'     | 'X7R'     | 'CH6103K1A00'(!)   = ''              | ''                 | ''       | 'CH6103K1A00'     |'C0805_H61'| '(SMC0805AW)'                                                        | '10UF'     | '16V'         | '10%'    | 'DISCRETE' | 'CAP CHIP 10UF 16V(+-10%,X7R,0805)'                            | 'CHIP0805'     | ''          | ''   | '20140331'
 '10UF'     | '16V'   | '10%'     | 'C0805'     | 'EMPTY'   | 'CH6103K1A00'(!)   = ''              | ''                 | ''       | 'CH6103K1A00'     |'C0805_H61'| '(SMC0805AW)'                                                        | 'NA'       | '16V'         | '10%'    | 'IO'       | 'CAP CHIP 10UF 16V(+-10%,X7R,0805)'                            | 'CHIP0805'     | ''          | ''   | '20140331'
 '0.01UF'   | '1KV'   | '10%'     | 'C1206'     | 'X7R'     | 'CH310FK1201'(!)   = 'End of Design' | 'Comp-Approve'     | ''       | 'CH310FK1201'     |'C1206_H76'| '(SMC1206AW)'                                                        | '0.01UF'   | '1KV'         | '10%'    | 'DISCRETE' | 'CAP CHIP 0.01U 1KV(+-10%,X7R,1206)H1.6'                       | 'CHIP1206'     | ''          | ''   | '20140331'
 '0.01UF'   | '1KV'   | '10%'     | 'C1206'     | 'EMPTY'   | 'CH310FK1201'(!)   = 'End of Design' | 'Comp-Approve'     | ''       | 'CH310FK1201'     |'C1206_H76'| '(SMC1206AW)'                                                        | 'NA'       | '1KV'         | '10%'    | 'IO'       | 'CAP CHIP 0.01U 1KV(+-10%,X7R,1206)H1.6'                       | 'CHIP1206'     | ''          | ''   | '20140331'
 '0.1UF'    | '100V'  | '10%'     | 'C1206'     | 'X7R'     | 'CH4108K1202'(!)   = 'End of Design' | 'Comp-Approve'     | ''       | 'CH4108K1202'     |'C1206_H42'| '(SMC1206AW)'                                                        | '0.1UF'    | '100V'        | '10%'    | 'DISCRETE' | 'CAP CHIP 0.1U 100V(+-10%.X7R.1206)H1.25'                      | 'CHIP1206'     | ''          | ''   | '20140331'
 '0.1UF'    | '100V'  | '10%'     | 'C1206'     | 'EMPTY'   | 'CH4108K1202'(!)   = 'End of Design' | 'Comp-Approve'     | ''       | 'CH4108K1202'     |'C1206_H42'| '(SMC1206AW)'                                                        | 'NA'       | '100V'        | '10%'    | 'IO'       | 'CAP CHIP 0.1U 100V(+-10%.X7R.1206)H1.25'                      | 'CHIP1206'     | ''          | ''   | '20140331'
 '0.1UF'    | '250V'  | '10%'     | 'C1206'     | 'X7R'     | 'CH410CK1200'(!)   = 'End of Design' | 'Comp-Approve'     | ''       | 'CH410CK1200'     |'C1206_H66'| '(SMC1206AW)'                                                        | '0.1UF'    | '250V'        | '10%'    | 'DISCRETE' | 'CAP CHIP 0.1U 250V(10%,X7R,1206)H1.6'                         | 'CHIP1206'     | ''          | ''   | '20140331'
 '0.1UF'    | '250V'  | '10%'     | 'C1206'     | 'EMPTY'   | 'CH410CK1200'(!)   = 'End of Design' | 'Comp-Approve'     | ''       | 'CH410CK1200'     |'C1206_H66'| '(SMC1206AW)'                                                        | 'NA'       | '250V'        | '10%'    | 'IO'       | 'CAP CHIP 0.1U 250V(10%,X7R,1206)H1.6'                         | 'CHIP1206'     | ''          | ''   | '20140331'
 '0.015UF'  | '50V'   | '10%'     | 'C0402'     | 'X7R'     | 'CH3156K1B00'(!)   = 'End of Design' | 'Comp-Approve'     | ''       | 'CH3156K1B00'     |'C0402'| '(C0402-0201)'                                                       | '0.015UF'  | '50V'         | '10%'    | 'DISCRETE' | 'CAP CHIP 0.015U 50V(+-10%,X7R,0402)'                          | 'CHIP0402'     | ''          | ''   | '20140331'
 '0.015UF'  | '50V'   | '10%'     | 'C0402'     | 'EMPTY'   | 'CH3156K1B00'(!)   = 'End of Design' | 'Comp-Approve'     | ''       | 'CH3156K1B00'     |'C0402'| '(C0402-0201)'                                                       | 'NA'       | '50V'         | '10%'    | 'IO'       | 'CAP CHIP 0.015U 50V(+-10%,X7R,0402)'                          | 'CHIP0402'     | ''          | ''   | '20140331'
 '22UF'     | '16V'   | '10%'     | 'C1206'     | 'X6S'     | 'CH6223KE200'(!)   = 'End of Design' | 'Comp-Approve'     | ''       | 'CH6223KE200'     |'C1206_H66'| '(SMC1206AW)'                                                        | '22UF'     | '16V'         | '10%'    | 'DISCRETE' | 'CAP CHIP 22UF 16V(+-10%,X6S,1206)'                            | 'CHIP1206'     | ''          | ''   | '20140401'
 '22UF'     | '16V'   | '10%'     | 'C1206'     | 'EMPTY'   | 'CH6223KE200'(!)   = 'End of Design' | 'Comp-Approve'     | ''       | 'CH6223KE200'     |'C1206_H66'| '(SMC1206AW)'                                                        | 'NA'       | '16V'         | '10%'    | 'IO'       | 'CAP CHIP 22UF 16V(+-10%,X6S,1206)'                            | 'CHIP1206'     | ''          | ''   | '20140401'
 '10UF'     | '6.3V'  | '20%'     | 'C0603'     | 'X6S'     | 'CH6101ME900'(!)   = 'End of Design' | 'Comp-Approve'     | ''       | 'CH6101ME900'     |'C0603'| '(SMC0603AW)'                                                        | '10UF'     | '6.3V'        | '20%'    | 'DISCRETE' | 'CAP CHIP 10U 6.3V(+-20%,X6S,0603)'                            | 'CHIP0603'     | ''          | ''   | '20140415'
 '10UF'     | '6.3V'  | '20%'     | 'C0603'     | 'EMPTY'   | 'CH6101ME900'(!)   = 'End of Design' | 'Comp-Approve'     | ''       | 'CH6101ME900'     |'C0603'| '(SMC0603AW)'                                                        | 'NA'       | '6.3V'        | '20%'    | 'IO'       | 'CAP CHIP 10U 6.3V(+-20%,X6S,0603)'                            | 'CHIP0603'     | ''          | ''   | '20140415'
 '1000PF'   | '2KV'   | '20%'     | 'C1808'     | 'X7R'     | 'CH210IM1I00'(!)   = 'End of Design' | 'Comp-Release Qty' | ''       | 'CH210IM1I00'     |'C1808_H80'| '(SMC1808AW)'                                                        | '1000PF'   | '2KV'         | '20%'    | 'DISCRETE' | 'CAP CHIP 1000P 2KV(20%,X7R,1808,H2.03)'                       | 'CHIP1808'     | ''          | ''   | '20140418'
 '1000PF'   | '2KV'   | '20%'     | 'C1808'     | 'EMPTY'   | 'CH210IM1I00'(!)   = 'End of Design' | 'Comp-Release Qty' | ''       | 'CH210IM1I00'     |'C1808_H80'| '(SMC1808AW)'                                                        | 'NA'       | '2KV'         | '20%'    | 'IO'       | 'CAP CHIP 1000P 2KV(20%,X7R,1808,H2.03)'                       | 'CHIP1808'     | ''          | ''   | '20140418'
 '33NF'     | '25V'   | '10%'     | 'C0402'     | 'X7R'     | 'CH3334K1B00'(!)   = ''              | ''                 | ''       | 'CH3334K1B00'     |'C0402'| '(C0402_OCTAGONXA,C0402-0201)'                                       | '33NF'     | '25V'         | '10%'    | 'DISCRETE' | 'CAP CHIP 33NF 25V(+-10%,X7R,0402)'                            | 'CHIP0402'     | ''          | ''   | '20140507'
 '33NF'     | '25V'   | '10%'     | 'C0402'     | 'EMPTY'   | 'CH3334K1B00'(!)   = ''              | ''                 | ''       | 'CH3334K1B00'     |'C0402'| '(C0402_OCTAGONXA,C0402-0201)'                                       | 'NA'       | '25V'         | '10%'    | 'IO'       | 'CAP CHIP 33NF 25V(+-10%,X7R,0402)'                            | 'CHIP0402'     | ''          | ''   | '20140507'
 '0.1UF'    | '6.3V'  | '10%'     | 'C0201'     | 'X6S'     | 'CH4101KEE01'(!)   = ''              | ''                 | ''       | 'CH4101KEE01'     |'C0201'| '(SMC0201AW)'                                                        | '0.1UF'    | '6.3V'        | '10%'    | 'DISCRETE' | 'CAP CHIP 0.1UF 6.3V(10%,X6S,0201,H0.3)'                       | 'CHIP0201'     | ''          | ''   | '20140508'
 '0.1UF'    | '6.3V'  | '10%'     | 'C0201'     | 'EMPTY'   | 'CH4101KEE01'(!)   = ''              | ''                 | ''       | 'CH4101KEE01'     |'C0201'| '(SMC0201AW)'                                                        | 'NA'       | '6.3V'        | '10%'    | 'IO'       | 'CAP CHIP 0.1UF 6.3V(10%,X6S,0201,H0.3)'                       | 'CHIP0201'     | ''          | ''   | '20140508'
 '0.1UF'    | '16V'   | '10%'     | 'C0201'     | 'X6S'     | 'CH4103KEE01'(!)   = ''              | ''                 | ''       | 'CH4103KEE01'     |'C0201'| '(SMC0201AW)'                                                        | '0.1UF'    | '16V'         | '10%'    | 'DISCRETE' | 'CAP CHIP 0.1UF 16V(+-10%,X6S,0201)'                           | 'CHIP0201'     | ''          | ''   | '20140508'
 '0.1UF'    | '16V'   | '10%'     | 'C0201'     | 'EMPTY'   | 'CH4103KEE01'(!)   = ''              | ''                 | ''       | 'CH4103KEE01'     |'C0201'| '(SMC0201AW)'                                                        | 'NA'       | '16V'         | '10%'    | 'IO'       | 'CAP CHIP 0.1UF 16V(+-10%,X6S,0201)'                           | 'CHIP0201'     | ''          | ''   | '20140508'
 '3300PF'   | '16V'   | '10%'     | 'C0201'     | 'X7R'     | 'CH2333K1E00'(!)   = ''              | ''                 | ''       | 'CH2333K1E00'     |'C0201'| '(C0201_HOME-PLATE_H22)'                                             | '3300PF'   | '16V'         | '10%'    | 'DISCRETE' | 'CAP CHIP 3300P 16V(+-10%,X7R,0201)'                           | 'CHIP0201'     | ''          | ''   | '20140707'
 '3300PF'   | '16V'   | '10%'     | 'C0201'     | 'EMPTY'   | 'CH2333K1E00'(!)   = ''              | ''                 | ''       | 'CH2333K1E00'     |'C0201'| '(C0201_HOME-PLATE_H22)'                                             | 'NA'       | '16V'         | '10%'    | 'IO'       | 'CAP CHIP 3300P 16V(+-10%,X7R,0201)'                           | 'CHIP0201'     | ''          | ''   | '20140707'
 '6800PF'   | '10V'   | '10%'     | 'C0201'     | 'X7R'     | 'CH2682K1E02'(!)   = ''              | ''                 | ''       | 'CH2682K1E02'     |'C0201'| '(SMC0201AW)'                                                        | '6800PF'   | '10V'         | '10%'    | 'DISCRETE' | 'CAP CHIP 6800PF 10V(10%,X7R,0201)'                            | 'CHIP0201'     | ''          | ''   | '20140707'
 '6800PF'   | '10V'   | '10%'     | 'C0201'     | 'EMPTY'   | 'CH2682K1E02'(!)   = ''              | ''                 | ''       | 'CH2682K1E02'     |'C0201'| '(SMC0201AW)'                                                        | 'NA'       | '10V'         | '10%'    | 'IO'       | 'CAP CHIP 6800PF 10V(10%,X7R,0201)'                            | 'CHIP0201'     | ''          | ''   | '20140707'
 '100PF'    | '25V'   | '5%'      | 'C0201'     | 'COG'     | 'CH1104J0E07'(!)   = ''              | ''                 | ''       | 'CH1104J0E07'     |'C0201'| '(SMC0201AW)'                                                        | '100PF'    | '25V'         | '5%'     | 'DISCRETE' | 'CAP CHIP 100P 25V(+-5%,COG,0201)'                             | 'CHIP0201'     | ''          | ''   | '20140707'
 '100PF'    | '25V'   | '5%'      | 'C0201'     | 'EMPTY'   | 'CH1104J0E07'(!)   = ''              | ''                 | ''       | 'CH1104J0E07'     |'C0201'| '(SMC0201AW)'                                                        | 'NA'       | '25V'         | '5%'     | 'IO'       | 'CAP CHIP 100P 25V(+-5%,COG,0201)'                             | 'CHIP0201'     | ''          | ''   | '20140707'
 '330PF'    | '25V'   | '5%'      | 'C0201'     | 'X7R'     | 'CH1334J1E00'(!)   = ''              | ''                 | ''       | 'CH1334J1E00'     |'C0201'| '(SMC0201AW)'                                                        | '330PF'    | '25V'         | '5%'     | 'DISCRETE' | 'CAP CHIP 330P 25V(+-5%,X7R,0201)'                             | 'CHIP0201'     | ''          | ''   | '20140707'
 '330PF'    | '25V'   | '5%'      | 'C0201'     | 'EMPTY'   | 'CH1334J1E00'(!)   = ''              | ''                 | ''       | 'CH1334J1E00'     |'C0201'| '(SMC0201AW)'                                                        | 'NA'       | '25V'         | '5%'     | 'IO'       | 'CAP CHIP 330P 25V(+-5%,X7R,0201)'                             | 'CHIP0201'     | ''          | ''   | '20140707'
 '22UF'     | '10V'   | '10%'     | 'C1206'     | 'X7R'     | 'CH6222K1200'(!)   = 'End of Design' | 'Comp-Approve'     | ''       | 'CH6222K1200'     |'C1206_H76'| '(SMC1206AW)'                                                        | '22UF'     | '10V'         | '10%'    | 'DISCRETE' | 'CAP CHIP 22U 10V(+-10%. X7R.1206)H1.6'                        | 'CHIP1206'     | ''          | ''   | '20140711'
 '22UF'     | '10V'   | '10%'     | 'C1206'     | 'EMPTY'   | 'CH6222K1200'(!)   = 'End of Design' | 'Comp-Approve'     | ''       | 'CH6222K1200'     |'C1206_H76'| '(SMC1206AW)'                                                        | 'NA'       | '10V'         | '10%'    | 'IO'       | 'CAP CHIP 22U 10V(+-10%. X7R.1206)H1.6'                        | 'CHIP1206'     | ''          | ''   | '20140711'
 '22UF'     | '6.3V'  | '20%'     | 'C0805'     | 'X6S'     | 'CH6221MEA02'(!)   = ''              | ''                 | 'SELASS' | 'CH6221MEA02'     |'C0805_H61'| '(SMC0805AW)'                                                        | '22UF'     | '6.3V'        | '20%'    | 'DISCRETE' | 'CAP CHIP 22U 6.3V(+-20%,X6S,0805)SELASS'                      | 'CHIP0805'     | ''          | ''   | '20140714'
 '22UF'     | '6.3V'  | '20%'     | 'C0805'     | 'EMPTY'   | 'CH6221MEA02'(!)   = ''              | ''                 | 'SELASS' | 'CH6221MEA02'     |'C0805_H61'| '(SMC0805AW)'                                                        | 'NA'       | '6.3V'        | '20%'    | 'IO'       | 'CAP CHIP 22U 6.3V(+-20%,X6S,0805)SELASS'                      | 'CHIP0805'     | ''          | ''   | '20140714'
 '1000PF'   | '2000V' | '10%'     | 'THLF'      | 'MEF'     | 'CD2100FKD00'(!)   = ''              | ''                 | ''       | 'CD2100FKD00'     |'EC591_R158X709_394'| '(EC591_R158X709_394)'                                               | '1000PF'   | '2000V'       | '10%'    | 'DISCRETE' | 'CAP MYLAR DIP 1000P 2000V(+-10%,P15)'                         | 'DIP'          | ''          | ''   | '20140725'
 '1000PF'   | '2000V' | '10%'     | 'THLF'      | 'EMPTY'   | 'CD2100FKD00'(!)   = ''              | ''                 | ''       | 'CD2100FKD00'     |'EC591_R158X709_394'| '(EC591_R158X709_394)'                                               | 'NA'       | '2000V'       | '10%'    | 'IO'       | 'CAP MYLAR DIP 1000P 2000V(+-10%,P15)'                         | 'DIP'          | ''          | ''   | '20140725'
 '1PF'      | '50V'   | '0.05P'   | 'C0402'     | 'COG'     | 'CH-106T0B00'(!)   = ''              | ''                 | ''       | 'CH-106T0B00'     |'C0402'| '(C0402-0201)'                                                       | '1PF'      | '50V'         | '0.05P'  | 'DISCRETE' | 'CAP CHIP 1P 50V(+-0.05P,COG,0402)'                            | 'CHIP0402'     | ''          | ''   | '20140812'
 '1PF'      | '50V'   | '0.05P'   | 'C0402'     | 'EMPTY'   | 'CH-106T0B00'(!)   = ''              | ''                 | ''       | 'CH-106T0B00'     |'C0402'| '(C0402-0201)'                                                       | 'NA'       | '50V'         | '0.05P'  | 'IO'       | 'CAP CHIP 1P 50V(+-0.05P,COG,0402)'                            | 'CHIP0402'     | ''          | ''   | '20140812'
 '18NF'     | '100V'  | '10%'     | 'C0603'     | 'X7R'     | 'CH3188K1900'(!)   = ''              | ''                 | ''       | 'CH3188K1900'     |'C0603'| '(SMC0603AW)'                                                        | '18NF'     | '100V'        | '10%'    | 'DISCRETE' | 'CAP CHIP 18NF 100V(+-10%,X7R,0603)'                           | 'CHIP0603'     | ''          | ''   | '20140813'
 '18NF'     | '100V'  | '10%'     | 'C0603'     | 'EMPTY'   | 'CH3188K1900'(!)   = ''              | ''                 | ''       | 'CH3188K1900'     |'C0603'| '(SMC0603AW)'                                                        | 'NA'       | '100V'        | '10%'    | 'IO'       | 'CAP CHIP 18NF 100V(+-10%,X7R,0603)'                           | 'CHIP0603'     | ''          | ''   | '20140813'
 '0.39UF'   | '10V'   | '10%'     | 'C0402'     | 'X5R'     | 'CH4392K9B00'(!)   = 'End of Design' | 'Comp-Release Qty' | ''       | 'CH4392K9B00'     |'C0402'| '(C0402-0201)'                                                       | '0.39UF'   | '10V'         | '10%'    | 'DISCRETE' | 'CAP CHIP 0.39UF 10V(+-10%,X5R,0402)'                          | 'CHIP0402'     | ''          | ''   | '20140813'
 '0.39UF'   | '10V'   | '10%'     | 'C0402'     | 'EMPTY'   | 'CH4392K9B00'(!)   = 'End of Design' | 'Comp-Release Qty' | ''       | 'CH4392K9B00'     |'C0402'| '(C0402-0201)'                                                       | 'NA'       | '10V'         | '10%'    | 'IO'       | 'CAP CHIP 0.39UF 10V(+-10%,X5R,0402)'                          | 'CHIP0402'     | ''          | ''   | '20140813'
 '0.47UF'   | '50V'   | '10%'     | 'C0603'     | 'X5R'     | 'CH4476K9901'(!)   = 'End of Design' | 'Comp-Approve'     | ''       | 'CH4476K9901'     |'C0603'| '(SMC0603AW)'                                                        | '0.47UF'   | '50V'         | '10%'    | 'DISCRETE' | 'CAP CHIP 0.47UF 50V(10%,X5R,0603)'                            | 'CHIP0603'     | ''          | ''   | '20140817'
 '0.47UF'   | '50V'   | '10%'     | 'C0603'     | 'EMPTY'   | 'CH4476K9901'(!)   = 'End of Design' | 'Comp-Approve'     | ''       | 'CH4476K9901'     |'C0603'| '(SMC0603AW)'                                                        | 'NA'       | '50V'         | '10%'    | 'IO'       | 'CAP CHIP 0.47UF 50V(10%,X5R,0603)'                            | 'CHIP0603'     | ''          | ''   | '20140817'
 '0.01UF'   | '25V'   | '5%'      | 'C0402'     | 'X7R'     | 'CH3104J1B00'(!)   = ''              | ''                 | ''       | 'CH3104J1B00'     |'C0402'| '(C0402-0201)'                                                       | '0.01UF'   | '25V'         | '5%'     | 'DISCRETE' | 'CAP CHIP 0.01U 25V (+-5%,X7R,0402)'                           | 'CHIP0402'     | ''          | ''   | '20140819'
 '0.01UF'   | '25V'   | '5%'      | 'C0402'     | 'EMPTY'   | 'CH3104J1B00'(!)   = ''              | ''                 | ''       | 'CH3104J1B00'     |'C0402'| '(C0402-0201)'                                                       | 'NA'       | '25V'         | '5%'     | 'IO'       | 'CAP CHIP 0.01U 25V (+-5%,X7R,0402)'                           | 'CHIP0402'     | ''          | ''   | '20140819'
 '22UF'     | '25V'   | '20%'     | 'C0805'     | 'X5R'     | 'CH6224M9A00'(!)   = ''              | ''                 | ''       | 'CH6224M9A00'     |'C0805_H61'| '(SMC0805AW)'                                                        | '22UF'     | '25V'         | '20%'    | 'DISCRETE' | 'CAP CHIP 22U 25V(+-20%,X5R,0805)'                             | 'CHIP0805'     | ''          | ''   | '20140819'
 '22UF'     | '25V'   | '20%'     | 'C0805'     | 'EMPTY'   | 'CH6224M9A00'(!)   = ''              | ''                 | ''       | 'CH6224M9A00'     |'C0805_H61'| '(SMC0805AW)'                                                        | 'NA'       | '25V'         | '20%'    | 'IO'       | 'CAP CHIP 22U 25V(+-20%,X5R,0805)'                             | 'CHIP0805'     | ''          | ''   | '20140819'
 '100UF'    | '10V'   | '20%'     | 'C1206'     | 'X5R'     | 'CH7102M9201'(!)   = 'End of Design' | 'Comp-Approve'     | ''       | 'CH7102M9201'     |'C1206_H76'| '(SMC1206AW)'                                                        | '100UF'    | '10V'         | '20%'    | 'DISCRETE' | 'CAP CHIP 100U 10V(+-20%,X5R,3216)'                            | 'CHIP1206'     | ''          | ''   | '20140819'
 '100UF'    | '10V'   | '20%'     | 'C1206'     | 'EMPTY'   | 'CH7102M9201'(!)   = 'End of Design' | 'Comp-Approve'     | ''       | 'CH7102M9201'     |'C1206_H76'| '(SMC1206AW)'                                                        | 'NA'       | '10V'         | '20%'    | 'IO'       | 'CAP CHIP 100U 10V(+-20%,X5R,3216)'                            | 'CHIP1206'     | ''          | ''   | '20140819'
 '10UF'     | '35V'   | '10%'     | 'C1206'     | 'X7R'     | 'CH6105K1200'(!)   = 'End of Design' | 'Comp-Approve'     | ''       | 'CH6105K1200'     |'C1206_H76'| '(SMC1206AW)'                                                        | '10UF'     | '35V'         | '10%'    | 'DISCRETE' | 'CAP CHIP 10U 35V(+-10%.X7R.1206)H1.6'                         | 'CHIP1206'     | ''          | ''   | '20140826'
 '10UF'     | '35V'   | '10%'     | 'C1206'     | 'EMPTY'   | 'CH6105K1200'(!)   = 'End of Design' | 'Comp-Approve'     | ''       | 'CH6105K1200'     |'C1206_H76'| '(SMC1206AW)'                                                        | 'NA'       | '35V'         | '10%'    | 'IO'       | 'CAP CHIP 10U 35V(+-10%.X7R.1206)H1.6'                         | 'CHIP1206'     | ''          | ''   | '20140826'
 '1UF'      | '16V'   | '10%'     | 'C0402'     | 'X6S'     | 'CH5103KEB01'(!)   = ''              | ''                 | ''       | 'CH5103KEB01'     |'C0402'| '(C0402_OCTAGONXA,C0402-0201)'                                       | '1UF'      | '16V'         | '10%'    | 'DISCRETE' | 'CAP CHIP 1UF 16V(10%,X6S,0402)'                               | 'CHIP0402'     | ''          | ''   | '20140828'
 '1UF'      | '16V'   | '10%'     | 'C0402'     | 'EMPTY'   | 'CH5103KEB01'(!)   = ''              | ''                 | ''       | 'CH5103KEB01'     |'C0402'| '(C0402_OCTAGONXA,C0402-0201)'                                       | 'NA'       | '16V'         | '10%'    | 'IO'       | 'CAP CHIP 1UF 16V(10%,X6S,0402)'                               | 'CHIP0402'     | ''          | ''   | '20140828'
 '10UF'     | '6.3V'  | '10%'     | 'C0805'     | 'X6S'     | 'CH6101KEA00'(!)   = 'End of Design' | 'Comp-Approve'     | ''       | 'CH6101KEA00'     |'C0805_H61'| '(SMC0805AW)'                                                        | '10UF'     | '6.3V'        | '10%'    | 'DISCRETE' | 'CAP CHIP 10UF,6.3V (+-10%,X6S,0805)'                          | 'CHIP0805'     | ''          | ''   | '20140829'
 '10UF'     | '6.3V'  | '10%'     | 'C0805'     | 'EMPTY'   | 'CH6101KEA00'(!)   = 'End of Design' | 'Comp-Approve'     | ''       | 'CH6101KEA00'     |'C0805_H61'| '(SMC0805AW)'                                                        | 'NA'       | '6.3V'        | '10%'    | 'IO'       | 'CAP CHIP 10UF,6.3V (+-10%,X6S,0805)'                          | 'CHIP0805'     | ''          | ''   | '20140829'
 '1UF'      | '6.3V'  | '10%'     | 'C0402'     | 'X6S'     | 'CH5101KEB00'(!)   = 'End of Design' | 'Comp-Approve'     | ''       | 'CH5101KEB00'     |'C0402'| '(C0402-0201)'                                                       | '1UF'      | '6.3V'        | '10%'    | 'DISCRETE' | 'CAP CHIP 1U 6.3V(+-10%,X6S,0402)'                             | 'CHIP0402'     | ''          | ''   | '20140829'
 '1UF'      | '6.3V'  | '10%'     | 'C0402'     | 'EMPTY'   | 'CH5101KEB00'(!)   = 'End of Design' | 'Comp-Approve'     | ''       | 'CH5101KEB00'     |'C0402'| '(C0402-0201)'                                                       | 'NA'       | '6.3V'        | '10%'    | 'IO'       | 'CAP CHIP 1U 6.3V(+-10%,X6S,0402)'                             | 'CHIP0402'     | ''          | ''   | '20140829'
 '100UF'    | '6.3V'  | '20%'     | 'C1206'     | 'X6T'     | 'CH7101MH200'(!)   = 'End of Design' | 'Comp-Approve'     | ''       | 'CH7101MH200'     |'C1206_H66'| '(SMC1206AW)'                                                        | '100UF'    | '6.3V'        | '20%'    | 'DISCRETE' | 'CAP CHIP 100U 6.3V(+-20%,X6T,1206)H1.6'                       | 'CHIP1206'     | ''          | ''   | '20140829'
 '100UF'    | '6.3V'  | '20%'     | 'C1206'     | 'EMPTY'   | 'CH7101MH200'(!)   = 'End of Design' | 'Comp-Approve'     | ''       | 'CH7101MH200'     |'C1206_H66'| '(SMC1206AW)'                                                        | 'NA'       | '6.3V'        | '20%'    | 'IO'       | 'CAP CHIP 100U 6.3V(+-20%,X6T,1206)H1.6'                       | 'CHIP1206'     | ''          | ''   | '20140829'
 '4.7UF'    | '25V'   | '10%'     | 'C0805'     | 'X7R'     | 'TH5474K1A00'(!)   = ''              | ''                 | 'EMSSEL' | 'TH5474K1A00'     |'C0805_H61'| '(SMC0805AW)'                                                        | '4.7UF'    | '25V'         | '10%'    | 'DISCRETE' | 'CAP CHIP 4.7U 25V(+-10%,X7R,0805)EMS SEL'                     | 'CHIP0805'     | ''          | ''   | '20140912'
 '4.7UF'    | '25V'   | '10%'     | 'C0805'     | 'EMPTY'   | 'TH5474K1A00'(!)   = ''              | ''                 | 'EMSSEL' | 'TH5474K1A00'     |'C0805_H61'| '(SMC0805AW)'                                                        | 'NA'       | '25V'         | '10%'    | 'IO'       | 'CAP CHIP 4.7U 25V(+-10%,X7R,0805)EMS SEL'                     | 'CHIP0805'     | ''          | ''   | '20140912'
 '1000PF'   | '200V'  | '10%'     | 'C1206'     | 'X7R'     | 'CH210CK1200'(!)   = ''              | ''                 | ''       | 'CH210CK1200'     |'C1206_H42'| '(SMC1206AW)'                                                        | '1000PF'   | '200V'        | '10%'    | 'DISCRETE' | 'CAP CHIP 1000PF 200V(+-10%,X7R,1206)H0.8'                     | 'CHIP1206'     | ''          | ''   | '20140930'
 '1000PF'   | '200V'  | '10%'     | 'C1206'     | 'EMPTY'   | 'CH210CK1200'(!)   = ''              | ''                 | ''       | 'CH210CK1200'     |'C1206_H42'| '(SMC1206AW)'                                                        | 'NA'       | '200V'        | '10%'    | 'IO'       | 'CAP CHIP 1000PF 200V(+-10%,X7R,1206)H0.8'                     | 'CHIP1206'     | ''          | ''   | '20140930'
 '0.47UF'   | '10V'   | '10%'     | 'C0402'     | 'X7R'     | 'CH4472K1B00'(!)   = 'End of Design' | 'Comp-Approve'     | ''       | 'CH4472K1B00'     |'C0402'| '(C0402_OCTAGONXA,C0402-0201)'                                       | '0.47UF'   | '10V'         | '10%'    | 'DISCRETE' | 'CAP CHIP 0.47UF 10V(+-10%,X7R,0402)'                          | 'CHIP0402'     | ''          | ''   | '20141003'
 '0.47UF'   | '10V'   | '10%'     | 'C0402'     | 'EMPTY'   | 'CH4472K1B00'(!)   = 'End of Design' | 'Comp-Approve'     | ''       | 'CH4472K1B00'     |'C0402'| '(C0402_OCTAGONXA,C0402-0201)'                                       | 'NA'       | '10V'         | '10%'    | 'IO'       | 'CAP CHIP 0.47UF 10V(+-10%,X7R,0402)'                          | 'CHIP0402'     | ''          | ''   | '20141003'
 '0.39UF'   | '10V'   | '10%'     | 'C0603'     | 'X7R'     | 'CH4392K1900'(!)   = 'End of Design' | 'P/N Release'      | ''       | 'CH4392K1900'     |'C0603'| '(SMC0603AW)'                                                        | '0.39UF'   | '10V'         | '10%'    | 'DISCRETE' | 'CAP CHIP 0.39U 10V(+-10%,X7R,0603)'                           | 'CHIP0603'     | ''          | ''   | '20141016'
 '0.39UF'   | '10V'   | '10%'     | 'C0603'     | 'EMPTY'   | 'CH4392K1900'(!)   = 'End of Design' | 'P/N Release'      | ''       | 'CH4392K1900'     |'C0603'| '(SMC0603AW)'                                                        | 'NA'       | '10V'         | '10%'    | 'IO'       | 'CAP CHIP 0.39U 10V(+-10%,X7R,0603)'                           | 'CHIP0603'     | ''          | ''   | '20141016'
 '22UF'     | '35V'   | '20%'     | 'C0805'     | 'X5R'     | 'CH6225M9A00'(!)   = 'End of Design' | 'Comp-Approve'     | ''       | 'CH6225M9A00'     |'C0805_H61'| '(SMC0805AW)'                                                        | '22UF'     | '35V'         | '20%'    | 'DISCRETE' | 'CAP CHIP 22UF 35V(+-20%,X5R,0805)'                            | 'CHIP0805'     | ''          | ''   | '20141016'
 '22UF'     | '35V'   | '20%'     | 'C0805'     | 'EMPTY'   | 'CH6225M9A00'(!)   = 'End of Design' | 'Comp-Approve'     | ''       | 'CH6225M9A00'     |'C0805_H61'| '(SMC0805AW)'                                                        | 'NA'       | '35V'         | '20%'    | 'IO'       | 'CAP CHIP 22UF 35V(+-20%,X5R,0805)'                            | 'CHIP0805'     | ''          | ''   | '20141016'
 '220UF'    | '4V'    | '20%'     | 'C1206'     | 'X5R'     | 'CH722KM9200'(!)   = 'End of Design' | 'Comp-Approve'     | ''       | 'CH722KM9200'     |'C1206_H76'| '(SMC1206AW)'                                                        | '220UF'    | '4V'          | '20%'    | 'DISCRETE' | 'CAP CHIP 220UF 4V(+-20%,X5R,1206)'                            | 'CHIP1206'     | ''          | ''   | '20141103'
 '220UF'    | '4V'    | '20%'     | 'C1206'     | 'EMPTY'   | 'CH722KM9200'(!)   = 'End of Design' | 'Comp-Approve'     | ''       | 'CH722KM9200'     |'C1206_H76'| '(SMC1206AW)'                                                        | 'NA'       | '4V'          | '20%'    | 'IO'       | 'CAP CHIP 220UF 4V(+-20%,X5R,1206)'                            | 'CHIP1206'     | ''          | ''   | '20141103'
 '22UF'     | '10V'   | '10%'     | 'C0805'     | 'X6S'     | 'CH6222KEA00'(!)   = 'End of Design' | 'Comp-Release Qty' | ''       | 'CH6222KEA00'     |'C0805_H61'| '(SMC0805AW)'                                                        | '22UF'     | '10V'         | '10%'    | 'DISCRETE' | 'CAP CHIP 22U 10V(+-10%,X6S,0805)'                             | 'CHIP0805'     | ''          | ''   | '20141127'
 '22UF'     | '10V'   | '10%'     | 'C0805'     | 'EMPTY'   | 'CH6222KEA00'(!)   = 'End of Design' | 'Comp-Release Qty' | ''       | 'CH6222KEA00'     |'C0805_H61'| '(SMC0805AW)'                                                        | 'NA'       | '10V'         | '10%'    | 'IO'       | 'CAP CHIP 22U 10V(+-10%,X6S,0805)'                             | 'CHIP0805'     | ''          | ''   | '20141127'
 '22UF'     | '10V'   | '20%'     | 'C0805'     | 'X7S'     | 'CH6222M1A00'(!)   = 'End of Design' | 'Comp-Release Qty' | ''       | 'CH6222M1A00'     |'C0805_H61'| '(SMC0805AW)'                                                        | '22UF'     | '10V'         | '20%'    | 'DISCRETE' | 'CAP CHIP 22U 10V(+-20%,X7S,0805)'                             | 'CHIP0805'     | ''          | ''   | '20141127'
 '22UF'     | '10V'   | '20%'     | 'C0805'     | 'EMPTY'   | 'CH6222M1A00'(!)   = 'End of Design' | 'Comp-Release Qty' | ''       | 'CH6222M1A00'     |'C0805_H61'| '(SMC0805AW)'                                                        | 'NA'       | '10V'         | '20%'    | 'IO'       | 'CAP CHIP 22U 10V(+-20%,X7S,0805)'                             | 'CHIP0805'     | ''          | ''   | '20141127'
 '4.7UF'    | '25V'   | '10%'     | 'C0603'     | 'X6S'     | 'CH-474KE900'(!)   = ''              | 'End of Life'      | ''       | 'CH-474KE900'     |'C0603_EOL'| '(SMC0603AW)'                                                        | '4.7UF'    | '25V'         | '10%'    | 'DISCRETE' | 'CAP CHIP 4.7UF 25V(+-10%,X6S,0603)'                           | 'CHIP0603'     | ''          | ''   | '20141212'
 '4.7UF'    | '25V'   | '10%'     | 'C0603'     | 'EMPTY'   | 'CH-474KE900'(!)   = ''              | 'End of Life'      | ''       | 'CH-474KE900'     |'C0603_EOL'| '(SMC0603AW)'                                                        | 'NA'       | '25V'         | '10%'    | 'IO'       | 'CAP CHIP 4.7UF 25V(+-10%,X6S,0603)'                           | 'CHIP0603'     | ''          | ''   | '20141212'
 '2PF'      | '50V'   | '0.05PF'  | 'C0402'     | 'C0G'     | 'CH-206T0B00'(!)   = ''              | ''                 | ''       | 'CH-206T0B00'     |'C0402'| '(C0402-0201)'                                                       | '2PF'      | '50V'         | '0.05PF' | 'DISCRETE' | 'CAP CHIP 2P 50V(+-0.05PF,C0G,0402)'                           | 'CHIP0402'     | ''          | ''   | '20141225'
 '2PF'      | '50V'   | '0.05PF'  | 'C0402'     | 'EMPTY'   | 'CH-206T0B00'(!)   = ''              | ''                 | ''       | 'CH-206T0B00'     |'C0402'| '(C0402-0201)'                                                       | 'NA'       | '50V'         | '0.05PF' | 'IO'       | 'CAP CHIP 2P 50V(+-0.05PF,C0G,0402)'                           | 'CHIP0402'     | ''          | ''   | '20141225'
 '330PF'    | '50V'   | '10%'     | 'C0402'     | 'X7R'     | 'CH13306KB11'(!)   = ''              | 'End of Life'      | ''       | 'CH13306KB11'     |'C0402_EOL'| '(C0402-0201)'                                                       | '330PF'    | '50V'         | '10%'    | 'DISCRETE' | 'CAP CHIP 330P 50V(+-10%.X7R.0402)'                            | 'CHIP0402'     | ''          | ''   | '20140116'
 '330PF'    | '50V'   | '10%'     | 'C0402'     | 'EMPTY'   | 'CH13306KB11'(!)   = ''              | 'End of Life'      | ''       | 'CH13306KB11'     |'C0402_EOL'| '(C0402-0201)'                                                       | 'NA'       | '50V'         | '10%'    | 'IO'       | 'CAP CHIP 330P 50V(+-10%.X7R.0402)'                            | 'CHIP0402'     | ''          | ''   | '20140116'
 '10UF'     | '16V'   | '20%'     | 'C0603'     | 'X6S'     | 'CH6103ME902'(!)   = ''              | ''                 | ''       | 'CH6103ME902'     |'C0603'| '(SMC0603AW)'                                                        | '10UF'     | '16V'         | '20%'    | 'DISCRETE' | 'CAP CHIP 10U 16V(+-20%,X6S,0603)'                             | 'CHIP0603'     | ''          | ''   | '20140116'
 '10UF'     | '16V'   | '20%'     | 'C0603'     | 'EMPTY'   | 'CH6103ME902'(!)   = ''              | ''                 | ''       | 'CH6103ME902'     |'C0603'| '(SMC0603AW)'                                                        | 'NA'       | '16V'         | '20%'    | 'IO'       | 'CAP CHIP 10U 16V(+-20%,X6S,0603)'                             | 'CHIP0603'     | ''          | ''   | '20140116'
 '0.068UF'  | '50V'   | '10%'     | 'C0603'     | 'X7R'     | 'CH3686K1901'(!)   = 'End of Design' | 'Comp-Approve'     | ''       | 'CH3686K1901'     |'C0603'| '(SMC0603AW)'                                                        | '0.068UF'  | '50V'         | '10%'    | 'DISCRETE' | 'CAP CHIP 0.068UF 50V(10%,X7R,0603)'                           | 'CHIP0603'     | ''          | ''   | '20140119'
 '0.068UF'  | '50V'   | '10%'     | 'C0603'     | 'EMPTY'   | 'CH3686K1901'(!)   = 'End of Design' | 'Comp-Approve'     | ''       | 'CH3686K1901'     |'C0603'| '(SMC0603AW)'                                                        | 'NA'       | '50V'         | '10%'    | 'IO'       | 'CAP CHIP 0.068UF 50V(10%,X7R,0603)'                           | 'CHIP0603'     | ''          | ''   | '20140119'
 '1UF'      | '6.3V'  | '10%'     | '0402'      | 'X5R'     | 'CH5101K9B01'(!)   = 'End of Design' | 'Comp-Release Qty' | ''       | 'CH5101K9B01'     |'C0402'| '(C0402_OCTAGONXA,C0402-0201)'                                       | '1UF'      | '6.3V'        | '10%'    | 'DISCRETE' | 'CAP CHIP 1U 6.3V(+-10%,X5R,0402)'                             | 'CHIP0402'     | ''          | ''   | '20150209'
 '1UF'      | '6.3V'  | '10%'     | '0402'      | 'EMPTY'   | 'CH5101K9B01'(!)   = 'End of Design' | 'Comp-Release Qty' | ''       | 'CH5101K9B01'     |'C0402'| '(C0402_OCTAGONXA,C0402-0201)'                                       | 'NA'       | '6.3V'        | '10%'    | 'IO'       | 'CAP CHIP 1U 6.3V(+-10%,X5R,0402)'                             | 'CHIP0402'     | ''          | ''   | '20150209'
 '10UF'     | '6.3V'  | '20%'     | '0603'      | 'X7R'     | 'CH6101M1904'(!)   = 'End of Design' | 'Comp-Approve'     | ''       | 'CH6101M1904'     |'C0603'| '(SMC0603AW)'                                                        | '10UF'     | '6.3V'        | '20%'    | 'DISCRETE' | 'CAP CHIP 10U.6.3V(+-20%.X7R.0603)'                            | 'CHIP0603'     | ''          | ''   | '20100917'
 '10UF'     | '6.3V'  | '20%'     | '0603'      | 'EMPTY'   | 'CH6101M1904'(!)   = 'End of Design' | 'Comp-Approve'     | ''       | 'CH6101M1904'     |'C0603'| '(SMC0603AW)'                                                        | 'NA'       | '6.3V'        | '20%'    | 'IO'       | 'CAP CHIP 10U.6.3V(+-20%.X7R.0603)'                            | 'CHIP0603'     | ''          | ''   | '20100917'
 '4.7UF'    | '10V'   | '10%'     | '0402'      | 'X5R'     | 'CH5472K9B00'(!)   = ''              | ''                 | ''       | 'CH5472K9B00'     |'C0402'| '(C0402-0201)'                                                       | '4.7UF'    | '10V'         | '10%'    | 'DISCRETE' | 'CAP CHIP 4.7U 10V(+-10%,X5R,0402)'                            | 'CHIP0402'     | ''          | ''   | '20150226'
 '4.7UF'    | '10V'   | '10%'     | '0402'      | 'EMPTY'   | 'CH5472K9B00'(!)   = ''              | ''                 | ''       | 'CH5472K9B00'     |'C0402'| '(C0402-0201)'                                                       | 'NA'       | '10V'         | '10%'    | 'IO'       | 'CAP CHIP 4.7U 10V(+-10%,X5R,0402)'                            | 'CHIP0402'     | ''          | ''   | '20150226'
 '22UF'     | '16V'   | '10%'     | '1206'      | 'X5R'     | 'CH6223K9201'(!)   = 'End of Design' | 'Comp-Approve'     | ''       | 'CH6223K9201'     |'C1206_H76'| '(SMC1206AW)'                                                        | '22UF'     | '16V'         | '10%'    | 'DISCRETE' | 'CAP CHIP 22U 16V(+-10%,X5R,1206)H1.6'                         | 'CHIP1206'     | ''          | ''   | '20150304'
 '22UF'     | '16V'   | '10%'     | '1206'      | 'EMPTY'   | 'CH6223K9201'(!)   = 'End of Design' | 'Comp-Approve'     | ''       | 'CH6223K9201'     |'C1206_H76'| '(SMC1206AW)'                                                        | 'NA'       | '16V'         | '10%'    | 'IO'       | 'CAP CHIP 22U 16V(+-10%,X5R,1206)H1.6'                         | 'CHIP1206'     | ''          | ''   | '20150304'
 '22UF'     | '10V'   | '20%'     | 'C0805'     | 'X6S'     | 'CH6222MEA00'(!)   = ''              | ''                 | ''       | 'CH6222MEA00'     |'C0805_H61'| '(SMC0805AW)'                                                        | '22UF'     | '10V'         | '20%'    | 'DISCRETE' | 'CAP CHIP 22U 10V(+-20%,X6S,0805)'                             | 'CHIP0805'     | ''          | ''   | '20150401'
 '22UF'     | '10V'   | '20%'     | 'C0805'     | 'EMPTY'   | 'CH6222MEA00'(!)   = ''              | ''                 | ''       | 'CH6222MEA00'     |'C0805_H61'| '(SMC0805AW)'                                                        | 'NA'       | '10V'         | '20%'    | 'IO'       | 'CAP CHIP 22U 10V(+-20%,X6S,0805)'                             | 'CHIP0805'     | ''          | ''   | '20150401'
 '1UF'      | '6.3V'  | '10%'     | '0402'      | 'X7R'     | 'CH5101K1B01'(!)   = ''              | ''                 | ''       | 'CH5101K1B01'     |'C0402'| '(C0402_OCTAGONXA,C0402-0201)'                                       | '1UF'      | '6.3V'        | '10%'    | 'DISCRETE' | 'CAP CHIP 1U,6.3V(+-10%,X7R,0402)'                             | 'CHIP0402'     | ''          | ''   | '20150410'
 '1UF'      | '6.3V'  | '10%'     | '0402'      | 'EMPTY'   | 'CH5101K1B01'(!)   = ''              | ''                 | ''       | 'CH5101K1B01'     |'C0402'| '(C0402_OCTAGONXA,C0402-0201)'                                       | 'NA'       | '6.3V'        | '10%'    | 'IO'       | 'CAP CHIP 1U,6.3V(+-10%,X7R,0402)'                             | 'CHIP0402'     | ''          | ''   | '20150410'
 '0.1UF'    | '16V'   | '10%'     | '0402'      | 'X7R'     | 'TMP_QCH4103K1B09'(!) = 'End of Design' | 'Comp-Approve'     | 'SELASS' | 'CH4103K1B09'     |'C0402'| '(C0402_OCTAGONXA,C0402-0201)'                                       | '0.1UF'    | '16V'         | '10%'    | 'DISCRETE' | 'CAP CHIP 0.1U 16V(10%,X7R,0402)SEL-ASS'                       | 'CHIP0402'     | ''          | ''   | '20150413'
 '0.1UF'    | '16V'   | '10%'     | '0402'      | 'EMPTY'   | 'TMP_QCH4103K1B09'(!) = 'End of Design' | 'Comp-Approve'     | 'SELASS' | 'CH4103K1B09'     |'C0402'| '(C0402_OCTAGONXA,C0402-0201)'                                       | 'NA'       | '16V'         | '10%'    | 'IO'       | 'CAP CHIP 0.1U 16V(10%,X7R,0402)SEL-ASS'                       | 'CHIP0402'     | ''          | ''   | '20150413'
 '0.22UF'   | '6.3V'  | '10%'     | '0201'      | 'X5R'     | 'CH4221K9E00'(!)   = ''              | ''                 | ''       | 'CH4221K9E00'     |'C0201'| '(SMC0201AW)'                                                        | '0.22UF'   | '6.3V'        | '10%'    | 'DISCRETE' | 'CAP CHIP 0.22UF 6.3V(+-10%,X5R,0201)'                         | 'CHIP0201'     | ''          | ''   | '20150511'
 '0.22UF'   | '6.3V'  | '10%'     | '0201'      | 'EMPTY'   | 'CH4221K9E00'(!)   = ''              | ''                 | ''       | 'CH4221K9E00'     |'C0201'| '(SMC0201AW)'                                                        | 'NA'       | '6.3V'        | '10%'    | 'IO'       | 'CAP CHIP 0.22UF 6.3V(+-10%,X5R,0201)'                         | 'CHIP0201'     | ''          | ''   | '20150511'
 '100UF'    | '4V'    | '20%'     | 'C0805'     | 'X6S'     | 'CH710KMEA00'(!)   = ''              | ''                 | ''       | 'CH710KMEA00'     |'C0805_H61'| '(SMC0805AW)'                                                        | '100UF'    | '4V'          | '20%'    | 'DISCRETE' | 'CAP CHIP 100U 4V(+-20%,X6S,0805)'                             | 'CHIP0805'     | ''          | ''   | '20150602'
 '100UF'    | '4V'    | '20%'     | 'C0805'     | 'EMPTY'   | 'CH710KMEA00'(!)   = ''              | ''                 | ''       | 'CH710KMEA00'     |'C0805_H61'| '(SMC0805AW)'                                                        | 'NA'       | '4V'          | '20%'    | 'IO'       | 'CAP CHIP 100U 4V(+-20%,X6S,0805)'                             | 'CHIP0805'     | ''          | ''   | '20150602'
 '2.2UF'    | '10V'   | '10%'     | 'C0402'     | 'X6S'     | 'CH5222KEB01'(!)   = ''              | ''                 | ''       | 'CH5222KEB01'     |'C0402'| '(C0402_OCTAGONXA,C0402-0201)'                                       | '2.2UF'    | '10V'         | '10%'    | 'DISCRETE' | 'CAP CHIP 2.2UF 10V(+-10%,X6S,0402)'                           | 'CHIP0402'     | ''          | ''   | '20150612'
 '2.2UF'    | '10V'   | '10%'     | 'C0402'     | 'EMPTY'   | 'CH5222KEB01'(!)   = ''              | ''                 | ''       | 'CH5222KEB01'     |'C0402'| '(C0402_OCTAGONXA,C0402-0201)'                                       | 'NA'       | '10V'         | '10%'    | 'IO'       | 'CAP CHIP 2.2UF 10V(+-10%,X6S,0402)'                           | 'CHIP0402'     | ''          | ''   | '20150612'
 '470PF'    | '50V'   | '5%'      | 'C0402'     | 'NPO'     | 'CH1476J0B04'(!)   = ''              | ''                 | ''       | 'CH1476J0B04'     |'C0402'| '(C0402-0201)'                                                       | '470PF'    | '50V'         | '5%'     | 'DISCRETE' | 'CAP CHIP 470P,50V(+-5%,NPO,0402)MUR'                          | 'CHIP0402'     | ''          | ''   | '20150612'
 '470PF'    | '50V'   | '5%'      | 'C0402'     | 'EMPTY'   | 'CH1476J0B04'(!)   = ''              | ''                 | ''       | 'CH1476J0B04'     |'C0402'| '(C0402-0201)'                                                       | 'NA'       | '50V'         | '5%'     | 'IO'       | 'CAP CHIP 470P,50V(+-5%,NPO,0402)MUR'                          | 'CHIP0402'     | ''          | ''   | '20150612'
 '4700PF'   | '50V'   | '10%'     | 'C0402'     | 'X7R'     | 'CH2476K1B04'(!)   = ''              | ''                 | ''       | 'CH2476K1B04'     |'C0402'| '(C0402-0201)'                                                       | '4700PF'   | '50V'         | '10%'    | 'DISCRETE' | 'CAP CHIP 4700PF 50V(10%,X7R,0402)MUR'                         | 'CHIP0402'     | ''          | ''   | '20150612'
 '4700PF'   | '50V'   | '10%'     | 'C0402'     | 'EMPTY'   | 'CH2476K1B04'(!)   = ''              | ''                 | ''       | 'CH2476K1B04'     |'C0402'| '(C0402-0201)'                                                       | 'NA'       | '50V'         | '10%'    | 'IO'       | 'CAP CHIP 4700PF 50V(10%,X7R,0402)MUR'                         | 'CHIP0402'     | ''          | ''   | '20150612'
 '0.1UF'    | '10V'   | '10%'     | 'C0402'     | 'X7R'     | 'CH4102K1B08'(!)   = 'End of Design' | 'Comp-Approve'     | ''       | 'CH4102K1B08'     |'C0402'| '(C0402-0201)'                                                       | '0.1UF'    | '10V'         | '10%'    | 'DISCRETE' | 'CAP CHIP 0.1U 10V(+-10%,X7R,0402)MUR'                         | 'CHIP0402'     | ''          | ''   | '20150612'
 '0.1UF'    | '10V'   | '10%'     | 'C0402'     | 'EMPTY'   | 'CH4102K1B08'(!)   = 'End of Design' | 'Comp-Approve'     | ''       | 'CH4102K1B08'     |'C0402'| '(C0402-0201)'                                                       | 'NA'       | '10V'         | '10%'    | 'IO'       | 'CAP CHIP 0.1U 10V(+-10%,X7R,0402)MUR'                         | 'CHIP0402'     | ''          | ''   | '20150612'
 '0.022UF'  | '16V'   | '10%'     | 'C0402'     | 'X7R'     | 'CH3223K1B11'(!)   = ''              | ''                 | ''       | 'CH3223K1B11'     |'C0402'| '(C0402-0201)'                                                       | '0.022UF'  | '16V'         | '10%'    | 'DISCRETE' | 'CAP CHIP 0.022U 16V(+-10%,X7R,0402)SAM'                       | 'CHIP0402'     | ''          | ''   | '20150612'
 '0.022UF'  | '16V'   | '10%'     | 'C0402'     | 'EMPTY'   | 'CH3223K1B11'(!)   = ''              | ''                 | ''       | 'CH3223K1B11'     |'C0402'| '(C0402-0201)'                                                       | 'NA'       | '16V'         | '10%'    | 'IO'       | 'CAP CHIP 0.022U 16V(+-10%,X7R,0402)SAM'                       | 'CHIP0402'     | ''          | ''   | '20150612'
 '0.01UF'   | '16V'   | '10%'     | 'C0402'     | 'X7R'     | 'CH3103K1B17'(!)   = ''              | ''                 | ''       | 'CH3103K1B17'     |'C0402'| '(C0402-0201)'                                                       | '0.01UF'   | '16V'         | '10%'    | 'DISCRETE' | 'CAP CHIP 0.01U 16V,+-10%,X7R,0402)SAM'                        | 'CHIP0402'     | ''          | ''   | '20150612'
 '0.01UF'   | '16V'   | '10%'     | 'C0402'     | 'EMPTY'   | 'CH3103K1B17'(!)   = ''              | ''                 | ''       | 'CH3103K1B17'     |'C0402'| '(C0402-0201)'                                                       | 'NA'       | '16V'         | '10%'    | 'IO'       | 'CAP CHIP 0.01U 16V,+-10%,X7R,0402)SAM'                        | 'CHIP0402'     | ''          | ''   | '20150612'
 '2700PF'   | '50V'   | '10%'     | 'C0402'     | 'X7R'     | 'CH2276K1B07'(!)   = ''              | ''                 | ''       | 'CH2276K1B07'     |'C0402'| '(C0402-0201)'                                                       | '2700PF'   | '50V'         | '10%'    | 'DISCRETE' | 'CAP CHIP 2700P 50V(+-10%,X7R,0402)SAM'                        | 'CHIP0402'     | ''          | ''   | '20150612'
 '2700PF'   | '50V'   | '10%'     | 'C0402'     | 'EMPTY'   | 'CH2276K1B07'(!)   = ''              | ''                 | ''       | 'CH2276K1B07'     |'C0402'| '(C0402-0201)'                                                       | 'NA'       | '50V'         | '10%'    | 'IO'       | 'CAP CHIP 2700P 50V(+-10%,X7R,0402)SAM'                        | 'CHIP0402'     | ''          | ''   | '20150612'
 '470PF'    | '50V'   | '5%'      | 'C0402'     | 'NPO'     | 'CH1476J0B03'(!)   = ''              | ''                 | ''       | 'CH1476J0B03'     |'C0402'| '(C0402-0201)'                                                       | '470PF'    | '50V'         | '5%'     | 'DISCRETE' | 'CAP CHIP 470P,50V(+-5%,NPO,0402)SAM'                          | 'CHIP0402'     | ''          | ''   | '20150612'
 '470PF'    | '50V'   | '5%'      | 'C0402'     | 'EMPTY'   | 'CH1476J0B03'(!)   = ''              | ''                 | ''       | 'CH1476J0B03'     |'C0402'| '(C0402-0201)'                                                       | 'NA'       | '50V'         | '5%'     | 'IO'       | 'CAP CHIP 470P,50V(+-5%,NPO,0402)SAM'                          | 'CHIP0402'     | ''          | ''   | '20150612'
 '47PF'     | '50V'   | '5%'      | 'C0402'     | 'NPO'     | 'CH0476J0B11'(!)   = 'End of Design' | 'Comp-Approve'     | ''       | 'CH0476J0B11'     |'C0402'| '(C0402-0201)'                                                       | '47PF'     | '50V'         | '5%'     | 'DISCRETE' | 'CAP CHIP 47P 50V(+-5%,NPO,0402)SAM'                           | 'CHIP0402'     | ''          | ''   | '20150612'
 '47PF'     | '50V'   | '5%'      | 'C0402'     | 'EMPTY'   | 'CH0476J0B11'(!)   = 'End of Design' | 'Comp-Approve'     | ''       | 'CH0476J0B11'     |'C0402'| '(C0402-0201)'                                                       | 'NA'       | '50V'         | '5%'     | 'IO'       | 'CAP CHIP 47P 50V(+-5%,NPO,0402)SAM'                           | 'CHIP0402'     | ''          | ''   | '20150612'
 '0.22UF'   | '6.3V'  | '20%'     | 'C0201'     | 'X6S'     | 'CH4221MEE01'(!)   = ''              | ''                 | ''       | 'CH4221MEE01'     |'C0201'| '(SMC0201AW)'                                                        | '0.22UF'   | '6.3V'        | '20%'    | 'DISCRETE' | 'CAP CHIP 0.22UF 6.3V(20%,X6S,0201)'                           | 'CHIP0201'     | ''          | ''   | '20150612'
 '0.22UF'   | '6.3V'  | '20%'     | 'C0201'     | 'EMPTY'   | 'CH4221MEE01'(!)   = ''              | ''                 | ''       | 'CH4221MEE01'     |'C0201'| '(SMC0201AW)'                                                        | 'NA'       | '6.3V'        | '20%'    | 'IO'       | 'CAP CHIP 0.22UF 6.3V(20%,X6S,0201)'                           | 'CHIP0201'     | ''          | ''   | '20150612'
 '220UF'    | '4V'    | '20%'     | 'C1206'     | 'X6S'     | 'CH722KME200'(!)   = 'End of Design' | 'Comp-Approve'     | ''       | 'CH722KME200'     |'C1206_H66'| '(SMC1206AW)'                                                        | '220UF'    | '4V'          | '20%'    | 'DISCRETE' | 'CAP CHIP 220U 4V(+-20%,X6S,1206)'                             | 'CHIP1206'     | ''          | ''   | '20150612'
 '220UF'    | '4V'    | '20%'     | 'C1206'     | 'EMPTY'   | 'CH722KME200'(!)   = 'End of Design' | 'Comp-Approve'     | ''       | 'CH722KME200'     |'C1206_H66'| '(SMC1206AW)'                                                        | 'NA'       | '4V'          | '20%'    | 'IO'       | 'CAP CHIP 220U 4V(+-20%,X6S,1206)'                             | 'CHIP1206'     | ''          | ''   | '20150612'
 '2.2UF'    | '16V'   | '10%'     | 'C0603'     | 'X6S'     | 'CH5223KE902'(!)   = ''              | ''                 | ''       | 'CH5223KE902'     |'C0603'| '(SMC0603AW)'                                                        | '2.2UF'    | '16V'         | '10%'    | 'DISCRETE' | 'CAP CHIP 2.2U 16V(+-10%,X6S,0603)MUR'                         | 'CHIP0603'     | ''          | ''   | '20150612'
 '2.2UF'    | '16V'   | '10%'     | 'C0603'     | 'EMPTY'   | 'CH5223KE902'(!)   = ''              | ''                 | ''       | 'CH5223KE902'     |'C0603'| '(SMC0603AW)'                                                        | 'NA'       | '16V'         | '10%'    | 'IO'       | 'CAP CHIP 2.2U 16V(+-10%,X6S,0603)MUR'                         | 'CHIP0603'     | ''          | ''   | '20150612'
 '1UF'      | '10V'   | '10%'     | 'C0603'     | 'X7R'     | 'CH5102K1902'(!)   = 'End of Design' | 'Comp-Approve'     | ''       | 'CH5102K1902'     |'C0603'| '(SMC0603AW)'                                                        | '1UF'      | '10V'         | '10%'    | 'DISCRETE' | 'CAP CHIP 1U 10V(+-10%,X7R,0603)SAM'                           | 'CHIP0603'     | ''          | ''   | '20150612'
 '1UF'      | '10V'   | '10%'     | 'C0603'     | 'EMPTY'   | 'CH5102K1902'(!)   = 'End of Design' | 'Comp-Approve'     | ''       | 'CH5102K1902'     |'C0603'| '(SMC0603AW)'                                                        | 'NA'       | '10V'         | '10%'    | 'IO'       | 'CAP CHIP 1U 10V(+-10%,X7R,0603)SAM'                           | 'CHIP0603'     | ''          | ''   | '20150612'
 '10UF'     | '10V'   | '20%'     | 'C0603'     | 'X7R'     | 'CH6102M1900'(!)   = ''              | 'End of Life'      | ''       | 'CH6102M1900'     |'C0603_EOL'| '(SMC0603AW)'                                                        | '10UF'     | '10V'         | '20%'    | 'DISCRETE' | 'CAP CHIP 10U,10V(+-20%,X7R,0603)SAM'                          | 'CHIP0603'     | ''          | ''   | '20150612'
 '10UF'     | '10V'   | '20%'     | 'C0603'     | 'EMPTY'   | 'CH6102M1900'(!)   = ''              | 'End of Life'      | ''       | 'CH6102M1900'     |'C0603_EOL'| '(SMC0603AW)'                                                        | 'NA'       | '10V'         | '20%'    | 'IO'       | 'CAP CHIP 10U,10V(+-20%,X7R,0603)SAM'                          | 'CHIP0603'     | ''          | ''   | '20150612'
 '10UF'     | '10V'   | '20%'     | 'C0603'     | 'X7R'     | 'CH6102M1901'(!)   = ''              | 'End of Life'      | ''       | 'CH6102M1901'     |'C0603_EOL'| '(SMC0603AW)'                                                        | '10UF'     | '10V'         | '20%'    | 'DISCRETE' | 'CAP CHIP 10U,10V(+-20%,X7R,0603)MUR'                          | 'CHIP0603'     | ''          | ''   | '20150612'
 '10UF'     | '10V'   | '20%'     | 'C0603'     | 'EMPTY'   | 'CH6102M1901'(!)   = ''              | 'End of Life'      | ''       | 'CH6102M1901'     |'C0603_EOL'| '(SMC0603AW)'                                                        | 'NA'       | '10V'         | '20%'    | 'IO'       | 'CAP CHIP 10U,10V(+-20%,X7R,0603)MUR'                          | 'CHIP0603'     | ''          | ''   | '20150612'
 '22UF'     | '4V'    | '20%'     | 'C0603'     | 'X6S'     | 'CH622KME905'(!)   = ''              | ''                 | ''       | 'CH622KME905'     |'C0603'| '(SMC0603AW)'                                                        | '22UF'     | '4V'          | '20%'    | 'DISCRETE' | 'CAP CHIP 22UF 4V(+-20%,X6S,0603)MUR'                          | 'CHIP0603'     | ''          | ''   | '20150612'
 '22UF'     | '4V'    | '20%'     | 'C0603'     | 'EMPTY'   | 'CH622KME905'(!)   = ''              | ''                 | ''       | 'CH622KME905'     |'C0603'| '(SMC0603AW)'                                                        | 'NA'       | '4V'          | '20%'    | 'IO'       | 'CAP CHIP 22UF 4V(+-20%,X6S,0603)MUR'                          | 'CHIP0603'     | ''          | ''   | '20150612'
 '1UF'      | '25V'   | '10%'     | 'C0402'     | 'X7R'     | 'CH-104K6B00'(!)   = 'End of Design' | 'End of Life'      | ''       | 'CH-104K6B00'     |'C0402_EOL'| '(C0402-0201)'                                                       | '1UF'      | '25V'         | '10%'    | 'DISCRETE' | 'CAP CHIP 1U 25V (+-10%,X7S,0402)'                             | 'CHIP0402'     | ''          | ''   | '20150612'
 '1UF'      | '25V'   | '10%'     | 'C0402'     | 'EMPTY'   | 'CH-104K6B00'(!)   = 'End of Design' | 'End of Life'      | ''       | 'CH-104K6B00'     |'C0402_EOL'| '(C0402-0201)'                                                       | 'NA'       | '25V'         | '10%'    | 'IO'       | 'CAP CHIP 1U 25V (+-10%,X7S,0402)'                             | 'CHIP0402'     | ''          | ''   | '20150612'
 '2.2UF'    | '10V'   | '10%'     | 'C0402'     | 'X7S'     | 'CH5222K6B00'(!)   = 'End of Design' | 'Comp-Approve'     | ''       | 'CH5222K6B00'     |'C0402'| '(C0402-0201)'                                                       | '2.2UF'    | '10V'         | '10%'    | 'DISCRETE' | 'CAP CHIP 2.2UF 10V(10%,X7S,0402)'                             | 'CHIP0402'     | ''          | ''   | '20150612'
 '2.2UF'    | '10V'   | '10%'     | 'C0402'     | 'EMPTY'   | 'CH5222K6B00'(!)   = 'End of Design' | 'Comp-Approve'     | ''       | 'CH5222K6B00'     |'C0402'| '(C0402-0201)'                                                       | 'NA'       | '10V'         | '10%'    | 'IO'       | 'CAP CHIP 2.2UF 10V(10%,X7S,0402)'                             | 'CHIP0402'     | ''          | ''   | '20150612'
 '0.22UF'   | '10V'   | '10%'     | 'C0402'     | 'X7R'     | 'CH4222K1B00'(!)   = 'End of Design' | 'Comp-Release Qty' | ''       | 'CH4222K1B00'     |'C0402'| '(C0402-0201)'                                                       | '0.22UF'   | '10V'         | '10%'    | 'DISCRETE' | 'CAP CHIP 0.22U 10V(+-10%,X7R,0402)'                           | 'CHIP0402'     | ''          | ''   | '20150612'
 '0.22UF'   | '10V'   | '10%'     | 'C0402'     | 'EMPTY'   | 'CH4222K1B00'(!)   = 'End of Design' | 'Comp-Release Qty' | ''       | 'CH4222K1B00'     |'C0402'| '(C0402-0201)'                                                       | 'NA'       | '10V'         | '10%'    | 'IO'       | 'CAP CHIP 0.22U 10V(+-10%,X7R,0402)'                           | 'CHIP0402'     | ''          | ''   | '20150612'
 '15PF'     | '50V'   | '5%'      | 'C0402'     | 'C0G'     | 'CH0156J0B07'(!)   = ''              | ''                 | ''       | 'CH0156J0B07'     |'C0402'| '(C0402-0201)'                                                       | '15PF'     | '50V'         | '5%'     | 'DISCRETE' | 'CAP CHIP 15P 50V(+-5% C0G 0402)MUR'                           | 'CHIP0402'     | ''          | ''   | '20150614'
 '15PF'     | '50V'   | '5%'      | 'C0402'     | 'EMPTY'   | 'CH0156J0B07'(!)   = ''              | ''                 | ''       | 'CH0156J0B07'     |'C0402'| '(C0402-0201)'                                                       | 'NA'       | '50V'         | '5%'     | 'IO'       | 'CAP CHIP 15P 50V(+-5% C0G 0402)MUR'                           | 'CHIP0402'     | ''          | ''   | '20150614'
 '18PF'     | '50V'   | '5%'      | 'C0402'     | 'C0G'     | 'CH0186J0B05'(!)   = ''              | ''                 | ''       | 'CH0186J0B05'     |'C0402'| '(C0402-0201)'                                                       | '18PF'     | '50V'         | '5%'     | 'DISCRETE' | 'CAP CHIP 18P 50V(+-5% C0G 0402)MUR'                           | 'CHIP0402'     | ''          | ''   | '20150614'
 '18PF'     | '50V'   | '5%'      | 'C0402'     | 'EMPTY'   | 'CH0186J0B05'(!)   = ''              | ''                 | ''       | 'CH0186J0B05'     |'C0402'| '(C0402-0201)'                                                       | 'NA'       | '50V'         | '5%'     | 'IO'       | 'CAP CHIP 18P 50V(+-5% C0G 0402)MUR'                           | 'CHIP0402'     | ''          | ''   | '20150614'
 '22PF'     | '50V'   | '5%'      | 'C0402'     | 'NPO'     | 'CH0226J0B16'(!)   = ''              | ''                 | ''       | 'CH0226J0B16'     |'C0402'| '(C0402-0201)'                                                       | '22PF'     | '50V'         | '5%'     | 'DISCRETE' | 'CAP CHIP 22P 50V(+-5%,NPO,0402)MUR'                           | 'CHIP0402'     | ''          | ''   | '20150614'
 '22PF'     | '50V'   | '5%'      | 'C0402'     | 'EMPTY'   | 'CH0226J0B16'(!)   = ''              | ''                 | ''       | 'CH0226J0B16'     |'C0402'| '(C0402-0201)'                                                       | 'NA'       | '50V'         | '5%'     | 'IO'       | 'CAP CHIP 22P 50V(+-5%,NPO,0402)MUR'                           | 'CHIP0402'     | ''          | ''   | '20150614'
 '100PF'    | '50V'   | '5%'      | 'C0402'     | 'NPO'     | 'CH1106J0B16'(!)   = ''              | ''                 | ''       | 'CH1106J0B16'     |'C0402'| '(C0402-0201)'                                                       | '100PF'    | '50V'         | '5%'     | 'DISCRETE' | 'CAP CHIP 100P 50V(+-5%,NPO,0402)MUR'                          | 'CHIP0402'     | ''          | ''   | '20150614'
 '100PF'    | '50V'   | '5%'      | 'C0402'     | 'EMPTY'   | 'CH1106J0B16'(!)   = ''              | ''                 | ''       | 'CH1106J0B16'     |'C0402'| '(C0402-0201)'                                                       | 'NA'       | '50V'         | '5%'     | 'IO'       | 'CAP CHIP 100P 50V(+-5%,NPO,0402)MUR'                          | 'CHIP0402'     | ''          | ''   | '20150614'
 '470PF'    | '50V'   | '10%'     | 'C0402'     | 'X7R'     | 'CH1476K1B11'(!)   = ''              | ''                 | ''       | 'CH1476K1B11'     |'C0402'| '(C0402-0201)'                                                       | '470PF'    | '50V'         | '10%'    | 'DISCRETE' | 'CAP CHIP 470P 50V(+-10%,X7R,0402)MUR'                         | 'CHIP0402'     | ''          | ''   | '20150614'
 '470PF'    | '50V'   | '10%'     | 'C0402'     | 'EMPTY'   | 'CH1476K1B11'(!)   = ''              | ''                 | ''       | 'CH1476K1B11'     |'C0402'| '(C0402-0201)'                                                       | 'NA'       | '50V'         | '10%'    | 'IO'       | 'CAP CHIP 470P 50V(+-10%,X7R,0402)MUR'                         | 'CHIP0402'     | ''          | ''   | '20150614'
 '1000PF'   | '50V'   | '5%'      | 'C0402'     | 'X7R'     | 'CH2106J1B04'(!)   = ''              | ''                 | ''       | 'CH2106J1B04'     |'C0402'| '(C0402-0201)'                                                       | '1000PF'   | '50V'         | '5%'     | 'DISCRETE' | 'CAP CHIP 1000P 50V(+-5%,X7R,0402)MUR'                         | 'CHIP0402'     | ''          | ''   | '20150614'
 '1000PF'   | '50V'   | '5%'      | 'C0402'     | 'EMPTY'   | 'CH2106J1B04'(!)   = ''              | ''                 | ''       | 'CH2106J1B04'     |'C0402'| '(C0402-0201)'                                                       | 'NA'       | '50V'         | '5%'     | 'IO'       | 'CAP CHIP 1000P 50V(+-5%,X7R,0402)MUR'                         | 'CHIP0402'     | ''          | ''   | '20150614'
 '1000PF'   | '16V'   | '10%'     | 'C0402'     | 'X7R'     | 'CH2103K1B03'(!)   = ''              | ''                 | ''       | 'CH2103K1B03'     |'C0402'| '(C0402_OCTAGONXA,C0402-0201)'                                       | '1000PF'   | '16V'         | '10%'    | 'DISCRETE' | 'CAP CHIP 1000PF 16V (+-10%,X7R,0402)MUR'                      | 'CHIP0402'     | ''          | ''   | '20150614'
 '1000PF'   | '16V'   | '10%'     | 'C0402'     | 'EMPTY'   | 'CH2103K1B03'(!)   = ''              | ''                 | ''       | 'CH2103K1B03'     |'C0402'| '(C0402_OCTAGONXA,C0402-0201)'                                       | 'NA'       | '16V'         | '10%'    | 'IO'       | 'CAP CHIP 1000PF 16V (+-10%,X7R,0402)MUR'                      | 'CHIP0402'     | ''          | ''   | '20150614'
 '1500PF'   | '50V'   | '10%'     | 'C0402'     | 'X7R'     | 'CH2156K1B08'(!)   = ''              | ''                 | ''       | 'CH2156K1B08'     |'C0402'| '(C0402-0201)'                                                       | '1500PF'   | '50V'         | '10%'    | 'DISCRETE' | 'CAP CHIP1500PF 50V(+-10%,X7R,0402)MUR'                        | 'CHIP0402'     | ''          | ''   | '20150614'
 '1500PF'   | '50V'   | '10%'     | 'C0402'     | 'EMPTY'   | 'CH2156K1B08'(!)   = ''              | ''                 | ''       | 'CH2156K1B08'     |'C0402'| '(C0402-0201)'                                                       | 'NA'       | '50V'         | '10%'    | 'IO'       | 'CAP CHIP1500PF 50V(+-10%,X7R,0402)MUR'                        | 'CHIP0402'     | ''          | ''   | '20150614'
 '2200PF'   | '50V'   | '10%'     | 'C0402'     | 'X7R'     | 'CH2226K1B06'(!)   = ''              | ''                 | ''       | 'CH2226K1B06'     |'C0402'| '(C0402-0201)'                                                       | '2200PF'   | '50V'         | '10%'    | 'DISCRETE' | 'CAP CHIP 2200P 50V(+-10%,X7R,0402)MUR'                        | 'CHIP0402'     | ''          | ''   | '20150614'
 '2200PF'   | '50V'   | '10%'     | 'C0402'     | 'EMPTY'   | 'CH2226K1B06'(!)   = ''              | ''                 | ''       | 'CH2226K1B06'     |'C0402'| '(C0402-0201)'                                                       | 'NA'       | '50V'         | '10%'    | 'IO'       | 'CAP CHIP 2200P 50V(+-10%,X7R,0402)MUR'                        | 'CHIP0402'     | ''          | ''   | '20150614'
 '4700P'    | '25V'   | '10%'     | 'C0402'     | 'X7R'     | 'CH2474K1B08'(!)   = ''              | ''                 | ''       | 'CH2474K1B08'     |'C0402'| '(C0402-0201)'                                                       | '4700P'    | '25V'         | '10%'    | 'DISCRETE' | 'CAP CHIP 4700P 25V(+-10%,X7R,0402)MUR'                        | 'CHIP0402'     | ''          | ''   | '20150614'
 '4700P'    | '25V'   | '10%'     | 'C0402'     | 'EMPTY'   | 'CH2474K1B08'(!)   = ''              | ''                 | ''       | 'CH2474K1B08'     |'C0402'| '(C0402-0201)'                                                       | 'NA'       | '25V'         | '10%'    | 'IO'       | 'CAP CHIP 4700P 25V(+-10%,X7R,0402)MUR'                        | 'CHIP0402'     | ''          | ''   | '20150614'
 '0.01UF'   | '25V'   | '10%'     | 'C0402'     | 'X7R'     | 'CH3104K1B11'(!)   = ''              | ''                 | ''       | 'CH3104K1B11'     |'C0402'| '(C0402-0201)'                                                       | '0.01UF'   | '25V'         | '10%'    | 'DISCRETE' | 'CAP CHIP 0.01U 25V(+-10%,X7R,0402)MUR'                        | 'CHIP0402'     | ''          | ''   | '20150614'
 '0.01UF'   | '25V'   | '10%'     | 'C0402'     | 'EMPTY'   | 'CH3104K1B11'(!)   = ''              | ''                 | ''       | 'CH3104K1B11'     |'C0402'| '(C0402-0201)'                                                       | 'NA'       | '25V'         | '10%'    | 'IO'       | 'CAP CHIP 0.01U 25V(+-10%,X7R,0402)MUR'                        | 'CHIP0402'     | ''          | ''   | '20150614'
 '0.015UF'  | '16V'   | '10%'     | 'C0402'     | 'X7R'     | 'CH3153K1B03'(!)   = ''              | ''                 | ''       | 'CH3153K1B03'     |'C0402'| '(C0402-0201)'                                                       | '0.015UF'  | '16V'         | '10%'    | 'DISCRETE' | 'CAP CHIP 0.015U 16V(+-10%.X7R.0402)MUR'                       | 'CHIP0402'     | ''          | ''   | '20150614'
 '0.015UF'  | '16V'   | '10%'     | 'C0402'     | 'EMPTY'   | 'CH3153K1B03'(!)   = ''              | ''                 | ''       | 'CH3153K1B03'     |'C0402'| '(C0402-0201)'                                                       | 'NA'       | '16V'         | '10%'    | 'IO'       | 'CAP CHIP 0.015U 16V(+-10%.X7R.0402)MUR'                       | 'CHIP0402'     | ''          | ''   | '20150614'
 '0.047UF'  | '10V'   | '10%'     | 'C0402'     | 'X7R'     | 'CH3472K1B04'(!)   = 'End of Design' | 'Comp-Approve'     | ''       | 'CH3472K1B04'     |'C0402'| '(C0402-0201)'                                                       | '0.047UF'  | '10V'         | '10%'    | 'DISCRETE' | 'CAP CHIP 0.047U 10V(+-10% X7R 0402)MUR'                       | 'CHIP0402'     | ''          | ''   | '20150614'
 '0.047UF'  | '10V'   | '10%'     | 'C0402'     | 'EMPTY'   | 'CH3472K1B04'(!)   = 'End of Design' | 'Comp-Approve'     | ''       | 'CH3472K1B04'     |'C0402'| '(C0402-0201)'                                                       | 'NA'       | '10V'         | '10%'    | 'IO'       | 'CAP CHIP 0.047U 10V(+-10% X7R 0402)MUR'                       | 'CHIP0402'     | ''          | ''   | '20150614'
 '0.047UF'  | '25V'   | '10%'     | 'C0402'     | 'X7R'     | 'CH3474K1B03'(!)   = ''              | ''                 | ''       | 'CH3474K1B03'     |'C0402'| '(C0402-0201)'                                                       | '0.047UF'  | '25V'         | '10%'    | 'DISCRETE' | 'CAP CHIP 0.047U 25V(+-10% X7R 0402)MUR'                       | 'CHIP0402'     | ''          | ''   | '20150614'
 '0.047UF'  | '25V'   | '10%'     | 'C0402'     | 'EMPTY'   | 'CH3474K1B03'(!)   = ''              | ''                 | ''       | 'CH3474K1B03'     |'C0402'| '(C0402-0201)'                                                       | 'NA'       | '25V'         | '10%'    | 'IO'       | 'CAP CHIP 0.047U 25V(+-10% X7R 0402)MUR'                       | 'CHIP0402'     | ''          | ''   | '20150614'
 '0.068UF'  | '16V'   | '10%'     | 'C0402'     | 'X7R'     | 'CH3683K1B02'(!)   = ''              | ''                 | ''       | 'CH3683K1B02'     |'C0402'| '(C0402-0201)'                                                       | '0.068UF'  | '16V'         | '10%'    | 'DISCRETE' | 'CAP CHIP 0.068UF 16V(+-10%,X7R 0402)MUR'                      | 'CHIP0402'     | ''          | ''   | '20150614'
 '0.068UF'  | '16V'   | '10%'     | 'C0402'     | 'EMPTY'   | 'CH3683K1B02'(!)   = ''              | ''                 | ''       | 'CH3683K1B02'     |'C0402'| '(C0402-0201)'                                                       | 'NA'       | '16V'         | '10%'    | 'IO'       | 'CAP CHIP 0.068UF 16V(+-10%,X7R 0402)MUR'                      | 'CHIP0402'     | ''          | ''   | '20150614'
 '0.1UF'    | '25V'   | '10%'     | 'C0402'     | 'X7R'     | 'CH4104K1B03'(!)   = 'End of Design' | 'Comp-Approve'     | ''       | 'CH4104K1B03'     |'C0402'| '(C0402_OCTAGONXA,C0402-0201,C0402_OCTAGONXA_BOUND22)'               | '0.1UF'    | '25V'         | '10%'    | 'DISCRETE' | 'CAP CHIP 0.1U 25V(+-10%,X7R,0402)MUR'                         | 'CHIP0402'     | ''          | ''   | '20150615'
 '0.1UF'    | '25V'   | '10%'     | 'C0402'     | 'EMPTY'   | 'CH4104K1B03'(!)   = 'End of Design' | 'Comp-Approve'     | ''       | 'CH4104K1B03'     |'C0402'| '(C0402_OCTAGONXA,C0402-0201,C0402_OCTAGONXA_BOUND22)'               | 'NA'       | '25V'         | '10%'    | 'IO'       | 'CAP CHIP 0.1U 25V(+-10%,X7R,0402)MUR'                         | 'CHIP0402'     | ''          | ''   | '20150615'
 '1UF'      | '16V'   | '10%'     | 'C0402'     | 'X6S'     | 'CH5103KEB03'(!)   = ''              | ''                 | ''       | 'CH5103KEB03'     |'C0402'| '(C0402_OCTAGONXA,C0402-0201)'                                       | '1UF'      | '16V'         | '10%'    | 'DISCRETE' | 'CAP CHIP 1UF 16V(10%,X6S,0402)MUR'                            | 'CHIP0402'     | ''          | ''   | '20150615'
 '1UF'      | '16V'   | '10%'     | 'C0402'     | 'EMPTY'   | 'CH5103KEB03'(!)   = ''              | ''                 | ''       | 'CH5103KEB03'     |'C0402'| '(C0402_OCTAGONXA,C0402-0201)'                                       | 'NA'       | '16V'         | '10%'    | 'IO'       | 'CAP CHIP 1UF 16V(10%,X6S,0402)MUR'                            | 'CHIP0402'     | ''          | ''   | '20150615'
 '0.47UF'   | '16V'   | '10%'     | 'C0603'     | 'X7R'     | 'CH4473K1904'(!)   = ''              | ''                 | ''       | 'CH4473K1904'     |'C0603'| '(SMC0603AW)'                                                        | '0.47UF'   | '16V'         | '10%'    | 'DISCRETE' | 'CAP CHIP 0.47U 16V (+-10%,X7R,0603)MUR'                       | 'CHIP0603'     | ''          | ''   | '20150615'
 '0.47UF'   | '16V'   | '10%'     | 'C0603'     | 'EMPTY'   | 'CH4473K1904'(!)   = ''              | ''                 | ''       | 'CH4473K1904'     |'C0603'| '(SMC0603AW)'                                                        | 'NA'       | '16V'         | '10%'    | 'IO'       | 'CAP CHIP 0.47U 16V (+-10%,X7R,0603)MUR'                       | 'CHIP0603'     | ''          | ''   | '20150615'
 '0.47UF'   | '25V'   | '10%'     | 'C0603'     | 'X7R'     | 'CH4474K1902'(!)   = 'End of Design' | 'Comp-Approve'     | ''       | 'CH4474K1902'     |'C0603'| '(SMC0603AW)'                                                        | '0.47UF'   | '25V'         | '10%'    | 'DISCRETE' | 'CAP CHIP 0.47UF 25V(+-10%,X7R,0603)MUR'                       | 'CHIP0603'     | ''          | ''   | '20150615'
 '0.47UF'   | '25V'   | '10%'     | 'C0603'     | 'EMPTY'   | 'CH4474K1902'(!)   = 'End of Design' | 'Comp-Approve'     | ''       | 'CH4474K1902'     |'C0603'| '(SMC0603AW)'                                                        | 'NA'       | '25V'         | '10%'    | 'IO'       | 'CAP CHIP 0.47UF 25V(+-10%,X7R,0603)MUR'                       | 'CHIP0603'     | ''          | ''   | '20150615'
 '4.7UF'    | '25V'   | '10%'     | 'C0603'     | 'X6S'     | 'CH5474KE902'(!)   = ''              | ''                 | ''       | 'CH5474KE902'     |'C0603'| '(SMC0603AW)'                                                        | '4.7UF'    | '25V'         | '10%'    | 'DISCRETE' | 'CAP CHIP 4.7UF 25V(+-10%,X6S,0603)MUR'                        | 'CHIP0603'     | ''          | ''   | '20150615'
 '4.7UF'    | '25V'   | '10%'     | 'C0603'     | 'EMPTY'   | 'CH5474KE902'(!)   = ''              | ''                 | ''       | 'CH5474KE902'     |'C0603'| '(SMC0603AW)'                                                        | 'NA'       | '25V'         | '10%'    | 'IO'       | 'CAP CHIP 4.7UF 25V(+-10%,X6S,0603)MUR'                        | 'CHIP0603'     | ''          | ''   | '20150615'
 '1UF'      | '25V'   | '10%'     | 'C0603'     | 'X7R'     | 'CH5104K1903'(!)   = 'End of Design' | 'Comp-Approve'     | ''       | 'CH5104K1903'     |'C0603'| '(SMC0603AW)'                                                        | '1UF'      | '25V'         | '10%'    | 'DISCRETE' | 'CAP CHIP 1U 25V(+-10%.X7R.0603)MUR'                           | 'CHIP0603'     | ''          | ''   | '20150615'
 '1UF'      | '25V'   | '10%'     | 'C0603'     | 'EMPTY'   | 'CH5104K1903'(!)   = 'End of Design' | 'Comp-Approve'     | ''       | 'CH5104K1903'     |'C0603'| '(SMC0603AW)'                                                        | 'NA'       | '25V'         | '10%'    | 'IO'       | 'CAP CHIP 1U 25V(+-10%.X7R.0603)MUR'                           | 'CHIP0603'     | ''          | ''   | '20150615'
 '2.2UF'    | '10V'   | '10%'     | 'C0603'     | 'X7R'     | 'CH5222K1904'(!)   = ''              | ''                 | ''       | 'CH5222K1904'     |'C0603'| '(SMC0603AW)'                                                        | '2.2UF'    | '10V'         | '10%'    | 'DISCRETE' | 'CAP CHIP 2.2UF 10V(+-10%,X7R,0603)MUR'                        | 'CHIP0603'     | ''          | ''   | '20150615'
 '2.2UF'    | '10V'   | '10%'     | 'C0603'     | 'EMPTY'   | 'CH5222K1904'(!)   = ''              | ''                 | ''       | 'CH5222K1904'     |'C0603'| '(SMC0603AW)'                                                        | 'NA'       | '10V'         | '10%'    | 'IO'       | 'CAP CHIP 2.2UF 10V(+-10%,X7R,0603)MUR'                        | 'CHIP0603'     | ''          | ''   | '20150615'
 '4.7UF'    | '6.3V'  | '10%'     | 'C0603'     | 'X6S'     | 'CH5471KE903'(!)   = 'End of Design' | 'Comp-Approve'     | ''       | 'CH5471KE903'     |'C0603'| '(SMC0603AW)'                                                        | '4.7UF'    | '6.3V'        | '10%'    | 'DISCRETE' | 'CAP CHIP 4.7U 6.3V(+-10%,X6S,0603)MUR'                        | 'CHIP0603'     | ''          | ''   | '20150615'
 '4.7UF'    | '6.3V'  | '10%'     | 'C0603'     | 'EMPTY'   | 'CH5471KE903'(!)   = 'End of Design' | 'Comp-Approve'     | ''       | 'CH5471KE903'     |'C0603'| '(SMC0603AW)'                                                        | 'NA'       | '6.3V'        | '10%'    | 'IO'       | 'CAP CHIP 4.7U 6.3V(+-10%,X6S,0603)MUR'                        | 'CHIP0603'     | ''          | ''   | '20150615'
 '10UF'     | '6.3V'  | '20%'     | 'C0603'     | 'X6S'     | 'CH6101ME902'(!)   = ''              | ''                 | ''       | 'CH6101ME902'     |'C0603'| '(SMC0603AW)'                                                        | '10UF'     | '6.3V'        | '20%'    | 'DISCRETE' | 'CAP CHIP 10U 6.3V(+-20%,X6S,0603)MUR'                         | 'CHIP0603'     | ''          | ''   | '20150615'
 '10UF'     | '6.3V'  | '20%'     | 'C0603'     | 'EMPTY'   | 'CH6101ME902'(!)   = ''              | ''                 | ''       | 'CH6101ME902'     |'C0603'| '(SMC0603AW)'                                                        | 'NA'       | '6.3V'        | '20%'    | 'IO'       | 'CAP CHIP 10U 6.3V(+-20%,X6S,0603)MUR'                         | 'CHIP0603'     | ''          | ''   | '20150615'
 '10UF'     | '4V'    | '20%'     | 'C0603'     | 'X6S'     | 'CH610KME905'(!)   = 'End of Design' | 'Comp-Approve'     | ''       | 'CH610KME905'     |'C0603'| '(SMC0603AW)'                                                        | '10UF'     | '4V'          | '20%'    | 'DISCRETE' | 'CAP CHIP 10U 4V(+-20%,X6S,0603)MUR'                           | 'CHIP0603'     | ''          | ''   | '20150615'
 '10UF'     | '4V'    | '20%'     | 'C0603'     | 'EMPTY'   | 'CH610KME905'(!)   = 'End of Design' | 'Comp-Approve'     | ''       | 'CH610KME905'     |'C0603'| '(SMC0603AW)'                                                        | 'NA'       | '4V'          | '20%'    | 'IO'       | 'CAP CHIP 10U 4V(+-20%,X6S,0603)MUR'                           | 'CHIP0603'     | ''          | ''   | '20150615'
 '0.1UF'    | '25V'   | '10%'     | 'C0603'     | 'X7R'     | 'CH4104K1909'(!)   = 'End of Design' | 'Comp-Approve'     | ''       | 'CH4104K1909'     |'C0603'| '(SMC0603AW)'                                                        | '0.1UF'    | '25V'         | '10%'    | 'DISCRETE' | 'CAP CHIP 0.1UF 25V(+-10%,X7R,0603)MUR'                        | 'CHIP0603'     | ''          | ''   | '20150615'
 '0.1UF'    | '25V'   | '10%'     | 'C0603'     | 'EMPTY'   | 'CH4104K1909'(!)   = 'End of Design' | 'Comp-Approve'     | ''       | 'CH4104K1909'     |'C0603'| '(SMC0603AW)'                                                        | 'NA'       | '25V'         | '10%'    | 'IO'       | 'CAP CHIP 0.1UF 25V(+-10%,X7R,0603)MUR'                        | 'CHIP0603'     | ''          | ''   | '20150615'
 '10UF'     | '6.3V'  | '20%'     | 'C0805'     | 'X6S'     | 'CH6101MEA00'(!)   = 'End of Design' | 'Comp-Approve'     | ''       | 'CH6101MEA00'     |'C0805_H61'| '(SMC0805AW)'                                                        | '10UF'     | '6.3V'        | '20%'    | 'DISCRETE' | 'CAP CHIP 10UF 6.3V(+-20%,X6S,0805)MUR'                        | 'CHIP0805'     | ''          | ''   | '20150615'
 '10UF'     | '6.3V'  | '20%'     | 'C0805'     | 'EMPTY'   | 'CH6101MEA00'(!)   = 'End of Design' | 'Comp-Approve'     | ''       | 'CH6101MEA00'     |'C0805_H61'| '(SMC0805AW)'                                                        | 'NA'       | '6.3V'        | '20%'    | 'IO'       | 'CAP CHIP 10UF 6.3V(+-20%,X6S,0805)MUR'                        | 'CHIP0805'     | ''          | ''   | '20150615'
 '100UF'    | '4V'    | '20%'     | 'C0805'     | 'X6S'     | 'CH710KMEA01'(!)   = ''              | ''                 | ''       | 'CH710KMEA01'     |'C0805_H61'| '(SMC0805AW)'                                                        | '100UF'    | '4V'          | '20%'    | 'DISCRETE' | 'CAP CHIP 100U 4V(+-20%,X6S,0805)MUR'                          | 'CHIP0805'     | ''          | ''   | '20150615'
 '100UF'    | '4V'    | '20%'     | 'C0805'     | 'EMPTY'   | 'CH710KMEA01'(!)   = ''              | ''                 | ''       | 'CH710KMEA01'     |'C0805_H61'| '(SMC0805AW)'                                                        | 'NA'       | '4V'          | '20%'    | 'IO'       | 'CAP CHIP 100U 4V(+-20%,X6S,0805)MUR'                          | 'CHIP0805'     | ''          | ''   | '20150615'
 '22UF'     | '10V'   | '20%'     | 'C0805'     | 'X6S'     | 'CH6222MEA01'(!)   = ''              | ''                 | ''       | 'CH6222MEA01'     |'C0805_H61'| '(SMC0805AW)'                                                        | '22UF'     | '10V'         | '20%'    | 'DISCRETE' | 'CAP CHIP 22U 10V(+-20%,X6S,0805)MUR'                          | 'CHIP0805'     | ''          | ''   | '20150615'
 '22UF'     | '10V'   | '20%'     | 'C0805'     | 'EMPTY'   | 'CH6222MEA01'(!)   = ''              | ''                 | ''       | 'CH6222MEA01'     |'C0805_H61'| '(SMC0805AW)'                                                        | 'NA'       | '10V'         | '20%'    | 'IO'       | 'CAP CHIP 22U 10V(+-20%,X6S,0805)MUR'                          | 'CHIP0805'     | ''          | ''   | '20150615'
 '10UF'     | '10V'   | '10%'     | 'C0805'     | 'X7R'     | 'CH6102K1A02'(!)   = ''              | ''                 | ''       | 'CH6102K1A02'     |'C0805_H61'| '(SMC0805AW)'                                                        | '10UF'     | '10V'         | '10%'    | 'DISCRETE' | 'CAP CHIP10UF 10V(+-10%,X7R,0805)MUR'                          | 'CHIP0805'     | ''          | ''   | '20150615'
 '10UF'     | '10V'   | '10%'     | 'C0805'     | 'EMPTY'   | 'CH6102K1A02'(!)   = ''              | ''                 | ''       | 'CH6102K1A02'     |'C0805_H61'| '(SMC0805AW)'                                                        | 'NA'       | '10V'         | '10%'    | 'IO'       | 'CAP CHIP10UF 10V(+-10%,X7R,0805)MUR'                          | 'CHIP0805'     | ''          | ''   | '20150615'
 '0.1UF'    | '100V'  | '10%'     | 'C0805'     | 'X7R'     | 'CH4108K1A01'(!)   = ''              | ''                 | ''       | 'CH4108K1A01'     |'C0805_H61'| '(SMC0805AW)'                                                        | '0.1UF'    | '100V'        | '10%'    | 'DISCRETE' | 'CAP CHIP 0.1UF 100V(+-10%,X7R,0805)MUR'                       | 'CHIP0805'     | ''          | ''   | '20150615'
 '0.1UF'    | '100V'  | '10%'     | 'C0805'     | 'EMPTY'   | 'CH4108K1A01'(!)   = ''              | ''                 | ''       | 'CH4108K1A01'     |'C0805_H61'| '(SMC0805AW)'                                                        | 'NA'       | '100V'        | '10%'    | 'IO'       | 'CAP CHIP 0.1UF 100V(+-10%,X7R,0805)MUR'                       | 'CHIP0805'     | ''          | ''   | '20150615'
 '4.7UF'    | '16V'   | '10%'     | 'C0805'     | 'X7R'     | 'CH5473K1A01'(!)   = 'End of Design' | 'Comp-Approve'     | ''       | 'CH5473K1A01'     |'C0805_H61'| '(SMC0805AW)'                                                        | '4.7UF'    | '16V'         | '10%'    | 'DISCRETE' | 'CAP CHIP 4.7UF 16V(+-10%,X7R,0805)MUR'                        | 'CHIP0805'     | ''          | ''   | '20150615'
 '4.7UF'    | '16V'   | '10%'     | 'C0805'     | 'EMPTY'   | 'CH5473K1A01'(!)   = 'End of Design' | 'Comp-Approve'     | ''       | 'CH5473K1A01'     |'C0805_H61'| '(SMC0805AW)'                                                        | 'NA'       | '16V'         | '10%'    | 'IO'       | 'CAP CHIP 4.7UF 16V(+-10%,X7R,0805)MUR'                        | 'CHIP0805'     | ''          | ''   | '20150615'
 '10UF'     | '25V'   | '10%'     | 'C0805'     | 'X6S'     | 'CH6104KEA03'(!)   = ''              | ''                 | ''       | 'CH6104KEA03'     |'C0805_H61'| '(SMC0805AW)'                                                        | '10UF'     | '25V'         | '10%'    | 'DISCRETE' | 'CAP CHIP 10U 25V(+-10%,X6S,0805)MUR'                          | 'CHIP0805'     | ''          | ''   | '20150615'
 '10UF'     | '25V'   | '10%'     | 'C0805'     | 'EMPTY'   | 'CH6104KEA03'(!)   = ''              | ''                 | ''       | 'CH6104KEA03'     |'C0805_H61'| '(SMC0805AW)'                                                        | 'NA'       | '25V'         | '10%'    | 'IO'       | 'CAP CHIP 10U 25V(+-10%,X6S,0805)MUR'                          | 'CHIP0805'     | ''          | ''   | '20150615'
 '22UF'     | '6.3V'  | '20%'     | 'C0805'     | 'X6S'     | 'CH6221MEA04'(!)   = 'End of Design' | 'Comp-Approve'     | ''       | 'CH6221MEA04'     |'C0805_H61'| '(SMC0805AW)'                                                        | '22UF'     | '6.3V'        | '20%'    | 'DISCRETE' | 'CAP CHIP 22U 6.3V(+-20%,X6S,0805)MUR'                         | 'CHIP0805'     | ''          | ''   | '20150615'
 '22UF'     | '6.3V'  | '20%'     | 'C0805'     | 'EMPTY'   | 'CH6221MEA04'(!)   = 'End of Design' | 'Comp-Approve'     | ''       | 'CH6221MEA04'     |'C0805_H61'| '(SMC0805AW)'                                                        | 'NA'       | '6.3V'        | '20%'    | 'IO'       | 'CAP CHIP 22U 6.3V(+-20%,X6S,0805)MUR'                         | 'CHIP0805'     | ''          | ''   | '20150615'
 '22UF'     | '4V'    | '20%'     | 'C0805'     | 'X6S'     | 'CH622KMEA03'(!)   = ''              | ''                 | ''       | 'CH622KMEA03'     |'C0805_H61'| '(SMC0805AW)'                                                        | '22UF'     | '4V'          | '20%'    | 'DISCRETE' | 'CAP CHIP 22U 4V(+-20%,X6S,0805)MUR'                           | 'CHIP0805'     | ''          | ''   | '20150615'
 '22UF'     | '4V'    | '20%'     | 'C0805'     | 'EMPTY'   | 'CH622KMEA03'(!)   = ''              | ''                 | ''       | 'CH622KMEA03'     |'C0805_H61'| '(SMC0805AW)'                                                        | 'NA'       | '4V'          | '20%'    | 'IO'       | 'CAP CHIP 22U 4V(+-20%,X6S,0805)MUR'                           | 'CHIP0805'     | ''          | ''   | '20150615'
 '2.2UF'    | '100V'  | '10%'     | 'C1206'     | 'X7R'     | 'CH5228K1207'(!)   = ''              | ''                 | ''       | 'CH5228K1207'     |'C1206_H66'| '(SMC1206AW)'                                                        | '2.2UF'    | '100V'        | '10%'    | 'DISCRETE' | 'CAP CHIP 2.2UF 100V(+-10%,X7R,1206)MUR'                       | 'CHIP1206'     | ''          | ''   | '20150615'
 '2.2UF'    | '100V'  | '10%'     | 'C1206'     | 'EMPTY'   | 'CH5228K1207'(!)   = ''              | ''                 | ''       | 'CH5228K1207'     |'C1206_H66'| '(SMC1206AW)'                                                        | 'NA'       | '100V'        | '10%'    | 'IO'       | 'CAP CHIP 2.2UF 100V(+-10%,X7R,1206)MUR'                       | 'CHIP1206'     | ''          | ''   | '20150615'
 '10UF'     | '25V'   | '10%'     | 'C1206'     | 'X7R'     | 'CH6104K1203'(!)   = 'End of Design' | 'Comp-Approve'     | ''       | 'CH6104K1203'     |'C1206_H66'| '(SMC1206AW)'                                                        | '10UF'     | '25V'         | '10%'    | 'DISCRETE' | 'CAP CHIP 10U 25V(+-10%,X7R,1206)MUR'                          | 'CHIP1206'     | ''          | ''   | '20150615'
 '10UF'     | '25V'   | '10%'     | 'C1206'     | 'EMPTY'   | 'CH6104K1203'(!)   = 'End of Design' | 'Comp-Approve'     | ''       | 'CH6104K1203'     |'C1206_H66'| '(SMC1206AW)'                                                        | 'NA'       | '25V'         | '10%'    | 'IO'       | 'CAP CHIP 10U 25V(+-10%,X7R,1206)MUR'                          | 'CHIP1206'     | ''          | ''   | '20150615'
 '1UF'      | '100V'  | '10%'     | 'C1206'     | 'X7R'     | 'CH5108K1201'(!)   = ''              | ''                 | ''       | 'CH5108K1201'     |'C1206_H66'| '(SMC1206AW)'                                                        | '1UF'      | '100V'        | '10%'    | 'DISCRETE' | 'CAP CHIP 1U 100V(10%.1206.X7R)MUR'                            | 'CHIP1206'     | ''          | ''   | '20150615'
 '1UF'      | '100V'  | '10%'     | 'C1206'     | 'EMPTY'   | 'CH5108K1201'(!)   = ''              | ''                 | ''       | 'CH5108K1201'     |'C1206_H66'| '(SMC1206AW)'                                                        | 'NA'       | '100V'        | '10%'    | 'IO'       | 'CAP CHIP 1U 100V(10%.1206.X7R)MUR'                            | 'CHIP1206'     | ''          | ''   | '20150615'
 '10UF'     | '25V'   | '10%'     | 'C1206'     | 'X7R'     | 'CH6104K1204'(!)   = 'End of Design' | 'Comp-Approve'     | ''       | 'CH6104K1204'     |'C1206_H66'| '(SMC1206AW)'                                                        | '10UF'     | '25V'         | '10%'    | 'DISCRETE' | 'CAP CHIP 10U,25V(+-10%,X7R,1206)SAM'                          | 'CHIP1206'     | ''          | ''   | '20150616'
 '10UF'     | '25V'   | '10%'     | 'C1206'     | 'EMPTY'   | 'CH6104K1204'(!)   = 'End of Design' | 'Comp-Approve'     | ''       | 'CH6104K1204'     |'C1206_H66'| '(SMC1206AW)'                                                        | 'NA'       | '25V'         | '10%'    | 'IO'       | 'CAP CHIP 10U,25V(+-10%,X7R,1206)SAM'                          | 'CHIP1206'     | ''          | ''   | '20150616'
 '10UF'     | '6.3V'  | '10%'     | 'C0805'     | 'X6S'     | 'CH6101KEA01'(!)   = ''              | ''                 | ''       | 'CH6101KEA01'     |'C0805_H61'| '(SMC0805AW)'                                                        | '10UF'     | '6.3V'        | '10%'    | 'DISCRETE' | 'CAP CHIP 10UF,6.3V (+-10%,X6S,0805)SAM'                       | 'CHIP0805'     | ''          | ''   | '20150616'
 '10UF'     | '6.3V'  | '10%'     | 'C0805'     | 'EMPTY'   | 'CH6101KEA01'(!)   = ''              | ''                 | ''       | 'CH6101KEA01'     |'C0805_H61'| '(SMC0805AW)'                                                        | 'NA'       | '6.3V'        | '10%'    | 'IO'       | 'CAP CHIP 10UF,6.3V (+-10%,X6S,0805)SAM'                       | 'CHIP0805'     | ''          | ''   | '20150616'
 '10UF'     | '16V'   | '10%'     | 'C0805'     | 'X7R'     | 'CH6103K1A01'(!)   = ''              | ''                 | ''       | 'CH6103K1A01'     |'C0805_H61'| '(SMC0805AW)'                                                        | '10UF'     | '16V'         | '10%'    | 'DISCRETE' | 'CAP CHIP 10UF 16V(+-10%,X7R,0805)SAM'                         | 'CHIP0805'     | ''          | ''   | '20150616'
 '10UF'     | '16V'   | '10%'     | 'C0805'     | 'EMPTY'   | 'CH6103K1A01'(!)   = ''              | ''                 | ''       | 'CH6103K1A01'     |'C0805_H61'| '(SMC0805AW)'                                                        | 'NA'       | '16V'         | '10%'    | 'IO'       | 'CAP CHIP 10UF 16V(+-10%,X7R,0805)SAM'                         | 'CHIP0805'     | ''          | ''   | '20150616'
 '0.01UF'   | '50V'   | '10%'     | 'C0402'     | 'X7R'     | 'CH31006KB00'(!)   = ''              | ''                 | ''       | 'CH31006KB00'     |'C0402'| '(C0402_OCTAGONXA,C0402-0201)'                                       | '0.01UF'   | '50V'         | '10%'    | 'DISCRETE' | 'CAP CHIP 0.01U 50V(+-10%,X7R,0402)MUR'                        | 'CHIP0402'     | ''          | ''   | '20150616'
 '0.01UF'   | '50V'   | '10%'     | 'C0402'     | 'EMPTY'   | 'CH31006KB00'(!)   = ''              | ''                 | ''       | 'CH31006KB00'     |'C0402'| '(C0402_OCTAGONXA,C0402-0201)'                                       | 'NA'       | '50V'         | '10%'    | 'IO'       | 'CAP CHIP 0.01U 50V(+-10%,X7R,0402)MUR'                        | 'CHIP0402'     | ''          | ''   | '20150616'
 '0.22UF'   | '16V'   | '10%'     | 'C0402'     | 'X7R'     | 'CH4223K1B04'(!)   = 'End of Design' | 'Comp-Approve'     | ''       | 'CH4223K1B04'     |'C0402'| '(C0402-0201)'                                                       | '0.22UF'   | '16V'         | '10%'    | 'DISCRETE' | 'CAP CHIP 0.22U 16V(10%,X7R,0402)MUR'                          | 'CHIP0402'     | ''          | ''   | '20150616'
 '0.22UF'   | '16V'   | '10%'     | 'C0402'     | 'EMPTY'   | 'CH4223K1B04'(!)   = 'End of Design' | 'Comp-Approve'     | ''       | 'CH4223K1B04'     |'C0402'| '(C0402-0201)'                                                       | 'NA'       | '16V'         | '10%'    | 'IO'       | 'CAP CHIP 0.22U 16V(10%,X7R,0402)MUR'                          | 'CHIP0402'     | ''          | ''   | '20150616'
 '3300PF'   | '50V'   | '10%'     | 'C0402'     | 'X7R'     | 'CH2336K1B06'(!)   = ''              | ''                 | ''       | 'CH2336K1B06'     |'C0402'| '(C0402-0201)'                                                       | '3300PF'   | '50V'         | '10%'    | 'DISCRETE' | 'CAP CHIP 3300P 50V(+-10%,X7R,0402)MUR'                        | 'CHIP0402'     | ''          | ''   | '20150617'
 '3300PF'   | '50V'   | '10%'     | 'C0402'     | 'EMPTY'   | 'CH2336K1B06'(!)   = ''              | ''                 | ''       | 'CH2336K1B06'     |'C0402'| '(C0402-0201)'                                                       | 'NA'       | '50V'         | '10%'    | 'IO'       | 'CAP CHIP 3300P 50V(+-10%,X7R,0402)MUR'                        | 'CHIP0402'     | ''          | ''   | '20150617'
 '10PF'     | '50V'   | '2%'      | 'C0402'     | 'NPO'     | 'CH0106G0B03'(!)   = ''              | ''                 | ''       | 'CH0106G0B03'     |'C0402'| '(C0402-0201)'                                                       | '10PF'     | '50V'         | '2%'     | 'DISCRETE' | 'CAP CHIP 10P 50V(+-2%,NPO,0402)MUR'                           | 'CHIP0402'     | ''          | ''   | '20150622'
 '10PF'     | '50V'   | '2%'      | 'C0402'     | 'EMPTY'   | 'CH0106G0B03'(!)   = ''              | ''                 | ''       | 'CH0106G0B03'     |'C0402'| '(C0402-0201)'                                                       | 'NA'       | '50V'         | '2%'     | 'IO'       | 'CAP CHIP 10P 50V(+-2%,NPO,0402)MUR'                           | 'CHIP0402'     | ''          | ''   | '20150622'
 '820PF'    | '50V'   | '10%'     | 'C0402'     | 'X7R'     | 'CH1826K1B07'(!)   = ''              | ''                 | ''       | 'CH1826K1B07'     |'C0402'| '(C0402-0201)'                                                       | '820PF'    | '50V'         | '10%'    | 'DISCRETE' | 'CAP CHIP 820P 50V(+-10%,X7R,0402)MUR'                         | 'CHIP0402'     | ''          | ''   | '20150622'
 '820PF'    | '50V'   | '10%'     | 'C0402'     | 'EMPTY'   | 'CH1826K1B07'(!)   = ''              | ''                 | ''       | 'CH1826K1B07'     |'C0402'| '(C0402-0201)'                                                       | 'NA'       | '50V'         | '10%'    | 'IO'       | 'CAP CHIP 820P 50V(+-10%,X7R,0402)MUR'                         | 'CHIP0402'     | ''          | ''   | '20150622'
 '33PF'     | '50V'   | '5%'      | 'C0402'     | 'NPO'     | 'CH0336J0B11'(!)   = ''              | ''                 | ''       | 'CH0336J0B11'     |'C0402'| '(C0402-0201)'                                                       | '33PF'     | '50V'         | '5%'     | 'DISCRETE' | 'CAP CHIP 33P 50V(+-5%,NPO,0402)SAM'                           | 'CHIP0402'     | ''          | ''   | '20150622'
 '33PF'     | '50V'   | '5%'      | 'C0402'     | 'EMPTY'   | 'CH0336J0B11'(!)   = ''              | ''                 | ''       | 'CH0336J0B11'     |'C0402'| '(C0402-0201)'                                                       | 'NA'       | '50V'         | '5%'     | 'IO'       | 'CAP CHIP 33P 50V(+-5%,NPO,0402)SAM'                           | 'CHIP0402'     | ''          | ''   | '20150622'
 '0.1UF'    | '100V'  | '10%'     | 'C1206'     | 'X7R'     | 'CH4108K1205'(!)   = ''              | ''                 | ''       | 'CH4108K1205'     |'C1206_H42'| '(SMC1206AW)'                                                        | '0.1UF'    | '100V'        | '10%'    | 'DISCRETE' | 'CAP CHIP 0.1U 100V(+-10%,X7R,1206)MUR'                        | 'CHIP1206'     | ''          | ''   | '20150622'
 '0.1UF'    | '100V'  | '10%'     | 'C1206'     | 'EMPTY'   | 'CH4108K1205'(!)   = ''              | ''                 | ''       | 'CH4108K1205'     |'C1206_H42'| '(SMC1206AW)'                                                        | 'NA'       | '100V'        | '10%'    | 'IO'       | 'CAP CHIP 0.1U 100V(+-10%,X7R,1206)MUR'                        | 'CHIP1206'     | ''          | ''   | '20150622'
 '22UF'     | '4V'    | '20%'     | 'C0402'     | 'X5R'     | 'CH622KM9B03'(!)   = ''              | ''                 | ''       | 'CH622KM9B03'     |'C0402'| '(C0402-0201)'                                                       | '22UF'     | '4V'          | '20%'    | 'DISCRETE' | 'CAP CHIP 22UF 4V (+-20%, X5R,0402)MUR'                        | 'CHIP0402'     | ''          | ''   | '20150625'
 '22UF'     | '4V'    | '20%'     | 'C0402'     | 'EMPTY'   | 'CH622KM9B03'(!)   = ''              | ''                 | ''       | 'CH622KM9B03'     |'C0402'| '(C0402-0201)'                                                       | 'NA'       | '4V'          | '20%'    | 'IO'       | 'CAP CHIP 22UF 4V (+-20%, X5R,0402)MUR'                        | 'CHIP0402'     | ''          | ''   | '20150625'
 '47UF'     | '4V'    | '20%'     | '0805'      | 'X6S'     | 'CH647KMEA00'(!)   = ''              | ''                 | ''       | 'CH647KMEA00'     |'C0805_H57'| '(C0805_BHS)'                                                        | '47UF'     | '4V'          | '20%'    | 'DISCRETE' | 'CAP CHIP 47U 4V(+-20%,X6S,0805)'                              | 'CHIP0805'     | ''          | ''   | '20150706'
 '47UF'     | '4V'    | '20%'     | '0805'      | 'EMPTY'   | 'CH647KMEA00'(!)   = ''              | ''                 | ''       | 'CH647KMEA00'     |'C0805_H57'| '(C0805_BHS)'                                                        | 'NA'       | '4V'          | '20%'    | 'IO'       | 'CAP CHIP 47U 4V(+-20%,X6S,0805)'                              | 'CHIP0805'     | ''          | ''   | '20150706'
 '1UF'      | '4V'    | '20%'     | '0201'      | 'X6S'     | 'CH-10KMEE00'(!)   = 'End of Design' | 'Comp-Approve'     | ''       | 'CH-10KMEE00'     |'C0201'| '(SMC0201AW)'                                                        | '1UF'      | '4V'          | '20%'    | 'DISCRETE' | 'CAP CHIP 1U 4V(+-20%,X6S,0201)'                               | 'CHIP0201'     | ''          | ''   | '20150713'
 '1UF'      | '4V'    | '20%'     | '0201'      | 'EMPTY'   | 'CH-10KMEE00'(!)   = 'End of Design' | 'Comp-Approve'     | ''       | 'CH-10KMEE00'     |'C0201'| '(SMC0201AW)'                                                        | 'NA'       | '4V'          | '20%'    | 'IO'       | 'CAP CHIP 1U 4V(+-20%,X6S,0201)'                               | 'CHIP0201'     | ''          | ''   | '20150713'
 '10UF'     | '10V'   | '20%'     | 'C0603'     | 'X6S'     | 'CH6102ME902'(!)   = ''              | ''                 | ''       | 'CH6102ME902'     |'C0603'| '(SMC0603AW)'                                                        | '10UF'     | '10V'         | '20%'    | 'DISCRETE' | 'CAP CHIP 10U,10V(+-20%,X6S,0603)TAY'                          | 'CHIP0603'     | ''          | ''   | '20150716'
 '10UF'     | '10V'   | '20%'     | 'C0603'     | 'EMPTY'   | 'CH6102ME902'(!)   = ''              | ''                 | ''       | 'CH6102ME902'     |'C0603'| '(SMC0603AW)'                                                        | 'NA'       | '10V'         | '20%'    | 'IO'       | 'CAP CHIP 10U,10V(+-20%,X6S,0603)TAY'                          | 'CHIP0603'     | ''          | ''   | '20150716'
 '0.047UF'  | '100V'  | '10%'     | 'C0805'     | 'X7R'     | 'CH3478K1A00'(!)   = ''              | ''                 | ''       | 'CH3478K1A00'     |'C0805_H57'| '(SMC0805AW)'                                                        | '0.047UF'  | '100V'        | '10%'    | 'DISCRETE' | 'CAP CHIP 0.047UF 100V(+-10%,X7R,0805)'                        | 'CHIP0805'     | ''          | ''   | '20150803'
 '0.047UF'  | '100V'  | '10%'     | 'C0805'     | 'EMPTY'   | 'CH3478K1A00'(!)   = ''              | ''                 | ''       | 'CH3478K1A00'     |'C0805_H57'| '(SMC0805AW)'                                                        | 'NA'       | '100V'        | '10%'    | 'IO'       | 'CAP CHIP 0.047UF 100V(+-10%,X7R,0805)'                        | 'CHIP0805'     | ''          | ''   | '20150803'
 '0.033UF'  | '16V'   | '10%'     | 'C0402'     | 'X7R'     | 'CH3333K1B06'(!)   = ''              | ''                 | ''       | 'CH3333K1B06'     |'C0402'| '(C0402-0201)'                                                       | '0.033UF'  | '16V'         | '10%'    | 'DISCRETE' | 'CAP CHIP 0.033U 16V(+-10%.X7R.0402)MUR'                       | 'CHIP0402'     | ''          | ''   | '20150825'
 '0.033UF'  | '16V'   | '10%'     | 'C0402'     | 'EMPTY'   | 'CH3333K1B06'(!)   = ''              | ''                 | ''       | 'CH3333K1B06'     |'C0402'| '(C0402-0201)'                                                       | 'NA'       | '16V'         | '10%'    | 'IO'       | 'CAP CHIP 0.033U 16V(+-10%.X7R.0402)MUR'                       | 'CHIP0402'     | ''          | ''   | '20150825'
 '330PF'    | '50V'   | '10%'     | 'C0402'     | 'X7R'     | 'CH1336K1B06'(!)   = ''              | ''                 | ''       | 'CH1336K1B06'     |'C0402'| '(C0402-0201)'                                                       | '330PF'    | '50V'         | '10%'    | 'DISCRETE' | 'CAP CHIP 330P 50V(+-10%,X7R,0402)MUR'                         | 'CHIP0402'     | ''          | ''   | '20150902'
 '330PF'    | '50V'   | '10%'     | 'C0402'     | 'EMPTY'   | 'CH1336K1B06'(!)   = ''              | ''                 | ''       | 'CH1336K1B06'     |'C0402'| '(C0402-0201)'                                                       | 'NA'       | '50V'         | '10%'    | 'IO'       | 'CAP CHIP 330P 50V(+-10%,X7R,0402)MUR'                         | 'CHIP0402'     | ''          | ''   | '20150902'
 '0.1UF'    | '16V'   | '10%'     | 'C0402'     | 'X7R'     | 'CH4103K1B08'(!)   = ''              | ''                 | ''       | 'CH4103K1B08'     |'C0402'| '(C0402_OCTAGONXA,C0402_OCTAGON,C0402-0201)'                         | '0.1UF'    | '16V'         | '10%'    | 'DISCRETE' | 'CAP CHIP 0.1U 16V(10%,X7R,0402)'                              | 'CHIP0402'     | ''          | ''   | '20150911'
 '0.1UF'    | '16V'   | '10%'     | 'C0402'     | 'EMPTY'   | 'CH4103K1B08'(!)   = ''              | ''                 | ''       | 'CH4103K1B08'     |'C0402'| '(C0402_OCTAGONXA,C0402_OCTAGON,C0402-0201)'                         | 'NA'       | '16V'         | '10%'    | 'IO'       | 'CAP CHIP 0.1U 16V(10%,X7R,0402)'                              | 'CHIP0402'     | ''          | ''   | '20150911'
 '1UF'      | '6.3V'  | '10%'     | 'C0402'     | 'X7R'     | 'CH5101K1B05'(!)   = ''              | ''                 | ''       | 'CH5101K1B05'     |'C0402'| '(C0402_OCTAGONXA,C0402_OCTAGON,C0402-0201,C0402_OCTAGONXA_BOUND22)' | '1UF'      | '6.3V'        | '10%'    | 'DISCRETE' | 'CAP CHIP 1U,6.3V(+-10%,X7R,0402)MUR'                          | 'CHIP0402'     | ''          | ''   | '20150911'
 '1UF'      | '6.3V'  | '10%'     | 'C0402'     | 'EMPTY'   | 'CH5101K1B05'(!)   = ''              | ''                 | ''       | 'CH5101K1B05'     |'C0402'| '(C0402_OCTAGONXA,C0402_OCTAGON,C0402-0201,C0402_OCTAGONXA_BOUND22)' | 'NA'       | '6.3V'        | '10%'    | 'IO'       | 'CAP CHIP 1U,6.3V(+-10%,X7R,0402)MUR'                          | 'CHIP0402'     | ''          | ''   | '20150911'
 '10UF'     | '4V'    | '20%'     | 'C0603'     | 'X6S'     | 'CH610KME902'(!)   = 'End of Design' | 'Comp-Approve'     | ''       | 'CH610KME902'     |'C0603'| '(SMC0603AW)'                                                        | '10UF'     | '4V'          | '20%'    | 'DISCRETE' | 'CAP CHIP 10U 4V(+-20%,X6S,0603)'                              | 'CHIP0603'     | ''          | ''   | '20151006'
 '10UF'     | '4V'    | '20%'     | 'C0603'     | 'EMPTY'   | 'CH610KME902'(!)   = 'End of Design' | 'Comp-Approve'     | ''       | 'CH610KME902'     |'C0603'| '(SMC0603AW)'                                                        | 'NA'       | '4V'          | '20%'    | 'IO'       | 'CAP CHIP 10U 4V(+-20%,X6S,0603)'                              | 'CHIP0603'     | ''          | ''   | '20151006'
 '0.01UF'   | '16V'   | '10%'     | 'C0201'     | 'X7R'     | 'CH3103K1E01'(!)   = ''              | ''                 | ''       | 'CH3103K1E01'     |'C0201'| '(SMC0201AW)'                                                        | '0.01UF'   | '16V'         | '10%'    | 'DISCRETE' | 'CAP CHIP 0.01U 16V(+-10%.X7R.0201)TAY'                        | 'CHIP0201'     | ''          | ''   | '20151022'
 '0.01UF'   | '16V'   | '10%'     | 'C0201'     | 'EMPTY'   | 'CH3103K1E01'(!)   = ''              | ''                 | ''       | 'CH3103K1E01'     |'C0201'| '(SMC0201AW)'                                                        | 'NA'       | '16V'         | '10%'    | 'IO'       | 'CAP CHIP 0.01U 16V(+-10%.X7R.0201)TAY'                        | 'CHIP0201'     | ''          | ''   | '20151022'
 '100UF'    | '6.3V'  | '20%'     | 'C1206'     | 'X6T'     | 'CH7101MH201'(!)   = ''              | ''                 | ''       | 'CH7101MH201'     |'C1206_H66'| '(SMC1206AW)'                                                        | '100UF'    | '6.3V'        | '20%'    | 'DISCRETE' | 'CAP CHIP 100U 6.3V(+-20%,X6T,1206)MUR'                        | 'CHIP1206'     | ''          | ''   | '20151022'
 '100UF'    | '6.3V'  | '20%'     | 'C1206'     | 'EMPTY'   | 'CH7101MH201'(!)   = ''              | ''                 | ''       | 'CH7101MH201'     |'C1206_H66'| '(SMC1206AW)'                                                        | 'NA'       | '6.3V'        | '20%'    | 'IO'       | 'CAP CHIP 100U 6.3V(+-20%,X6T,1206)MUR'                        | 'CHIP1206'     | ''          | ''   | '20151022'
 '2.2UF'    | '10V'   | '10%'     | 'C0402'     | 'X6S'     | 'CH5222KEB02'(!)   = ''              | ''                 | ''       | 'CH5222KEB02'     |'C0402_H28'| '(C0402-0201_H28,C0402_OCTAGONXA)'                                   | '2.2UF'    | '10V'         | '10%'    | 'DISCRETE' | 'CAP CHIP 2.2UF 10V(+-10%,X6S,0402)MUR'                        | 'CHIP0402'     | ''          | ''   | '20151022'
 '2.2UF'    | '10V'   | '10%'     | 'C0402'     | 'EMPTY'   | 'CH5222KEB02'(!)   = ''              | ''                 | ''       | 'CH5222KEB02'     |'C0402_H28'| '(C0402-0201_H28,C0402_OCTAGONXA)'                                   | 'NA'       | '10V'         | '10%'    | 'IO'       | 'CAP CHIP 2.2UF 10V(+-10%,X6S,0402)MUR'                        | 'CHIP0402'     | ''          | ''   | '20151022'
 '2.2UF'    | '100V'  | '10%'     | 'C1206'     | 'X7R'     | 'CH5228K1208'(!)   = ''              | ''                 | ''       | 'CH5228K1208'     |'C1206_H66'| '(SMC1206AW)'                                                        | '2.2UF'    | '100V'        | '10%'    | 'DISCRETE' | 'CAP CHIP 2.2UF 100V(+-10%,X7R,1206)SAM'                       | 'CHIP1206'     | ''          | ''   | '20151022'
 '2.2UF'    | '100V'  | '10%'     | 'C1206'     | 'EMPTY'   | 'CH5228K1208'(!)   = ''              | ''                 | ''       | 'CH5228K1208'     |'C1206_H66'| '(SMC1206AW)'                                                        | 'NA'       | '100V'        | '10%'    | 'IO'       | 'CAP CHIP 2.2UF 100V(+-10%,X7R,1206)SAM'                       | 'CHIP1206'     | ''          | ''   | '20151022'
 '47UF'     | '4V'    | '20%'     | 'C0805'     | 'X6S'     | 'CH647KMEA06'(!)   = ''              | ''                 | ''       | 'CH647KMEA06'     |'C0805_H57'| '(SMC0805AW)'                                                        | '47UF'     | '4V'          | '20%'    | 'DISCRETE' | 'CAP CHIP 47U 4V(+-20%.X6S.0805)SAM'                           | 'CHIP0805'     | ''          | ''   | '20151022'
 '47UF'     | '4V'    | '20%'     | 'C0805'     | 'EMPTY'   | 'CH647KMEA06'(!)   = ''              | ''                 | ''       | 'CH647KMEA06'     |'C0805_H57'| '(SMC0805AW)'                                                        | 'NA'       | '4V'          | '20%'    | 'IO'       | 'CAP CHIP 47U 4V(+-20%.X6S.0805)SAM'                           | 'CHIP0805'     | ''          | ''   | '20151022'
 '12PF'     | '50V'   | '2%'      | 'C0402'     | 'C0G'     | 'CH0126G0B07'(!)   = ''              | ''                 | ''       | 'CH0126G0B07'     |'C0402'| '(C0402-0201)'                                                       | '12P'      | '50V'         | '2%'     | 'DISCRETE' | 'CAP CHIP 12P 50V(+-2%,C0G,0402)SAM'                           | 'CHIP0402'     | ''          | ''   | '20151022'
 '12PF'     | '50V'   | '2%'      | 'C0402'     | 'EMPTY'   | 'CH0126G0B07'(!)   = ''              | ''                 | ''       | 'CH0126G0B07'     |'C0402'| '(C0402-0201)'                                                       | 'NA'       | '50V'         | '2%'     | 'IO'       | 'CAP CHIP 12P 50V(+-2%,C0G,0402)SAM'                           | 'CHIP0402'     | ''          | ''   | '20151022'
 '1UF'      | '25V'   | '10%'     | 'C0402'     | 'X6S'     | 'CH5104KEB04'(!)   = ''              | ''                 | ''       | 'CH5104KEB04'     |'C0402'| '(C0402-0201)'                                                       | '1UF'      | '25V'         | '10%'    | 'DISCRETE' | 'CAP CHIP 1UF 25V(+-10%,X6S,0402)SAM'                          | 'CHIP0402'     | ''          | ''   | '20151022'
 '1UF'      | '25V'   | '10%'     | 'C0402'     | 'EMPTY'   | 'CH5104KEB04'(!)   = ''              | ''                 | ''       | 'CH5104KEB04'     |'C0402'| '(C0402-0201)'                                                       | 'NA'       | '25V'         | '10%'    | 'IO'       | 'CAP CHIP 1UF 25V(+-10%,X6S,0402)SAM'                          | 'CHIP0402'     | ''          | ''   | '20151022'
 '12PF'     | '50V'   | '2%'      | 'C0402'     | 'C0G'     | 'CH0126G0B06'(!)   = ''              | ''                 | ''       | 'CH0126G0B06'     |'C0402'| '(C0402-0201)'                                                       | '12PF'     | '50V'         | '2%'     | 'DISCRETE' | 'CAP CHIP 12P 50V(+-2%,C0G,0402)MUR'                           | 'CHIP0402'     | ''          | ''   | '20151029'
 '12PF'     | '50V'   | '2%'      | 'C0402'     | 'EMPTY'   | 'CH0126G0B06'(!)   = ''              | ''                 | ''       | 'CH0126G0B06'     |'C0402'| '(C0402-0201)'                                                       | 'NA'       | '50V'         | '2%'     | 'IO'       | 'CAP CHIP 12P 50V(+-2%,C0G,0402)MUR'                           | 'CHIP0402'     | ''          | ''   | '20151029'
 '0.01UF'   | '1KV'   | '10%'     | 'C1206'     | 'X7R'     | 'CH310FK1202'(!)   = ''              | ''                 | ''       | 'CH310FK1202'     |'C1206_H76'| '(SMC1206AW)'                                                        | '0.01UF'   | '1KV'         | '10%'    | 'DISCRETE' | 'CAP CHIP 0.01U 1KV(+-10%,X7R,1206)MUR'                        | 'CHIP1206'     | ''          | ''   | '20151029'
 '0.01UF'   | '1KV'   | '10%'     | 'C1206'     | 'EMPTY'   | 'CH310FK1202'(!)   = ''              | ''                 | ''       | 'CH310FK1202'     |'C1206_H76'| '(SMC1206AW)'                                                        | 'NA'       | '1KV'         | '10%'    | 'IO'       | 'CAP CHIP 0.01U 1KV(+-10%,X7R,1206)MUR'                        | 'CHIP1206'     | ''          | ''   | '20151029'
 '22UF'     | '25V'   | '20%'     | 'C1206'     | 'X7S'     | 'CH6224M6200'(!)   = 'End of Design' | 'Comp-Approve'     | ''       | 'CH6224M6200'     |'C1206_H76'| '(SMC1206AW)'                                                        | '22UF'     | '25V'         | '20%'    | 'DISCRETE' | 'CAP CHIP 22UF 25V(+-20%,X7S,1206)'                            | 'CHIP1206'     | ''          | ''   | '20151110'
 '22UF'     | '25V'   | '20%'     | 'C1206'     | 'EMPTY'   | 'CH6224M6200'(!)   = 'End of Design' | 'Comp-Approve'     | ''       | 'CH6224M6200'     |'C1206_H76'| '(SMC1206AW)'                                                        | 'NA'       | '25V'         | '20%'    | 'IO'       | 'CAP CHIP 22UF 25V(+-20%,X7S,1206)'                            | 'CHIP1206'     | ''          | ''   | '20151110'
 '1000PF'   | '50V'   | '10%'     | 'C0402'     | 'X7R'     | 'CH2106K1B20'(!)   = ''              | ''                 | ''       | 'CH2106K1B20'     |'C0402'| '(C0402-0201)'                                                       | '1000PF'   | '50V'         | '10%'    | 'DISCRETE' | 'CAP CHIP 1000P 50V(+-10%,X7R,0402)MUR'                        | 'CHIP0402'     | ''          | ''   | '20151112'
 '1000PF'   | '50V'   | '10%'     | 'C0402'     | 'EMPTY'   | 'CH2106K1B20'(!)   = ''              | ''                 | ''       | 'CH2106K1B20'     |'C0402'| '(C0402-0201)'                                                       | 'NA'       | '50V'         | '10%'    | 'IO'       | 'CAP CHIP 1000P 50V(+-10%,X7R,0402)MUR'                        | 'CHIP0402'     | ''          | ''   | '20151112'
 '47UF'     | '6.3V'  | '20%'     | 'C1206'     | 'X6S'     | 'CH6471ME201'(!)   = ''              | ''                 | ''       | 'CH6471ME201'     |'C1206_H76'| '(SMC1206AW)'                                                        | '47UF'     | '6.3V'        | '20%'    | 'DISCRETE' | 'CAP CHIP 47U 6.3V(+-20%,X6S,1206)MUR'                         | 'CHIP1206'     | ''          | ''   | '20151112'
 '47UF'     | '6.3V'  | '20%'     | 'C1206'     | 'EMPTY'   | 'CH6471ME201'(!)   = ''              | ''                 | ''       | 'CH6471ME201'     |'C1206_H76'| '(SMC1206AW)'                                                        | 'NA'       | '6.3V'        | '20%'    | 'IO'       | 'CAP CHIP 47U 6.3V(+-20%,X6S,1206)MUR'                         | 'CHIP1206'     | ''          | ''   | '20151112'
 '47UF'     | '6.3V'  | '20%'     | 'C1206'     | 'X6S'     | 'CH6471ME200'(!)   = 'End of Design' | 'Comp-Approve'     | ''       | 'CH6471ME200'     |'C1206_H76'| '(SMC1206AW)'                                                        | '47UF'     | '6.3V'        | '20%'    | 'DISCRETE' | 'CAP CHIP 47U 6.3V(+-20%,X6S,1206)'                            | 'CHIP1206'     | ''          | ''   | '20151112'
 '47UF'     | '6.3V'  | '20%'     | 'C1206'     | 'EMPTY'   | 'CH6471ME200'(!)   = 'End of Design' | 'Comp-Approve'     | ''       | 'CH6471ME200'     |'C1206_H76'| '(SMC1206AW)'                                                        | 'NA'       | '6.3V'        | '20%'    | 'IO'       | 'CAP CHIP 47U 6.3V(+-20%,X6S,1206)'                            | 'CHIP1206'     | ''          | ''   | '20151112'
 '0.1UF'    | '50V'   | '10%'     | 'C0603'     | 'X7R'     | 'CH4106K1910'(!)   = 'End of Design' | 'Comp-Approve'     | ''       | 'CH4106K1910'     |'C0603'| '(SMC0603AW)'                                                        | '0.1UF'    | '50V'         | '10%'    | 'DISCRETE' | 'CAP CHIP 0.1U 50V(+-10%,X7R,0603)MUR'                         | 'CHIP0603'     | ''          | ''   | '20151120'
 '0.1UF'    | '50V'   | '10%'     | 'C0603'     | 'EMPTY'   | 'CH4106K1910'(!)   = 'End of Design' | 'Comp-Approve'     | ''       | 'CH4106K1910'     |'C0603'| '(SMC0603AW)'                                                        | 'NA'       | '50V'         | '10%'    | 'IO'       | 'CAP CHIP 0.1U 50V(+-10%,X7R,0603)MUR'                         | 'CHIP0603'     | ''          | ''   | '20151120'
 '270PF'    | '25V'   | '5%'      | 'C0402'     | 'NPO'     | 'CH1274J0B01'(!)   = ''              | ''                 | ''       | 'CH1274J0B01'     |'C0402'| '(C0402-0201)'                                                       | '270PF'    | '25V'         | '5%'     | 'DISCRETE' | 'CAP CHIP 270P 25V(+-5%,NPO,0402)MUR'                          | 'CHIP0402'     | ''          | ''   | '20151201'
 '270PF'    | '25V'   | '5%'      | 'C0402'     | 'EMPTY'   | 'CH1274J0B01'(!)   = ''              | ''                 | ''       | 'CH1274J0B01'     |'C0402'| '(C0402-0201)'                                                       | 'NA'       | '25V'         | '5%'     | 'IO'       | 'CAP CHIP 270P 25V(+-5%,NPO,0402)MUR'                          | 'CHIP0402'     | ''          | ''   | '20151201'
 '1UF'      | '25V'   | '10%'     | 'C0805'     | 'X7R'     | 'CH5104K1A06'(!)   = ''              | ''                 | ''       | 'CH5104K1A06'     |'C0805_H57'| '(SMC0805AW)'                                                        | '1UF'      | '25V'         | '10%'    | 'DISCRETE' | 'CAP CHIP 1U 25V(+-10%.X7R.0805)MUR'                           | 'CHIP0805'     | ''          | ''   | '20151209'
 '1UF'      | '25V'   | '10%'     | 'C0805'     | 'EMPTY'   | 'CH5104K1A06'(!)   = ''              | ''                 | ''       | 'CH5104K1A06'     |'C0805_H57'| '(SMC0805AW)'                                                        | 'NA'       | '25V'         | '10%'    | 'IO'       | 'CAP CHIP 1U 25V(+-10%.X7R.0805)MUR'                           | 'CHIP0805'     | ''          | ''   | '20151209'
 '10PF'     | '3KV'   | '5%'      | 'C1808'     | 'NPO'     | 'CH010GJ0I08'(!)   = ''              | ''                 | ''       | 'CH010GJ0I08'     |'C1808_H71'| '(SMC1808AW)'                                                        | '10PF'     | '3KV'         | '5%'     | 'DISCRETE' | 'CAP CHIP 10P 3KV(+-5%,NPO,1808)EP'                            | 'CHIP1808'     | ''          | ''   | '20151211'
 '10PF'     | '3KV'   | '5%'      | 'C1808'     | 'EMPTY'   | 'CH010GJ0I08'(!)   = ''              | ''                 | ''       | 'CH010GJ0I08'     |'C1808_H71'| '(SMC1808AW)'                                                        | 'NA'       | '3KV'         | '5%'     | 'IO'       | 'CAP CHIP 10P 3KV(+-5%,NPO,1808)EP'                            | 'CHIP1808'     | ''          | ''   | '20151211'
 '4.7UF'    | '6.3V'  | '20%'     | '0402'      | 'X6S'     | 'CH5471MEB01'(!)   = ''              | ''                 | ''       | 'CH5471MEB01'     |'C0402'| '(C0402_OCTAGON,C0402_OCTAGONXA,C0402-0201)'                         | '4.7UF'    | '6.3V'        | '20%'    | 'DISCRETE' | 'CAP CHIP 4.7UF 6.3V(+-20%,X6S,0402)'                          | 'CHIP0402'     | ''          | ''   | '20151211'
 '4.7UF'    | '6.3V'  | '20%'     | '0402'      | 'EMPTY'   | 'CH5471MEB01'(!)   = ''              | ''                 | ''       | 'CH5471MEB01'     |'C0402'| '(C0402_OCTAGON,C0402_OCTAGONXA,C0402-0201)'                         | 'NA'       | '6.3V'        | '20%'    | 'IO'       | 'CAP CHIP 4.7UF 6.3V(+-20%,X6S,0402)'                          | 'CHIP0402'     | ''          | ''   | '20151211'
 '0.039UF'  | '50V'   | '10%'     | 'C0603'     | 'X7R'     | 'CH3396K1901'(!)   = 'End of Design' | 'Comp-Approve'     | ''       | 'CH3396K1901'     |'C0603'| '(SMC0603AW)'                                                        | '0.039UF'  | '50V'         | '10%'    | 'DISCRETE' | 'CAP CHIP 0.039U 50V(+-10%,X7R,0603)MUR'                       | 'CHIP0603'     | ''          | ''   | '20151229'
 '0.039UF'  | '50V'   | '10%'     | 'C0603'     | 'EMPTY'   | 'CH3396K1901'(!)   = 'End of Design' | 'Comp-Approve'     | ''       | 'CH3396K1901'     |'C0603'| '(SMC0603AW)'                                                        | 'NA'       | '50V'         | '10%'    | 'IO'       | 'CAP CHIP 0.039U 50V(+-10%,X7R,0603)MUR'                       | 'CHIP0603'     | ''          | ''   | '20151229'
 '0.1UF'    | '10V'   | '10%'     | 'C0402'     | 'X7R'     | 'CH3104K1B15'(!)   = ''              | 'End of Life'      | ''       | 'CH3104K1B15'     |'C0402_EOL'| '(C0402-0201)'                                                       | '0.1UF'    | '10V'         | '10%'    | 'DISCRETE' | 'CAP CHIP 0.1U 10V(+-10%,X7R,0402)AEC'                         | 'CHIP0402'     | ''          | ''   | '20151231'
 '0.1UF'    | '10V'   | '10%'     | 'C0402'     | 'EMPTY'   | 'CH3104K1B15'(!)   = ''              | 'End of Life'      | ''       | 'CH3104K1B15'     |'C0402_EOL'| '(C0402-0201)'                                                       | 'NA'       | '10V'         | '10%'    | 'IO'       | 'CAP CHIP 0.1U 10V(+-10%,X7R,0402)AEC'                         | 'CHIP0402'     | ''          | ''   | '20151231'
 '0.1UF'    | '16V'   | '10%'     | 'C0402'     | 'X7R'     | 'CH4103K1B21'(!)   = ''              | ''                 | ''       | 'CH4103K1B21'     |'C0402'| '(C0402-0201)'                                                       | '0.1UF'    | '16V'         | '10%'    | 'DISCRETE' | 'CAP CHIP 0.1U 16V(+-10%,X7R,0402)AEC'                         | 'CHIP0402'     | ''          | ''   | '20151231'
 '0.1UF'    | '16V'   | '10%'     | 'C0402'     | 'EMPTY'   | 'CH4103K1B21'(!)   = ''              | ''                 | ''       | 'CH4103K1B21'     |'C0402'| '(C0402-0201)'                                                       | 'NA'       | '16V'         | '10%'    | 'IO'       | 'CAP CHIP 0.1U 16V(+-10%,X7R,0402)AEC'                         | 'CHIP0402'     | ''          | ''   | '20151231'
 '0.1UF'    | '25V'   | '10%'     | 'C0603'     | 'X7R'     | 'CH4104K1914'(!)   = ''              | ''                 | ''       | 'CH4104K1914'     |'C0603'| '(SMC0603AW)'                                                        | '0.1UF'    | '25V'         | '10%'    | 'DISCRETE' | 'CAP CHIP 0.1U 25V(+-10%,X7R,0603)AEC'                         | 'CHIP0603'     | ''          | ''   | '20151231'
 '0.1UF'    | '25V'   | '10%'     | 'C0603'     | 'EMPTY'   | 'CH4104K1914'(!)   = ''              | ''                 | ''       | 'CH4104K1914'     |'C0603'| '(SMC0603AW)'                                                        | 'NA'       | '25V'         | '10%'    | 'IO'       | 'CAP CHIP 0.1U 25V(+-10%,X7R,0603)AEC'                         | 'CHIP0603'     | ''          | ''   | '20151231'
 '1000PF'   | '50V'   | '5%'      | 'C0402'     | 'X7R'     | 'CH2106J1B06'(!)   = ''              | ''                 | ''       | 'CH2106J1B06'     |'C0402'| '(C0402-0201)'                                                       | '1000PF'   | '50V'         | '5%'     | 'DISCRETE' | 'CAP CHIP 1000P 50V(+-5%,X7R,0402)AEC'                         | 'CHIP0402'     | ''          | ''   | '20151231'
 '1000PF'   | '50V'   | '5%'      | 'C0402'     | 'EMPTY'   | 'CH2106J1B06'(!)   = ''              | ''                 | ''       | 'CH2106J1B06'     |'C0402'| '(C0402-0201)'                                                       | 'NA'       | '50V'         | '5%'     | 'IO'       | 'CAP CHIP 1000P 50V(+-5%,X7R,0402)AEC'                         | 'CHIP0402'     | ''          | ''   | '20151231'
 '100PF'    | '50V'   | '5%'      | 'C0402'     | 'NPO'     | 'CH1106J0B18'(!)   = ''              | ''                 | ''       | 'CH1106J0B18'     |'C0402'| '(C0402-0201)'                                                       | '100PF'    | '50V'         | '5%'     | 'DISCRETE' | 'CAP CHIP 100P 50V(+-5%,NPO,0402)AEC'                          | 'CHIP0402'     | ''          | ''   | '20151231'
 '100PF'    | '50V'   | '5%'      | 'C0402'     | 'EMPTY'   | 'CH1106J0B18'(!)   = ''              | ''                 | ''       | 'CH1106J0B18'     |'C0402'| '(C0402-0201)'                                                       | 'NA'       | '50V'         | '5%'     | 'IO'       | 'CAP CHIP 100P 50V(+-5%,NPO,0402)AEC'                          | 'CHIP0402'     | ''          | ''   | '20151231'
 '15PF'     | '50V'   | '5%'      | 'C0402'     | 'NPO'     | 'CH0156J0B11'(!)   = ''              | ''                 | ''       | 'CH0156J0B11'     |'C0402'| '(C0402-0201)'                                                       | '15PF'     | '50V'         | '5%'     | 'DISCRETE' | 'CAP CHIP 15P 50V(+-5%,NPO,0402)AEC'                           | 'CHIP0402'     | ''          | ''   | '20151231'
 '15PF'     | '50V'   | '5%'      | 'C0402'     | 'EMPTY'   | 'CH0156J0B11'(!)   = ''              | ''                 | ''       | 'CH0156J0B11'     |'C0402'| '(C0402-0201)'                                                       | 'NA'       | '50V'         | '5%'     | 'IO'       | 'CAP CHIP 15P 50V(+-5%,NPO,0402)AEC'                           | 'CHIP0402'     | ''          | ''   | '20151231'
 '18PF'     | '50V'   | '5%'      | 'C0402'     | 'NPO'     | 'CH0186J0B07'(!)   = ''              | ''                 | ''       | 'CH0186J0B07'     |'C0402'| '(C0402-0201)'                                                       | '18PF'     | '50V'         | '5%'     | 'DISCRETE' | 'CAP CHIP 18P 50V(+-5%,NPO,0402)AEC'                           | 'CHIP0402'     | ''          | ''   | '20151231'
 '18PF'     | '50V'   | '5%'      | 'C0402'     | 'EMPTY'   | 'CH0186J0B07'(!)   = ''              | ''                 | ''       | 'CH0186J0B07'     |'C0402'| '(C0402-0201)'                                                       | 'NA'       | '50V'         | '5%'     | 'IO'       | 'CAP CHIP 18P 50V(+-5%,NPO,0402)AEC'                           | 'CHIP0402'     | ''          | ''   | '20151231'
 '2200PF'   | '50V'   | '10%'     | 'C0402'     | 'X7R'     | 'CH2226K1B13'(!)   = ''              | ''                 | ''       | 'CH2226K1B13'     |'C0402'| '(C0402-0201)'                                                       | '2200PF'   | '50V'         | '10%'    | 'DISCRETE' | 'CAP CHIP 2200P 50V(+-10%,X7R,0402)AEC'                        | 'CHIP0402'     | ''          | ''   | '20151231'
 '2200PF'   | '50V'   | '10%'     | 'C0402'     | 'EMPTY'   | 'CH2226K1B13'(!)   = ''              | ''                 | ''       | 'CH2226K1B13'     |'C0402'| '(C0402-0201)'                                                       | 'NA'       | '50V'         | '10%'    | 'IO'       | 'CAP CHIP 2200P 50V(+-10%,X7R,0402)AEC'                        | 'CHIP0402'     | ''          | ''   | '20151231'
 '22PF'     | '50V'   | '5%'      | 'C0402'     | 'NPO'     | 'CH0226J0B20'(!)   = ''              | ''                 | ''       | 'CH0226J0B20'     |'C0402'| '(C0402-0201)'                                                       | '22PF'     | '50V'         | '5%'     | 'DISCRETE' | 'CAP CHIP 22P 50V(+-5%,NPO,0402)AEC'                           | 'CHIP0402'     | ''          | ''   | '20151231'
 '22PF'     | '50V'   | '5%'      | 'C0402'     | 'EMPTY'   | 'CH0226J0B20'(!)   = ''              | ''                 | ''       | 'CH0226J0B20'     |'C0402'| '(C0402-0201)'                                                       | 'NA'       | '50V'         | '5%'     | 'IO'       | 'CAP CHIP 22P 50V(+-5%,NPO,0402)AEC'                           | 'CHIP0402'     | ''          | ''   | '20151231'
 '3300PF'   | '50V'   | '10%'     | 'C0402'     | 'X7R'     | 'CH2336K1B09'(!)   = ''              | ''                 | ''       | 'CH2336K1B09'     |'C0402'| '(C0402-0201)'                                                       | '3300PF'   | '50V'         | '10%'    | 'DISCRETE' | 'CAP CHIP 3300P 50V(+-10%,X7R,0402)AEC'                        | 'CHIP0402'     | ''          | ''   | '20151231'
 '3300PF'   | '50V'   | '10%'     | 'C0402'     | 'EMPTY'   | 'CH2336K1B09'(!)   = ''              | ''                 | ''       | 'CH2336K1B09'     |'C0402'| '(C0402-0201)'                                                       | 'NA'       | '50V'         | '10%'    | 'IO'       | 'CAP CHIP 3300P 50V(+-10%,X7R,0402)AEC'                        | 'CHIP0402'     | ''          | ''   | '20151231'
 '0.01UF'   | '16V'   | '10%'     | 'C0402'     | 'X7R'     | 'CH3103K1B22'(!)   = ''              | ''                 | ''       | 'CH3103K1B22'     |'C0402'| '(C0402-0201)'                                                       | '0.01UF'   | '16V'         | '10%'    | 'DISCRETE' | 'CAP CHIP 0.01U 16V(+-10%,X7R,0402)AEC'                        | 'CHIP0402'     | ''          | ''   | '20151231'
 '0.01UF'   | '16V'   | '10%'     | 'C0402'     | 'EMPTY'   | 'CH3103K1B22'(!)   = ''              | ''                 | ''       | 'CH3103K1B22'     |'C0402'| '(C0402-0201)'                                                       | 'NA'       | '16V'         | '10%'    | 'IO'       | 'CAP CHIP 0.01U 16V(+-10%,X7R,0402)AEC'                        | 'CHIP0402'     | ''          | ''   | '20151231'
 '0.01UF'   | '25V'   | '10%'     | 'C0402'     | 'X7R'     | 'CH3104K1B14'(!)   = ''              | ''                 | ''       | 'CH3104K1B14'     |'C0402'| '(C0402-0201)'                                                       | '0.01UF'   | '25V'         | '10%'    | 'DISCRETE' | 'CAP CHIP 0.01U 25V(+-10%,X7R,0402)AEC'                        | 'CHIP0402'     | ''          | ''   | '20151231'
 '0.01UF'   | '25V'   | '10%'     | 'C0402'     | 'EMPTY'   | 'CH3104K1B14'(!)   = ''              | ''                 | ''       | 'CH3104K1B14'     |'C0402'| '(C0402-0201)'                                                       | 'NA'       | '25V'         | '10%'    | 'IO'       | 'CAP CHIP 0.01U 25V(+-10%,X7R,0402)AEC'                        | 'CHIP0402'     | ''          | ''   | '20151231'
 '0.1UF'    | '25V'   | '10%'     | 'C0402'     | 'X7R'     | 'CH4104K1B05'(!)   = ''              | ''                 | ''       | 'CH4104K1B05'     |'C0402'| '(C0402-0201)'                                                       | '0.1UF'    | '25V'         | '10%'    | 'DISCRETE' | 'CAP CHIP 0.1U 25V(+-10%,X7R,0402)AEC'                         | 'CHIP0402'     | ''          | ''   | '20160104'
 '0.1UF'    | '25V'   | '10%'     | 'C0402'     | 'EMPTY'   | 'CH4104K1B05'(!)   = ''              | ''                 | ''       | 'CH4104K1B05'     |'C0402'| '(C0402-0201)'                                                       | 'NA'       | '25V'         | '10%'    | 'IO'       | 'CAP CHIP 0.1U 25V(+-10%,X7R,0402)AEC'                         | 'CHIP0402'     | ''          | ''   | '20160104'
 '0.47UF'   | '10V'   | '10%'     | 'C0402'     | 'X7S'     | 'CH4472K6B00'(!)   = ''              | ''                 | ''       | 'CH4472K6B00'     |'C0402'| '(C0402-0201)'                                                       | '0.47UF'   | '10V'         | '10%'    | 'DISCRETE' | 'CAP CHIP 0.47U 10V(+10%,X7S,0402)AEC'                         | 'CHIP0402'     | ''          | ''   | '20160104'
 '0.47UF'   | '10V'   | '10%'     | 'C0402'     | 'EMPTY'   | 'CH4472K6B00'(!)   = ''              | ''                 | ''       | 'CH4472K6B00'     |'C0402'| '(C0402-0201)'                                                       | 'NA'       | '10V'         | '10%'    | 'IO'       | 'CAP CHIP 0.47U 10V(+10%,X7S,0402)AEC'                         | 'CHIP0402'     | ''          | ''   | '20160104'
 '1000PF'   | '50V'   | '10%'     | 'C0402'     | 'X7R'     | 'CH2106K1B24'(!)   = ''              | ''                 | ''       | 'CH2106K1B24'     |'C0402'| '(C0402-0201)'                                                       | '1000PF'   | '50V'         | '10%'    | 'DISCRETE' | 'CAP CHIP 1000P 50V(+10%,X7R,0402)AEC'                         | 'CHIP0402'     | ''          | ''   | '20160104'
 '1000PF'   | '50V'   | '10%'     | 'C0402'     | 'EMPTY'   | 'CH2106K1B24'(!)   = ''              | ''                 | ''       | 'CH2106K1B24'     |'C0402'| '(C0402-0201)'                                                       | 'NA'       | '50V'         | '10%'    | 'IO'       | 'CAP CHIP 1000P 50V(+10%,X7R,0402)AEC'                         | 'CHIP0402'     | ''          | ''   | '20160104'
 '10UF'     | '10V'   | '20%'     | 'C0603'     | 'X6S'     | 'CH6102ME903'(!)   = ''              | ''                 | ''       | 'CH6102ME903'     |'C0603'| '(SMC0603AW)'                                                        | '10UF'     | '10V'         | '20%'    | 'DISCRETE' | 'CAP CHIP 10U 10V(+-20%,X6S,0603)AEC'                          | 'CHIP0603'     | ''          | ''   | '20160104'
 '10UF'     | '10V'   | '20%'     | 'C0603'     | 'EMPTY'   | 'CH6102ME903'(!)   = ''              | ''                 | ''       | 'CH6102ME903'     |'C0603'| '(SMC0603AW)'                                                        | 'NA'       | '10V'         | '20%'    | 'IO'       | 'CAP CHIP 10U 10V(+-20%,X6S,0603)AEC'                          | 'CHIP0603'     | ''          | ''   | '20160104'
 '10UF'     | '4V'    | '20%'     | 'C0603'     | 'X6S'     | 'CH610KME907'(!)   = ''              | ''                 | ''       | 'CH610KME907'     |'C0603'| '(SMC0603AW)'                                                        | '10UF'     | '4V'          | '20%'    | 'DISCRETE' | 'CAP CHIP 10U 4V(+-20%,X6S,0603)AEC'                           | 'CHIP0603'     | ''          | ''   | '20160104'
 '10UF'     | '4V'    | '20%'     | 'C0603'     | 'EMPTY'   | 'CH610KME907'(!)   = ''              | ''                 | ''       | 'CH610KME907'     |'C0603'| '(SMC0603AW)'                                                        | 'NA'       | '4V'          | '20%'    | 'IO'       | 'CAP CHIP 10U 4V(+-20%,X6S,0603)AEC'                           | 'CHIP0603'     | ''          | ''   | '20160104'
 '1UF'      | '16V'   | '10%'     | 'C0603'     | 'X7R'     | 'CH5103K1912'(!)   = ''              | ''                 | ''       | 'CH5103K1912'     |'C0603'| '(SMC0603AW)'                                                        | '1UF'      | '16V'         | '10%'    | 'DISCRETE' | 'CAP CHIP 1U 16V(+-10%,X7R,0603)AEC'                           | 'CHIP0603'     | ''          | ''   | '20160104'
 '1UF'      | '16V'   | '10%'     | 'C0603'     | 'EMPTY'   | 'CH5103K1912'(!)   = ''              | ''                 | ''       | 'CH5103K1912'     |'C0603'| '(SMC0603AW)'                                                        | 'NA'       | '16V'         | '10%'    | 'IO'       | 'CAP CHIP 1U 16V(+-10%,X7R,0603)AEC'                           | 'CHIP0603'     | ''          | ''   | '20160104'
 '1UF'      | '16V'   | '10%'     | 'C0402'     | 'X6S'     | 'CH5103KEB05'(!)   = ''              | ''                 | ''       | 'CH5103KEB05'     |'C0402'| '(C0402-0201)'                                                       | '1UF'      | '16V'         | '10%'    | 'DISCRETE' | 'CAP CHIP 1U 16V(10%,X6S,0402)AEC'                             | 'CHIP0402'     | ''          | ''   | '20160104'
 '1UF'      | '16V'   | '10%'     | 'C0402'     | 'EMPTY'   | 'CH5103KEB05'(!)   = ''              | ''                 | ''       | 'CH5103KEB05'     |'C0402'| '(C0402-0201)'                                                       | 'NA'       | '16V'         | '10%'    | 'IO'       | 'CAP CHIP 1U 16V(10%,X6S,0402)AEC'                             | 'CHIP0402'     | ''          | ''   | '20160104'
 '1UF'      | '25V'   | '10%'     | 'C0402'     | 'X6S'     | 'CH5104KEB05'(!)   = ''              | ''                 | ''       | 'CH5104KEB05'     |'C0402'| '(C0402-0201)'                                                       | '1UF'      | '25V'         | '10%'    | 'DISCRETE' | 'CAP CHIP 1U 25V(+-10%,X6S,0402)AEC'                           | 'CHIP0402'     | ''          | ''   | '20160104'
 '1UF'      | '25V'   | '10%'     | 'C0402'     | 'EMPTY'   | 'CH5104KEB05'(!)   = ''              | ''                 | ''       | 'CH5104KEB05'     |'C0402'| '(C0402-0201)'                                                       | 'NA'       | '25V'         | '10%'    | 'IO'       | 'CAP CHIP 1U 25V(+-10%,X6S,0402)AEC'                           | 'CHIP0402'     | ''          | ''   | '20160104'
 '1UF'      | '6.3V'  | '10%'     | 'C0402'     | 'X7R'     | 'CH5101K1B08'(!)   = ''              | ''                 | ''       | 'CH5101K1B08'     |'C0402'| '(C0402-0201)'                                                       | '1UF'      | '6.3V'        | '10%'    | 'DISCRETE' | 'CAP CHIP 1U 6.3V(+-10%,X7R,0402)AEC'                          | 'CHIP0402'     | ''          | ''   | '20160104'
 '1UF'      | '6.3V'  | '10%'     | 'C0402'     | 'EMPTY'   | 'CH5101K1B08'(!)   = ''              | ''                 | ''       | 'CH5101K1B08'     |'C0402'| '(C0402-0201)'                                                       | 'NA'       | '6.3V'        | '10%'    | 'IO'       | 'CAP CHIP 1U 6.3V(+-10%,X7R,0402)AEC'                          | 'CHIP0402'     | ''          | ''   | '20160104'
 '2.2UF'    | '10V'   | '10%'     | 'C0402'     | 'X6S'     | 'CH5222KEB03'(!)   = ''              | ''                 | ''       | 'CH5222KEB03'     |'C0402'| '(C0402-0201)'                                                       | '2.2UF'    | '10V'         | '10%'    | 'DISCRETE' | 'CAP CHIP 2.2U 10V(+-10%,X6S,0402)AEC'                         | 'CHIP0402'     | ''          | ''   | '20160104'
 '2.2UF'    | '10V'   | '10%'     | 'C0402'     | 'EMPTY'   | 'CH5222KEB03'(!)   = ''              | ''                 | ''       | 'CH5222KEB03'     |'C0402'| '(C0402-0201)'                                                       | 'NA'       | '10V'         | '10%'    | 'IO'       | 'CAP CHIP 2.2U 10V(+-10%,X6S,0402)AEC'                         | 'CHIP0402'     | ''          | ''   | '20160104'
 '10UF'     | '16V'   | '10%'     | 'C0805'     | 'X7S'     | 'CH6103K6A00'(!)   = ''              | ''                 | ''       | 'CH6103K6A00'     |'C0805_H57'| '(SMC0805AW)'                                                        | '10UF'     | '16V'         | '10%'    | 'DISCRETE' | 'CAP CHIP 10U 16V(+-10%,X7S,0805)AEC'                          | 'CHIP0805'     | ''          | ''   | '20160106'
 '10UF'     | '16V'   | '10%'     | 'C0805'     | 'EMPTY'   | 'CH6103K6A00'(!)   = ''              | ''                 | ''       | 'CH6103K6A00'     |'C0805_H57'| '(SMC0805AW)'                                                        | 'NA'       | '16V'         | '10%'    | 'IO'       | 'CAP CHIP 10U 16V(+-10%,X7S,0805)AEC'                          | 'CHIP0805'     | ''          | ''   | '20160106'
 '10UF'     | '6.3V'  | '10%'     | 'C0805'     | 'X7R'     | 'CH6101K1A01'(!)   = ''              | ''                 | ''       | 'CH6101K1A01'     |'C0805_H57'| '(SMC0805AW)'                                                        | '10UF'     | '6.3V'        | '10%'    | 'DISCRETE' | 'CAP CHIP 10U 6.3V(+-10%,X7R,0805)AEC'                         | 'CHIP0805'     | ''          | ''   | '20160106'
 '10UF'     | '6.3V'  | '10%'     | 'C0805'     | 'EMPTY'   | 'CH6101K1A01'(!)   = ''              | ''                 | ''       | 'CH6101K1A01'     |'C0805_H57'| '(SMC0805AW)'                                                        | 'NA'       | '6.3V'        | '10%'    | 'IO'       | 'CAP CHIP 10U 6.3V(+-10%,X7R,0805)AEC'                         | 'CHIP0805'     | ''          | ''   | '20160106'
 '2.2UF'    | '10V'   | '10%'     | 'C0805'     | 'X7R'     | 'CH5222K1A01'(!)   = 'End of Design' | 'Comp-Approve'     | ''       | 'CH5222K1A01'     |'C0805_H57'| '(SMC0805AW)'                                                        | '2.2UF'    | '10V'         | '10%'    | 'DISCRETE' | 'CAP CHIP 2.2U 10V(+-10%,X7R,0805)AEC'                         | 'CHIP0805'     | ''          | ''   | '20160106'
 '2.2UF'    | '10V'   | '10%'     | 'C0805'     | 'EMPTY'   | 'CH5222K1A01'(!)   = 'End of Design' | 'Comp-Approve'     | ''       | 'CH5222K1A01'     |'C0805_H57'| '(SMC0805AW)'                                                        | 'NA'       | '10V'         | '10%'    | 'IO'       | 'CAP CHIP 2.2U 10V(+-10%,X7R,0805)AEC'                         | 'CHIP0805'     | ''          | ''   | '20160106'
 '22UF'     | '10V'   | '20%'     | 'C0805'     | 'X6S'     | 'CH6222MEA03'(!)   = ''              | ''                 | ''       | 'CH6222MEA03'     |'C0805_H57'| '(SMC0805AW)'                                                        | '22UF'     | '10V'         | '20%'    | 'DISCRETE' | 'CAP CHIP 22U 10V(+-20%,X6S,0805)AEC'                          | 'CHIP0805'     | ''          | ''   | '20160106'
 '22UF'     | '10V'   | '20%'     | 'C0805'     | 'EMPTY'   | 'CH6222MEA03'(!)   = ''              | ''                 | ''       | 'CH6222MEA03'     |'C0805_H57'| '(SMC0805AW)'                                                        | 'NA'       | '10V'         | '20%'    | 'IO'       | 'CAP CHIP 22U 10V(+-20%,X6S,0805)AEC'                          | 'CHIP0805'     | ''          | ''   | '20160106'
 '4.7UF'    | '16V'   | '10%'     | 'C0805'     | 'X7R'     | 'CH5473K1A03'(!)   = 'End of Design' | 'Comp-Approve'     | ''       | 'CH5473K1A03'     |'C0805_H57'| '(SMC0805AW)'                                                        | '4.7UF'    | '16V'         | '10%'    | 'DISCRETE' | 'CAP CHIP 4.7UF 16V(+-10%,X7R,0805)AEC'                        | 'CHIP0805'     | ''          | ''   | '20160106'
 '4.7UF'    | '16V'   | '10%'     | 'C0805'     | 'EMPTY'   | 'CH5473K1A03'(!)   = 'End of Design' | 'Comp-Approve'     | ''       | 'CH5473K1A03'     |'C0805_H57'| '(SMC0805AW)'                                                        | 'NA'       | '16V'         | '10%'    | 'IO'       | 'CAP CHIP 4.7UF 16V(+-10%,X7R,0805)AEC'                        | 'CHIP0805'     | ''          | ''   | '20160106'
 '47UF'     | '4V'    | '20%'     | 'C0805'     | 'X6S'     | 'CH647KMEA07'(!)   = ''              | ''                 | ''       | 'CH647KMEA07'     |'C0805_H57'| '(SMC0805AW)'                                                        | '47UF'     | '4V'          | '20%'    | 'DISCRETE' | 'CAP CHIP 47U 4V(+-20%,X6S,0805)AEC'                           | 'CHIP0805'     | ''          | ''   | '20160106'
 '47UF'     | '4V'    | '20%'     | 'C0805'     | 'EMPTY'   | 'CH647KMEA07'(!)   = ''              | ''                 | ''       | 'CH647KMEA07'     |'C0805_H57'| '(SMC0805AW)'                                                        | 'NA'       | '4V'          | '20%'    | 'IO'       | 'CAP CHIP 47U 4V(+-20%,X6S,0805)AEC'                           | 'CHIP0805'     | ''          | ''   | '20160106'
 '22UF'     | '6.3V'  | '20%'     | 'C0805'     | 'X7T'     | 'CH6221MJA00'(!)   = ''              | ''                 | ''       | 'CH6221MJA00'     |'C0805_H57'| '(SMC0805AW)'                                                        | '22UF'     | '6.3V'        | '20%'    | 'DISCRETE' | 'CAP CHIP 22U 6.3V(+-20%,X7T,0805)AEC'                         | 'CHIP0805'     | ''          | ''   | '20160106'
 '22UF'     | '6.3V'  | '20%'     | 'C0805'     | 'EMPTY'   | 'CH6221MJA00'(!)   = ''              | ''                 | ''       | 'CH6221MJA00'     |'C0805_H57'| '(SMC0805AW)'                                                        | 'NA'       | '6.3V'        | '20%'    | 'IO'       | 'CAP CHIP 22U 6.3V(+-20%,X7T,0805)AEC'                         | 'CHIP0805'     | ''          | ''   | '20160106'
 '4.7UF'    | '6.3V'  | '10%'     | 'C0603'     | 'X6S'     | 'CH5471KE905'(!)   = ''              | ''                 | ''       | 'CH5471KE905'     |'C0603'| '(SMC0603AW)'                                                        | '4.7UF'    | '6.3V'        | '10%'    | 'DISCRETE' | 'CAP CHIP 4.7U 6.3V(+-10%,X6S,0603)AEC'                        | 'CHIP0603'     | ''          | ''   | '20160106'
 '4.7UF'    | '6.3V'  | '10%'     | 'C0603'     | 'EMPTY'   | 'CH5471KE905'(!)   = ''              | ''                 | ''       | 'CH5471KE905'     |'C0603'| '(SMC0603AW)'                                                        | 'NA'       | '6.3V'        | '10%'    | 'IO'       | 'CAP CHIP 4.7U 6.3V(+-10%,X6S,0603)AEC'                        | 'CHIP0603'     | ''          | ''   | '20160106'
 '470PF'    | '50V'   | '10%'     | 'C0402'     | 'X7R'     | 'CH1476K1B13'(!)   = ''              | ''                 | ''       | 'CH1476K1B13'     |'C0402'| '(C0402-0201)'                                                       | '470PF'    | '50V'         | '10%'    | 'DISCRETE' | 'CAP CHIP 470P 50V(+10%,X7R,0402)AEC'                          | 'CHIP0402'     | ''          | ''   | '20160106'
 '470PF'    | '50V'   | '10%'     | 'C0402'     | 'EMPTY'   | 'CH1476K1B13'(!)   = ''              | ''                 | ''       | 'CH1476K1B13'     |'C0402'| '(C0402-0201)'                                                       | 'NA'       | '50V'         | '10%'    | 'IO'       | 'CAP CHIP 470P 50V(+10%,X7R,0402)AEC'                          | 'CHIP0402'     | ''          | ''   | '20160106'
 '47PF'     | '50V'   | '5%'      | 'C0402'     | 'C0G'     | 'CH0476J0B13'(!)   = ''              | ''                 | ''       | 'CH0476J0B13'     |'C0402'| '(C0402-0201)'                                                       | '47PF'     | '50V'         | '5%'     | 'DISCRETE' | 'CAP CHIP 47P 50V(+5%,C0G,0402)AEC'                            | 'CHIP0402'     | ''          | ''   | '20160106'
 '47PF'     | '50V'   | '5%'      | 'C0402'     | 'EMPTY'   | 'CH0476J0B13'(!)   = ''              | ''                 | ''       | 'CH0476J0B13'     |'C0402'| '(C0402-0201)'                                                       | 'NA'       | '50V'         | '5%'     | 'IO'       | 'CAP CHIP 47P 50V(+5%,C0G,0402)AEC'                            | 'CHIP0402'     | ''          | ''   | '20160106'
 '10UF'     | '6.3V'  | '20%'     | 'C0402'     | 'X6S'     | 'CH6101MEB03'(!)   = ''              | ''                 | ''       | 'CH6101MEB03'     |'C0402'| '(C0402_OCTAGONXA,C0402-0201)'                                       | '10UF'     | '6.3V'        | '20%'    | 'DISCRETE' | 'CAP CHIP 10UF 6.3V(+-20%,X6S,0402)MUR'                        | 'CHIP0402'     | ''          | ''   | '20160111'
 '10UF'     | '6.3V'  | '20%'     | 'C0402'     | 'EMPTY'   | 'CH6101MEB03'(!)   = ''              | ''                 | ''       | 'CH6101MEB03'     |'C0402'| '(C0402_OCTAGONXA,C0402-0201)'                                       | 'NA'       | '6.3V'        | '20%'    | 'IO'       | 'CAP CHIP 10UF 6.3V(+-20%,X6S,0402)MUR'                        | 'CHIP0402'     | ''          | ''   | '20160111'
 '47UF'     | '6.3V'  | '20%'     | 'C1206'     | 'X6S'     | 'CH6471ME203'(!)   = ''              | ''                 | ''       | 'CH6471ME203'     |'C1206_H76'| '(SMC1206AW)'                                                        | '47UF'     | '6.3V'        | '20%'    | 'DISCRETE' | 'CAP CHIP 47U 6.3V(+-20%,X6S,1206)AEC'                         | 'CHIP1206'     | ''          | ''   | '20160111'
 '47UF'     | '6.3V'  | '20%'     | 'C1206'     | 'EMPTY'   | 'CH6471ME203'(!)   = ''              | ''                 | ''       | 'CH6471ME203'     |'C1206_H76'| '(SMC1206AW)'                                                        | 'NA'       | '6.3V'        | '20%'    | 'IO'       | 'CAP CHIP 47U 6.3V(+-20%,X6S,1206)AEC'                         | 'CHIP1206'     | ''          | ''   | '20160111'
 '22UF'     | '25V'   | '10%'     | 'C1206'     | 'X5R'     | 'CH6224K9203'(!)   = ''              | ''                 | ''       | 'CH6224K9203'     |'C1206_H76'| '(SMC1206AW)'                                                        | '22UF'     | '25V'         | '10%'    | 'DISCRETE' | 'CAP CHIP 22U 25V(+-10%,X5R,1206)AEC'                          | 'CHIP1206'     | ''          | ''   | '20160111'
 '22UF'     | '25V'   | '10%'     | 'C1206'     | 'EMPTY'   | 'CH6224K9203'(!)   = ''              | ''                 | ''       | 'CH6224K9203'     |'C1206_H76'| '(SMC1206AW)'                                                        | 'NA'       | '25V'         | '10%'    | 'IO'       | 'CAP CHIP 22U 25V(+-10%,X5R,1206)AEC'                          | 'CHIP1206'     | ''          | ''   | '20160111'
 '10UF'     | '25V'   | '10%'     | 'C1206'     | 'X7S'     | 'CH6104K6200'(!)   = ''              | ''                 | ''       | 'CH6104K6200'     |'C1206_H76'| '(SMC1206AW)'                                                        | '10UF'     | '25V'         | '10%'    | 'DISCRETE' | 'CAP CHIP 10U 25V(+-10%,X7S,1206)AEC'                          | 'CHIP1206'     | ''          | ''   | '20160111'
 '10UF'     | '25V'   | '10%'     | 'C1206'     | 'EMPTY'   | 'CH6104K6200'(!)   = ''              | ''                 | ''       | 'CH6104K6200'     |'C1206_H76'| '(SMC1206AW)'                                                        | 'NA'       | '25V'         | '10%'    | 'IO'       | 'CAP CHIP 10U 25V(+-10%,X7S,1206)AEC'                          | 'CHIP1206'     | ''          | ''   | '20160111'
 '10UF'     | '16V'   | '10%'     | 'C1206'     | 'X7R'     | 'CH6103K1202'(!)   = ''              | ''                 | ''       | 'CH6103K1202'     |'C1206_H76'| '(SMC1206AW)'                                                        | '10UF'     | '16V'         | '10%'    | 'DISCRETE' | 'CAP CHIP 10U 16V(+-10%,X7R,1206)AEC'                          | 'CHIP1206'     | ''          | ''   | '20160111'
 '10UF'     | '16V'   | '10%'     | 'C1206'     | 'EMPTY'   | 'CH6103K1202'(!)   = ''              | ''                 | ''       | 'CH6103K1202'     |'C1206_H76'| '(SMC1206AW)'                                                        | 'NA'       | '16V'         | '10%'    | 'IO'       | 'CAP CHIP 10U 16V(+-10%,X7R,1206)AEC'                          | 'CHIP1206'     | ''          | ''   | '20160111'
 '0.01UF'   | '50V'   | '5%'      | 'C0603'     | 'X7R'     | 'CH3106J1900'(!)   = 'End of Design' | 'Comp-Approve'     | ''       | 'CH3106J1900'     |'C0603'| '(SMC0603AW)'                                                        | '0.01UF'   | '50V'         | '10%'    | 'DISCRETE' | 'CAP CHIP 0.01U 50V(+-5%,X7R,0603)MUR'                         | 'CHIP0603'     | ''          | ''   | '20161113'
 '0.01UF'   | '50V'   | '5%'      | 'C0603'     | 'EMPTY'   | 'CH3106J1900'(!)   = 'End of Design' | 'Comp-Approve'     | ''       | 'CH3106J1900'     |'C0603'| '(SMC0603AW)'                                                        | 'NA'       | '50V'         | '10%'    | 'IO'       | 'CAP CHIP 0.01U 50V(+-5%,X7R,0603)MUR'                         | 'CHIP0603'     | ''          | ''   | '20161113'
 '0.1UF'    | '25V'   | '10%'     | '0402'      | 'X7R'     | 'CH4104K1B00'(!)   = ''              | ''                 | ''       | 'CH4104K1B00'     |'C0402'| '(C0402_OCTAGONXA,C0402-0201)'                                       | '0.1UF'    | '25V'         | '10%'    | 'DISCRETE' | 'CAP CHIP 0.1U 25V(+-10%,X7R,0402)'                            | 'CHIP0402'     | ''          | ''   | '20160113'
 '0.1UF'    | '25V'   | '10%'     | '0402'      | 'EMPTY'   | 'CH4104K1B00'(!)   = ''              | ''                 | ''       | 'CH4104K1B00'     |'C0402'| '(C0402_OCTAGONXA,C0402-0201)'                                       | 'NA'       | '25V'         | '10%'    | 'IO'       | 'CAP CHIP 0.1U 25V(+-10%,X7R,0402)'                            | 'CHIP0402'     | ''          | ''   | '20160113'
 '0.033UF'  | '50V'   | '10%'     | 'C0603'     | 'X7R'     | 'CH3336K1905'(!)   = 'End of Design' | 'Comp-Approve'     | ''       | 'CH3336K1905'     |'C0603'| '(SMC0603AW)'                                                        | '0.033UF'  | '50V'         | '10%'    | 'DISCRETE' | 'CAP CHIP 0.033U 50V(+-10%,X7R,0603)MUR'                       | 'CHIP0603'     | ''          | ''   | '20160114'
 '0.033UF'  | '50V'   | '10%'     | 'C0603'     | 'EMPTY'   | 'CH3336K1905'(!)   = 'End of Design' | 'Comp-Approve'     | ''       | 'CH3336K1905'     |'C0603'| '(SMC0603AW)'                                                        | 'NA'       | '50V'         | '10%'    | 'IO'       | 'CAP CHIP 0.033U 50V(+-10%,X7R,0603)MUR'                       | 'CHIP0603'     | ''          | ''   | '20160114'
 '8200PF'   | '25V'   | '10%'     | 'C0402'     | 'X7R'     | 'CH2824K1B04'(!)   = ''              | ''                 | ''       | 'CH2824K1B04'     |'C0402'| '(C0402-0201)'                                                       | '8200PF'   | '25V'         | '10%'    | 'DISCRETE' | 'CAP CHIP 8200P 25V (+-10%.X7R.0402)MUR'                       | 'CHIP0402'     | ''          | ''   | '20160115'
 '8200PF'   | '25V'   | '10%'     | 'C0402'     | 'EMPTY'   | 'CH2824K1B04'(!)   = ''              | ''                 | ''       | 'CH2824K1B04'     |'C0402'| '(C0402-0201)'                                                       | 'NA'       | '25V'         | '10%'    | 'IO'       | 'CAP CHIP 8200P 25V (+-10%.X7R.0402)MUR'                       | 'CHIP0402'     | ''          | ''   | '20160115'
 '22UF'     | '25V'   | '20%'     | 'C1206'     | 'X7S'     | 'CH6224M6201'(!)   = ''              | ''                 | ''       | 'CH6224M6201'     |'C1206_H76'| '(SMC1206AW)'                                                        | '22UF'     | '25V'         | '20%'    | 'DISCRETE' | 'CAP CHIP 22UF 25V(+-20%,X7S,1206)MUR'                         | 'CHIP1206'     | ''          | ''   | '20160115'
 '22UF'     | '25V'   | '20%'     | 'C1206'     | 'EMPTY'   | 'CH6224M6201'(!)   = ''              | ''                 | ''       | 'CH6224M6201'     |'C1206_H76'| '(SMC1206AW)'                                                        | 'NA'       | '25V'         | '20%'    | 'IO'       | 'CAP CHIP 22UF 25V(+-20%,X7S,1206)MUR'                         | 'CHIP1206'     | ''          | ''   | '20160115'
 '6800PF'   | '50V'   | '10%'     | 'C0402'     | 'X7R'     | 'CH2686K1B03'(!)   = ''              | ''                 | ''       | 'CH2686K1B03'     |'C0402'| '(C0402-0201)'                                                       | '6800PF'   | '50V'         | '10%'    | 'DISCRETE' | 'CAP CHIP 6800P 50V(+-10%,X7R,0402)MUR'                        | 'CHIP0402'     | ''          | ''   | '20160118'
 '6800PF'   | '50V'   | '10%'     | 'C0402'     | 'EMPTY'   | 'CH2686K1B03'(!)   = ''              | ''                 | ''       | 'CH2686K1B03'     |'C0402'| '(C0402-0201)'                                                       | 'NA'       | '50V'         | '10%'    | 'IO'       | 'CAP CHIP 6800P 50V(+-10%,X7R,0402)MUR'                        | 'CHIP0402'     | ''          | ''   | '20160118'
 '10UF'     | '10V'   | '20%'     | 'C0402'     | 'X5R'     | 'CH6102M9B00'(!)   = ''              | ''                 | ''       | 'CH6102M9B00'     |'C0402'| '(C0402-0201)'                                                       | '10UF'     | '10V'         | '20%'    | 'DISCRETE' | 'CAP CHIP 10U 10V (+-20%, X5R, 0402)'                          | 'CHIP0402'     | ''          | ''   | '20160118'
 '10UF'     | '10V'   | '20%'     | 'C0402'     | 'EMPTY'   | 'CH6102M9B00'(!)   = ''              | ''                 | ''       | 'CH6102M9B00'     |'C0402'| '(C0402-0201)'                                                       | 'NA'       | '10V'         | '20%'    | 'IO'       | 'CAP CHIP 10U 10V (+-20%, X5R, 0402)'                          | 'CHIP0402'     | ''          | ''   | '20160118'
 '22UF'     | '16V'   | '20%'     | 'C0805'     | 'X6S'     | 'CH6223MEA00'(!)   = ''              | ''                 | ''       | 'CH6223MEA00'     |'C0805_H57'| '(SMC0805AW)'                                                        | '22UF'     | '16V'         | '20%'    | 'DISCRETE' | 'CAP CHIP 22U 16V(+-20%,X6S,0805)'                             | 'CHIP0805'     | ''          | ''   | '2016019' 
 '22UF'     | '16V'   | '20%'     | 'C0805'     | 'EMPTY'   | 'CH6223MEA00'(!)   = ''              | ''                 | ''       | 'CH6223MEA00'     |'C0805_H57'| '(SMC0805AW)'                                                        | 'NA'       | '16V'         | '20%'    | 'IO'       | 'CAP CHIP 22U 16V(+-20%,X6S,0805)'                             | 'CHIP0805'     | ''          | ''   | '2016019' 
 '47NF'     | '100V'  | '10%'     | 'C1206'     | 'X7R'     | 'CH3478K1200'(!)   = ''              | ''                 | ''       | 'CH3478K1200'     |'C1206_H56'| '(SMC1206AW)'                                                        | '47NF'     | '100V'        | '10%'    | 'DISCRETE' | 'CAP CHIP 47N 100V (+-10%,X7R,1206)MUR'                        | 'CHIP1206'     | ''          | ''   | '20160219'
 '47NF'     | '100V'  | '10%'     | 'C1206'     | 'EMPTY'   | 'CH3478K1200'(!)   = ''              | ''                 | ''       | 'CH3478K1200'     |'C1206_H56'| '(SMC1206AW)'                                                        | 'NA'       | '100V'        | '10%'    | 'IO'       | 'CAP CHIP 47N 100V (+-10%,X7R,1206)MUR'                        | 'CHIP1206'     | ''          | ''   | '20160219'
 '22UF'     | '10V'   | '20%'     | 'C0805'     | 'X5R'     | 'CH6222M9A02'(!)   = 'End of Design' | 'Comp-Approve'     | ''       | 'CH6222M9A02'     |'C0805_H61'| '(SMC0805AW)'                                                        | '22UF'     | '10V'         | '20%'    | 'DISCRETE' | 'CAP CHIP 22U 10V(+-20%,X5R,0805)'                             | 'CHIP0805'     | ''          | ''   | '20160226'
 '22UF'     | '10V'   | '20%'     | 'C0805'     | 'EMPTY'   | 'CH6222M9A02'(!)   = 'End of Design' | 'Comp-Approve'     | ''       | 'CH6222M9A02'     |'C0805_H61'| '(SMC0805AW)'                                                        | 'NA'       | '10V'         | '20%'    | 'IO'       | 'CAP CHIP 22U 10V(+-20%,X5R,0805)'                             | 'CHIP0805'     | ''          | ''   | '20160226'
 '33000PF'  | '50V'   | '5%'      | 'C0805'     | 'U2J'     | 'CH3336JFA00'(!)   = ''              | ''                 | ''       | 'CH3336JFA00'     |'C0805_H43'| '(SMC0805AW)'                                                        | '33000PF'  | '50V'         | '5%'     | 'DISCRETE' | 'CAP CHIP 33000P 50V(+-5%,U2J,0805)'                           | 'CHIP0805'     | ''          | ''   | '20160310'
 '33000PF'  | '50V'   | '5%'      | 'C0805'     | 'EMPTY'   | 'CH3336JFA00'(!)   = ''              | ''                 | ''       | 'CH3336JFA00'     |'C0805_H43'| '(SMC0805AW)'                                                        | 'NA'       | '50V'         | '5%'     | 'IO'       | 'CAP CHIP 33000P 50V(+-5%,U2J,0805)'                           | 'CHIP0805'     | ''          | ''   | '20160310'
 '39000PF'  | '50V'   | '5%'      | 'C0805'     | 'U2J'     | 'CH3396JFA00'(!)   = ''              | ''                 | ''       | 'CH3396JFA00'     |'C0805_H57'| '(SMC0805AW)'                                                        | '39000PF'  | '50V'         | '5%'     | 'DISCRETE' | 'CAP CHIP 39000P 50V(+-5%,U2J,0805)'                           | 'CHIP0805'     | ''          | ''   | '20160310'
 '39000PF'  | '50V'   | '5%'      | 'C0805'     | 'EMPTY'   | 'CH3396JFA00'(!)   = ''              | ''                 | ''       | 'CH3396JFA00'     |'C0805_H57'| '(SMC0805AW)'                                                        | 'NA'       | '50V'         | '5%'     | 'IO'       | 'CAP CHIP 39000P 50V(+-5%,U2J,0805)'                           | 'CHIP0805'     | ''          | ''   | '20160310'
 '220PF'    | '50V'   | '5%'      | 'C0402'     | 'C0G'     | 'CH12206JB00'(!)   = ''              | ''                 | ''       | 'CH12206JB00'     |'C0402'| '(C0402-0201)'                                                       | '220PF'    | '50V'         | '5%'     | 'DISCRETE' | 'CAP CHIP 220P 50V(+-5%.COG.0402)'                             | 'CHIP0402'     | ''          | ''   | '20160314'
 '220PF'    | '50V'   | '5%'      | 'C0402'     | 'EMPTY'   | 'CH12206JB00'(!)   = ''              | ''                 | ''       | 'CH12206JB00'     |'C0402'| '(C0402-0201)'                                                       | 'NA'       | '50V'         | '5%'     | 'IO'       | 'CAP CHIP 220P 50V(+-5%.COG.0402)'                             | 'CHIP0402'     | ''          | ''   | '20160314'
 '560PF'    | '50V'   | '5%'      | 'C0402'     | 'C0G'     | 'CH1566J0B00'(!)   = ''              | ''                 | ''       | 'CH1566J0B00'     |'C0402'| '(C0402-0201)'                                                       | '560PF'    | '50V'         | '5%'     | 'DISCRETE' | 'CAP CHIP 560P 50V(+-5%,C0G,0402)'                             | 'CHIP0402'     | ''          | ''   | '20160314'
 '560PF'    | '50V'   | '5%'      | 'C0402'     | 'EMPTY'   | 'CH1566J0B00'(!)   = ''              | ''                 | ''       | 'CH1566J0B00'     |'C0402'| '(C0402-0201)'                                                       | 'NA'       | '50V'         | '5%'     | 'IO'       | 'CAP CHIP 560P 50V(+-5%,C0G,0402)'                             | 'CHIP0402'     | ''          | ''   | '20160314'
 '1200PF'   | '50V'   | '10%'     | 'C0402'     | 'X7R'     | 'CH2126K1B05'(!)   = ''              | ''                 | ''       | 'CH2126K1B05'     |'C0402'| '(C0402-0201)'                                                       | '1200PF'   | '50V'         | '10%'    | 'DISCRETE' | 'CAP CHIP 1200P 50V(+-10%.X7R.0402)'                           | 'CHIP0402'     | ''          | ''   | '20160322'
 '1200PF'   | '50V'   | '10%'     | 'C0402'     | 'EMPTY'   | 'CH2126K1B05'(!)   = ''              | ''                 | ''       | 'CH2126K1B05'     |'C0402'| '(C0402-0201)'                                                       | 'NA'       | '50V'         | '10%'    | 'IO'       | 'CAP CHIP 1200P 50V(+-10%.X7R.0402)'                           | 'CHIP0402'     | ''          | ''   | '20160322'
 '0.01UF'   | '100V'  | '5%'      | 'C1206'     | 'C0G'     | 'CH3108J0200'(!)   = ''              | ''                 | ''       | 'CH3108J0200'     |'C1206_H42'| '(SMC1206AW)'                                                        | '0.01UF'   | '100V'        | '5%'     | 'DISCRETE' | 'CAP CHIP 0.01U 100V(+-5%,C0G,1206)MUR'                        | 'CHIP1206'     | ''          | ''   | '20160324'
 '0.01UF'   | '100V'  | '5%'      | 'C1206'     | 'EMPTY'   | 'CH3108J0200'(!)   = ''              | ''                 | ''       | 'CH3108J0200'     |'C1206_H42'| '(SMC1206AW)'                                                        | 'NA'       | '100V'        | '5%'     | 'IO'       | 'CAP CHIP 0.01U 100V(+-5%,C0G,1206)MUR'                        | 'CHIP1206'     | ''          | ''   | '20160324'
 '27PF'     | '50V'   | '5%'      | 'C0402'     | 'C0G'     | 'CH0276J0B07'(!)   = ''              | ''                 | ''       | 'CH0276J0B07'     |'C0402'| '(C0402-0201)'                                                       | '27PF'     | '50V'         | '5%'     | 'DISCRETE' | 'CAP CHIP 27P 50V(+-5%,C0G,0402)AEC'                           | 'CHIP0402'     | ''          | ''   | '20160328'
 '27PF'     | '50V'   | '5%'      | 'C0402'     | 'EMPTY'   | 'CH0276J0B07'(!)   = ''              | ''                 | ''       | 'CH0276J0B07'     |'C0402'| '(C0402-0201)'                                                       | 'NA'       | '50V'         | '5%'     | 'IO'       | 'CAP CHIP 27P 50V(+-5%,C0G,0402)AEC'                           | 'CHIP0402'     | ''          | ''   | '20160328'
 '1UF'      | '10V'   | '10%'     | 'C0402'     | 'X7S'     | 'CH5102K6B01'(!)   = ''              | ''                 | ''       | 'CH5102K6B01'     |'C0402'| '(C0402-0201)'                                                       | '1UF'      | '10V'         | '10%'    | 'DISCRETE' | 'CAP CHIP 1U 10V(10%,X7S,0402)AEC'                             | 'CHIP0402'     | ''          | ''   | '20160328'
 '1UF'      | '10V'   | '10%'     | 'C0402'     | 'EMPTY'   | 'CH5102K6B01'(!)   = ''              | ''                 | ''       | 'CH5102K6B01'     |'C0402'| '(C0402-0201)'                                                       | 'NA'       | '10V'         | '10%'    | 'IO'       | 'CAP CHIP 1U 10V(10%,X7S,0402)AEC'                             | 'CHIP0402'     | ''          | ''   | '20160328'
 '0.22UF'   | '16V'   | '10%'     | 'C0402'     | 'X7R'     | 'CH4223K1B07'(!)   = ''              | ''                 | ''       | 'CH4223K1B07'     |'C0402'| '(C0402-0201)'                                                       | '0.22UF'   | '16V'         | '10%'    | 'DISCRETE' | 'CAP CHIP 0.22U 16V(10%,X7R,0402)MUR_AEC'                      | 'CHIP0402'     | ''          | ''   | '20160518'
 '0.22UF'   | '16V'   | '10%'     | 'C0402'     | 'EMPTY'   | 'CH4223K1B07'(!)   = ''              | ''                 | ''       | 'CH4223K1B07'     |'C0402'| '(C0402-0201)'                                                       | 'NA'       | '16V'         | '10%'    | 'IO'       | 'CAP CHIP 0.22U 16V(10%,X7R,0402)MUR_AEC'                      | 'CHIP0402'     | ''          | ''   | '20160518'
 '0.01UF'   | '50V'   | '10%'     | 'C0402'     | 'X7R'     | 'CH3106K1B09'(!)   = ''              | ''                 | ''       | 'CH3106K1B09'     |'C0402'| '(C0402-0201)'                                                       | '0.01UF'   | '50V'         | '10%'    | 'DISCRETE' | 'CAP CHIP 0.01U 50V(10%,X7R,0402)MUR_AEC'                      | 'CHIP0402'     | ''          | ''   | '20160518'
 '0.01UF'   | '50V'   | '10%'     | 'C0402'     | 'EMPTY'   | 'CH3106K1B09'(!)   = ''              | ''                 | ''       | 'CH3106K1B09'     |'C0402'| '(C0402-0201)'                                                       | 'NA'       | '50V'         | '10%'    | 'IO'       | 'CAP CHIP 0.01U 50V(10%,X7R,0402)MUR_AEC'                      | 'CHIP0402'     | ''          | ''   | '20160518'
 '330PF'    | '50V'   | '10%'     | 'C0402'     | 'X7R'     | 'CH1336K1B08'(!)   = ''              | ''                 | ''       | 'CH1336K1B08'     |'C0402'| '(C0402-0201)'                                                       | '330PF'    | '50V'         | '10%'    | 'DISCRETE' | 'CAP CHIP 330P 50V(10%,X7R,0402)MUR_AEC'                       | 'CHIP0402'     | ''          | ''   | '20160520'
 '330PF'    | '50V'   | '10%'     | 'C0402'     | 'EMPTY'   | 'CH1336K1B08'(!)   = ''              | ''                 | ''       | 'CH1336K1B08'     |'C0402'| '(C0402-0201)'                                                       | 'NA'       | '50V'         | '10%'    | 'IO'       | 'CAP CHIP 330P 50V(10%,X7R,0402)MUR_AEC'                       | 'CHIP0402'     | ''          | ''   | '20160520'
 '0.1UF'    | '16V'   | '10%'     | 'C0402'     | 'X7R'     | 'CH4103K1B22'(!)   = 'End of Design' | 'Comp-Approve'     | ''       | 'CH4103K1B22'     |'C0402'| '(C0402_OCTAGONXA,C0402-0201)'                                       | '0.1UF'    | '16V'         | '10%'    | 'DISCRETE' | 'CAP CHIP 0.1U 16V(10%,X7R,0402)MUR_AEC'                       | 'CHIP0402'     | ''          | ''   | '20160520'
 '0.1UF'    | '16V'   | '10%'     | 'C0402'     | 'EMPTY'   | 'CH4103K1B22'(!)   = 'End of Design' | 'Comp-Approve'     | ''       | 'CH4103K1B22'     |'C0402'| '(C0402_OCTAGONXA,C0402-0201)'                                       | 'NA'       | '16V'         | '10%'    | 'IO'       | 'CAP CHIP 0.1U 16V(10%,X7R,0402)MUR_AEC'                       | 'CHIP0402'     | ''          | ''   | '20160520'
 '2.2UF'    | '10V'   | '10%'     | 'C0402'     | 'X6S'     | 'CH5222KEB05'(!)   = ''              | ''                 | ''       | 'CH5222KEB05'     |'C0402'| '(C0402_OCTAGONXA,C0402-0201)'                                       | '2.2UF'    | '10V'         | '10%'    | 'DISCRETE' | 'CAP CHIP 2.2U 10V(10%,X6S,0402)MUR_AEC'                       | 'CHIP0402'     | ''          | ''   | '20160520'
 '2.2UF'    | '10V'   | '10%'     | 'C0402'     | 'EMPTY'   | 'CH5222KEB05'(!)   = ''              | ''                 | ''       | 'CH5222KEB05'     |'C0402'| '(C0402_OCTAGONXA,C0402-0201)'                                       | 'NA'       | '10V'         | '10%'    | 'IO'       | 'CAP CHIP 2.2U 10V(10%,X6S,0402)MUR_AEC'                       | 'CHIP0402'     | ''          | ''   | '20160520'
 '1UF'      | '6.3V'  | '10%'     | 'C0402'     | 'X7R'     | 'CH5101K1B09'(!)   = ''              | ''                 | ''       | 'CH5101K1B09'     |'C0402'| '(C0402_OCTAGONXA,C0402-0201)'                                       | '1UF'      | '6.3V'        | '10%'    | 'DISCRETE' | 'CAP CHIP 1U 6.3V(10%,X7R,0402)MUR_AEC'                        | 'CHIP0402'     | ''          | ''   | '20160520'
 '1UF'      | '6.3V'  | '10%'     | 'C0402'     | 'EMPTY'   | 'CH5101K1B09'(!)   = ''              | ''                 | ''       | 'CH5101K1B09'     |'C0402'| '(C0402_OCTAGONXA,C0402-0201)'                                       | 'NA'       | '6.3V'        | '10%'    | 'IO'       | 'CAP CHIP 1U 6.3V(10%,X7R,0402)MUR_AEC'                        | 'CHIP0402'     | ''          | ''   | '20160520'
 '0.022UF'  | '25V'   | '10%'     | 'C0402'     | 'X7R'     | 'CH3224K1B03'(!)   = ''              | ''                 | ''       | 'CH3224K1B03'     |'C0402'| '(C0402_OCTAGONXA,C0402-0201)'                                       | '0.022UF'  | '25V'         | '10%'    | 'DISCRETE' | 'CAP CHIP 0.022U 25V(+-10%,X7R,0402)MUR'                       | 'CHIP0402'     | ''          | ''   | '20160520'
 '0.022UF'  | '25V'   | '10%'     | 'C0402'     | 'EMPTY'   | 'CH3224K1B03'(!)   = ''              | ''                 | ''       | 'CH3224K1B03'     |'C0402'| '(C0402_OCTAGONXA,C0402-0201)'                                       | 'NA'       | '25V'         | '10%'    | 'IO'       | 'CAP CHIP 0.022U 25V(+-10%,X7R,0402)MUR'                       | 'CHIP0402'     | ''          | ''   | '20160520'
 '0.047UF'  | '25V'   | '10%'     | 'C0402'     | 'X7R'     | 'CH3474K1B07'(!)   = ''              | ''                 | ''       | 'CH3474K1B07'     |'C0402'| '(C0402_OCTAGONXA,C0402-0201)'                                       | '0.047UF'  | '25V'         | '10%'    | 'DISCRETE' | 'CAP CHIP 0.047U 25V(+10% X7R 0402)AEC'                        | 'CHIP0402'     | ''          | ''   | '20160520'
 '0.047UF'  | '25V'   | '10%'     | 'C0402'     | 'EMPTY'   | 'CH3474K1B07'(!)   = ''              | ''                 | ''       | 'CH3474K1B07'     |'C0402'| '(C0402_OCTAGONXA,C0402-0201)'                                       | 'NA'       | '25V'         | '10%'    | 'IO'       | 'CAP CHIP 0.047U 25V(+10% X7R 0402)AEC'                        | 'CHIP0402'     | ''          | ''   | '20160520'
 '10PF'     | '50V'   | '2%'      | 'C0402'     | 'NPO'     | 'CH0106G0B04'(!)   = ''              | ''                 | ''       | 'CH0106G0B04'     |'C0402'| '(C0402_OCTAGONXA,C0402-0201)'                                       | '10PF'     | '50V'         | '2%'     | 'DISCRETE' | 'CAP CHIP 10P 50V(+-2%,NPO,0402)AEC'                           | 'CHIP0402'     | ''          | ''   | '20160520'
 '10PF'     | '50V'   | '2%'      | 'C0402'     | 'EMPTY'   | 'CH0106G0B04'(!)   = ''              | ''                 | ''       | 'CH0106G0B04'     |'C0402'| '(C0402_OCTAGONXA,C0402-0201)'                                       | 'NA'       | '50V'         | '2%'     | 'IO'       | 'CAP CHIP 10P 50V(+-2%,NPO,0402)AEC'                           | 'CHIP0402'     | ''          | ''   | '20160520'
 '0.01UF'   | '50V'   | '10%'     | 'C0402'     | 'X7R'     | 'CH3106K1B08'(!)   = ''              | ''                 | ''       | 'CH3106K1B08'     |'C0402'| '(C0402_OCTAGONXA,C0402-0201)'                                       | '0.01UF'   | '50V'         | '10%'    | 'DISCRETE' | 'CAP CHIP 0.01U 50V(+-10%,X7R,0402)AEC'                        | 'CHIP0402'     | ''          | ''   | '20160520'
 '0.01UF'   | '50V'   | '10%'     | 'C0402'     | 'EMPTY'   | 'CH3106K1B08'(!)   = ''              | ''                 | ''       | 'CH3106K1B08'     |'C0402'| '(C0402_OCTAGONXA,C0402-0201)'                                       | 'NA'       | '50V'         | '10%'    | 'IO'       | 'CAP CHIP 0.01U 50V(+-10%,X7R,0402)AEC'                        | 'CHIP0402'     | ''          | ''   | '20160520'
 '4700PF'   | '25V'   | '10%'     | 'C0402'     | 'X7R'     | 'CH2474K1B10'(!)   = ''              | ''                 | ''       | 'CH2474K1B10'     |'C0402'| '(C0402_OCTAGONXA,C0402-0201)'                                       | '4700PF'   | '25V'         | '10%'    | 'DISCRETE' | 'CAP CHIP 4700P 25V(+-10%,X7R,0402)AEC'                        | 'CHIP0402'     | ''          | ''   | '20160520'
 '4700PF'   | '25V'   | '10%'     | 'C0402'     | 'EMPTY'   | 'CH2474K1B10'(!)   = ''              | ''                 | ''       | 'CH2474K1B10'     |'C0402'| '(C0402_OCTAGONXA,C0402-0201)'                                       | 'NA'       | '25V'         | '10%'    | 'IO'       | 'CAP CHIP 4700P 25V(+-10%,X7R,0402)AEC'                        | 'CHIP0402'     | ''          | ''   | '20160520'
 '4.7UF'    | '6.3V'  | '20%'     | 'C0402'     | 'X6S'     | 'CH5471MEB02'(!)   = ''              | ''                 | ''       | 'CH5471MEB02'     |'C0402'| '(C0402_OCTAGON,C0402_OCTAGONXA,C0402-0201,C0402_OCTAGONXA_BOUND22)' | '4.7UF'    | '6.3V'        | '20%'    | 'DISCRETE' | 'CAP CHIP 4.7UF 6.3V(+-20%,X6S,0402)MUR'                       | 'CHIP0402'     | ''          | ''   | '20160520'
 '4.7UF'    | '6.3V'  | '20%'     | 'C0402'     | 'EMPTY'   | 'CH5471MEB02'(!)   = ''              | ''                 | ''       | 'CH5471MEB02'     |'C0402'| '(C0402_OCTAGON,C0402_OCTAGONXA,C0402-0201,C0402_OCTAGONXA_BOUND22)' | 'NA'       | '6.3V'        | '20%'    | 'IO'       | 'CAP CHIP 4.7UF 6.3V(+-20%,X6S,0402)MUR'                       | 'CHIP0402'     | ''          | ''   | '20160520'
 '0.01UF'   | '16V'   | '10%'     | 'C0402'     | 'X7R'     | 'CH3103K1B16'(!)   = ''              | ''                 | ''       | 'CH3103K1B16'     |'C0402'| '(C0402_OCTAGONXA,C0402-0201)'                                       | '0.01UF'   | '16V'         | '10%'    | 'DISCRETE' | 'CAP CHIP 0.01U 16V(10%,X7R,0402)MUR'                          | 'CHIP0402'     | ''          | ''   | '20160520'
 '0.01UF'   | '16V'   | '10%'     | 'C0402'     | 'EMPTY'   | 'CH3103K1B16'(!)   = ''              | ''                 | ''       | 'CH3103K1B16'     |'C0402'| '(C0402_OCTAGONXA,C0402-0201)'                                       | 'NA'       | '16V'         | '10%'    | 'IO'       | 'CAP CHIP 0.01U 16V(10%,X7R,0402)MUR'                          | 'CHIP0402'     | ''          | ''   | '20160520'
 '0.22UF'   | '16V'   | '10%'     | 'C0402'     | 'X7R'     | 'CH4223K1B06'(!)   = ''              | ''                 | ''       | 'CH4223K1B06'     |'C0402'| '(C0402_OCTAGONXA,C0402-0201)'                                       | '0.22UF'   | '16V'         | '10%'    | 'DISCRETE' | 'CAP CHIP 0.22U 16V(10%,X7R,0402)AEC'                          | 'CHIP0402'     | ''          | ''   | '20160520'
 '0.22UF'   | '16V'   | '10%'     | 'C0402'     | 'EMPTY'   | 'CH4223K1B06'(!)   = ''              | ''                 | ''       | 'CH4223K1B06'     |'C0402'| '(C0402_OCTAGONXA,C0402-0201)'                                       | 'NA'       | '16V'         | '10%'    | 'IO'       | 'CAP CHIP 0.22U 16V(10%,X7R,0402)AEC'                          | 'CHIP0402'     | ''          | ''   | '20160520'
 '0.01UF'   | '25V'   | '10%'     | 'C0402'     | 'X7R'     | 'CH3104K1B16'(!)   = ''              | ''                 | ''       | 'CH3104K1B16'     |'C0402'| '(C0402-0201)'                                                       | '0.01UF'   | '25V'         | '10%'    | 'DISCRETE' | 'CAP CHIP 0.01U 25V(10%,X7R,0402)MUR_AEC'                      | 'CHIP0402'     | ''          | ''   | '20160525'
 '0.01UF'   | '25V'   | '10%'     | 'C0402'     | 'EMPTY'   | 'CH3104K1B16'(!)   = ''              | ''                 | ''       | 'CH3104K1B16'     |'C0402'| '(C0402-0201)'                                                       | 'NA'       | '25V'         | '10%'    | 'IO'       | 'CAP CHIP 0.01U 25V(10%,X7R,0402)MUR_AEC'                      | 'CHIP0402'     | ''          | ''   | '20160525'
 '0.047UF'  | '25V'   | '10%'     | 'C0402'     | 'X7R'     | 'CH3474K1B08'(!)   = ''              | ''                 | ''       | 'CH3474K1B08'     |'C0402'| '(C0402-0201)'                                                       | '0.047UF'  | '25V'         | '10%'    | 'DISCRETE' | 'CAP CHIP 0.047U 25V(10% X7R 0402)MUR_AEC'                     | 'CHIP0402'     | ''          | ''   | '20160525'
 '0.047UF'  | '25V'   | '10%'     | 'C0402'     | 'EMPTY'   | 'CH3474K1B08'(!)   = ''              | ''                 | ''       | 'CH3474K1B08'     |'C0402'| '(C0402-0201)'                                                       | 'NA'       | '25V'         | '10%'    | 'IO'       | 'CAP CHIP 0.047U 25V(10% X7R 0402)MUR_AEC'                     | 'CHIP0402'     | ''          | ''   | '20160525'
 '0.1UF'    | '10V'   | '10%'     | 'C0402'     | 'X7R'     | 'CH4102K1B12'(!)   = ''              | ''                 | ''       | 'CH4102K1B12'     |'C0402'| '(C0402-0201)'                                                       | '0.1UF'    | '10V'         | '10%'    | 'DISCRETE' | 'CAP CHIP 0.1U 10V(10%,X7R,0402)MUR_AEC'                       | 'CHIP0402'     | ''          | ''   | '20160525'
 '0.1UF'    | '10V'   | '10%'     | 'C0402'     | 'EMPTY'   | 'CH4102K1B12'(!)   = ''              | ''                 | ''       | 'CH4102K1B12'     |'C0402'| '(C0402-0201)'                                                       | 'NA'       | '10V'         | '10%'    | 'IO'       | 'CAP CHIP 0.1U 10V(10%,X7R,0402)MUR_AEC'                       | 'CHIP0402'     | ''          | ''   | '20160525'
 '0.1UF'    | '25V'   | '10%'     | 'C0402'     | 'X7R'     | 'CH4104K1B07'(!)   = ''              | ''                 | ''       | 'CH4104K1B07'     |'C0402'| '(C0402-0201)'                                                       | '0.1UF'    | '25V'         | '10%'    | 'DISCRETE' | 'CAP CHIP 0.1U 25V(10%,X7R,0402)MUR_AEC'                       | 'CHIP0402'     | ''          | ''   | '20160525'
 '0.1UF'    | '25V'   | '10%'     | 'C0402'     | 'EMPTY'   | 'CH4104K1B07'(!)   = ''              | ''                 | ''       | 'CH4104K1B07'     |'C0402'| '(C0402-0201)'                                                       | 'NA'       | '25V'         | '10%'    | 'IO'       | 'CAP CHIP 0.1U 25V(10%,X7R,0402)MUR_AEC'                       | 'CHIP0402'     | ''          | ''   | '20160525'
 '0.1UF'    | '25V'   | '10%'     | 'C0603'     | 'X7R'     | 'CH4104K1915'(!)   = 'End of Design' | 'Comp-Approve'     | ''       | 'CH4104K1915'     |'C0603'| '(SMC0603AW)'                                                        | '0.1UF'    | '25V'         | '10%'    | 'DISCRETE' | 'CAP CHIP 0.1U 25V(10%,X7R,0603)MUR_AEC'                       | 'CHIP0603'     | ''          | ''   | '20160525'
 '0.1UF'    | '25V'   | '10%'     | 'C0603'     | 'EMPTY'   | 'CH4104K1915'(!)   = 'End of Design' | 'Comp-Approve'     | ''       | 'CH4104K1915'     |'C0603'| '(SMC0603AW)'                                                        | 'NA'       | '25V'         | '10%'    | 'IO'       | 'CAP CHIP 0.1U 25V(10%,X7R,0603)MUR_AEC'                       | 'CHIP0603'     | ''          | ''   | '20160525'
 '0.47UF'   | '10V'   | '10%'     | 'C0402'     | 'X7S'     | 'CH4472K6B01'(!)   = ''              | ''                 | ''       | 'CH4472K6B01'     |'C0402'| '(C0402-0201)'                                                       | '0.47UF'   | '10V'         | '10%'    | 'DISCRETE' | 'CAP CHIP 0.47U 10V(10%,X7S,0402)MUR_AEC'                      | 'CHIP0402'     | ''          | ''   | '20160525'
 '0.47UF'   | '10V'   | '10%'     | 'C0402'     | 'EMPTY'   | 'CH4472K6B01'(!)   = ''              | ''                 | ''       | 'CH4472K6B01'     |'C0402'| '(C0402-0201)'                                                       | 'NA'       | '10V'         | '10%'    | 'IO'       | 'CAP CHIP 0.47U 10V(10%,X7S,0402)MUR_AEC'                      | 'CHIP0402'     | ''          | ''   | '20160525'
 '1000PF'   | '50V'   | '10%'     | 'C0402'     | 'X7R'     | 'CH2106K1B25'(!)   = ''              | ''                 | ''       | 'CH2106K1B25'     |'C0402'| '(C0402-0201)'                                                       | '1000PF'   | '50V'         | '10%'    | 'DISCRETE' | 'CAP CHIP 1000P 50V(10%,X7R,0402)MUR_AEC'                      | 'CHIP0402'     | ''          | ''   | '20160525'
 '1000PF'   | '50V'   | '10%'     | 'C0402'     | 'EMPTY'   | 'CH2106K1B25'(!)   = ''              | ''                 | ''       | 'CH2106K1B25'     |'C0402'| '(C0402-0201)'                                                       | 'NA'       | '50V'         | '10%'    | 'IO'       | 'CAP CHIP 1000P 50V(10%,X7R,0402)MUR_AEC'                      | 'CHIP0402'     | ''          | ''   | '20160525'
 '1000PF'   | '50V'   | '5%'      | 'C0402'     | 'X7R'     | 'CH2106J1B07'(!)   = ''              | ''                 | ''       | 'CH2106J1B07'     |'C0402'| '(C0402-0201)'                                                       | '1000PF'   | '50V'         | '5%'     | 'DISCRETE' | 'CAP CHIP 1000P 50V(5%,X7R,0402)MUR_AEC'                       | 'CHIP0402'     | ''          | ''   | '20160525'
 '1000PF'   | '50V'   | '5%'      | 'C0402'     | 'EMPTY'   | 'CH2106J1B07'(!)   = ''              | ''                 | ''       | 'CH2106J1B07'     |'C0402'| '(C0402-0201)'                                                       | 'NA'       | '50V'         | '5%'     | 'IO'       | 'CAP CHIP 1000P 50V(5%,X7R,0402)MUR_AEC'                       | 'CHIP0402'     | ''          | ''   | '20160525'
 '100PF'    | '50V'   | '5%'      | 'C0402'     | 'NPO'     | 'CH1106J0B19'(!)   = ''              | ''                 | ''       | 'CH1106J0B19'     |'C0402'| '(C0402-0201)'                                                       | '100PF'    | '50V'         | '5%'     | 'DISCRETE' | 'CAP CHIP 100P 50V(5%,NPO,0402)MUR_AEC'                        | 'CHIP0402'     | ''          | ''   | '20160525'
 '100PF'    | '50V'   | '5%'      | 'C0402'     | 'EMPTY'   | 'CH1106J0B19'(!)   = ''              | ''                 | ''       | 'CH1106J0B19'     |'C0402'| '(C0402-0201)'                                                       | 'NA'       | '50V'         | '5%'     | 'IO'       | 'CAP CHIP 100P 50V(5%,NPO,0402)MUR_AEC'                        | 'CHIP0402'     | ''          | ''   | '20160525'
 '10PF'     | '50V'   | '2%'      | 'C0402'     | 'NPO'     | 'CH0106G0B05'(!)   = ''              | ''                 | ''       | 'CH0106G0B05'     |'C0402'| '(C0402-0201)'                                                       | '10PF'     | '50V'         | '2%'     | 'DISCRETE' | 'CAP CHIP 10P 50V(2%,NPO,0402)MUR_AEC'                         | 'CHIP0402'     | ''          | ''   | '20160525'
 '10PF'     | '50V'   | '2%'      | 'C0402'     | 'EMPTY'   | 'CH0106G0B05'(!)   = ''              | ''                 | ''       | 'CH0106G0B05'     |'C0402'| '(C0402-0201)'                                                       | 'NA'       | '50V'         | '2%'     | 'IO'       | 'CAP CHIP 10P 50V(2%,NPO,0402)MUR_AEC'                         | 'CHIP0402'     | ''          | ''   | '20160525'
 '10UF'     | '10V'   | '20%'     | 'C0603'     | 'X6S'     | 'CH6102ME905'(!)   = ''              | ''                 | ''       | 'CH6102ME905'     |'C0603'| '(SMC0603AW)'                                                        | '10UF'     | '10V'         | '20%'    | 'DISCRETE' | 'CAP CHIP 10U 10V(20%,X6S,0603)MUR_AEC'                        | 'CHIP0603'     | ''          | ''   | '20160525'
 '10UF'     | '10V'   | '20%'     | 'C0603'     | 'EMPTY'   | 'CH6102ME905'(!)   = ''              | ''                 | ''       | 'CH6102ME905'     |'C0603'| '(SMC0603AW)'                                                        | 'NA'       | '10V'         | '20%'    | 'IO'       | 'CAP CHIP 10U 10V(20%,X6S,0603)MUR_AEC'                        | 'CHIP0603'     | ''          | ''   | '20160525'
 '10UF'     | '4V'    | '20%'     | 'C0603'     | 'X6S'     | 'CH610KME909'(!)   = ''              | ''                 | ''       | 'CH610KME909'     |'C0603'| '(SMC0603AW)'                                                        | '10UF'     | '4V'          | '20%'    | 'DISCRETE' | 'CAP CHIP 10U 4V(20%,X6S,0603)MUR_AEC'                         | 'CHIP0603'     | ''          | ''   | '20160525'
 '10UF'     | '4V'    | '20%'     | 'C0603'     | 'EMPTY'   | 'CH610KME909'(!)   = ''              | ''                 | ''       | 'CH610KME909'     |'C0603'| '(SMC0603AW)'                                                        | 'NA'       | '4V'          | '20%'    | 'IO'       | 'CAP CHIP 10U 4V(20%,X6S,0603)MUR_AEC'                         | 'CHIP0603'     | ''          | ''   | '20160525'
 '15PF'     | '50V'   | '5%'      | 'C0402'     | 'NPO'     | 'CH0156J0B12'(!)   = ''              | ''                 | ''       | 'CH0156J0B12'     |'C0402'| '(C0402-0201)'                                                       | '15PF'     | '50V'         | '5%'     | 'DISCRETE' | 'CAP CHIP 15P 50V(5%,NPO,0402)MUR_AEC'                         | 'CHIP0402'     | ''          | ''   | '20160525'
 '15PF'     | '50V'   | '5%'      | 'C0402'     | 'EMPTY'   | 'CH0156J0B12'(!)   = ''              | ''                 | ''       | 'CH0156J0B12'     |'C0402'| '(C0402-0201)'                                                       | 'NA'       | '50V'         | '5%'     | 'IO'       | 'CAP CHIP 15P 50V(5%,NPO,0402)MUR_AEC'                         | 'CHIP0402'     | ''          | ''   | '20160525'
 '18PF'     | '50V'   | '5%'      | 'C0402'     | 'NPO'     | 'CH0186J0B09'(!)   = ''              | ''                 | ''       | 'CH0186J0B09'     |'C0402'| '(C0402-0201)'                                                       | '15PF'     | '50V'         | '5%'     | 'DISCRETE' | 'CAP CHIP 18P 50V(5%,NPO,0402)MUR_AEC'                         | 'CHIP0402'     | ''          | ''   | '20160526'
 '18PF'     | '50V'   | '5%'      | 'C0402'     | 'EMPTY'   | 'CH0186J0B09'(!)   = ''              | ''                 | ''       | 'CH0186J0B09'     |'C0402'| '(C0402-0201)'                                                       | 'NA'       | '50V'         | '5%'     | 'IO'       | 'CAP CHIP 18P 50V(5%,NPO,0402)MUR_AEC'                         | 'CHIP0402'     | ''          | ''   | '20160526'
 '1UF'      | '16V'   | '10%'     | 'C0603'     | 'X7R'     | 'CH5103K1914'(!)   = 'End of Design' | 'Comp-Approve'     | ''       | 'CH5103K1914'     |'C0603'| '(SMC0603AW)'                                                        | '15PF'     | '16V'         | '10%'    | 'DISCRETE' | 'CAP CHIP 1U 16V(10%,X7R,0603)MUR_AEC'                         | 'CHIP0603'     | ''          | ''   | '20160526'
 '1UF'      | '16V'   | '10%'     | 'C0603'     | 'EMPTY'   | 'CH5103K1914'(!)   = 'End of Design' | 'Comp-Approve'     | ''       | 'CH5103K1914'     |'C0603'| '(SMC0603AW)'                                                        | 'NA'       | '16V'         | '10%'    | 'IO'       | 'CAP CHIP 1U 16V(10%,X7R,0603)MUR_AEC'                         | 'CHIP0603'     | ''          | ''   | '20160526'
 '1UF'      | '16V'   | '10%'     | 'C0402'     | 'X6S'     | 'CH5103KEB06'(!)   = ''              | ''                 | ''       | 'CH5103KEB06'     |'C0402'| '(C0402-0201)'                                                       | '15PF'     | '16V'         | '10%'    | 'DISCRETE' | 'CAP CHIP 1U 16V(10%,X6S,0402)MUR_AEC'                         | 'CHIP0402'     | ''          | ''   | '20160526'
 '1UF'      | '16V'   | '10%'     | 'C0402'     | 'EMPTY'   | 'CH5103KEB06'(!)   = ''              | ''                 | ''       | 'CH5103KEB06'     |'C0402'| '(C0402-0201)'                                                       | 'NA'       | '16V'         | '10%'    | 'IO'       | 'CAP CHIP 1U 16V(10%,X6S,0402)MUR_AEC'                         | 'CHIP0402'     | ''          | ''   | '20160526'
 '1UF'      | '25V'   | '10%'     | 'C0402'     | 'X6S'     | 'CH5104KEB06'(!)   = ''              | ''                 | ''       | 'CH5104KEB06'     |'C0402'| '(C0402-0201)'                                                       | '15PF'     | '25V'         | '10%'    | 'DISCRETE' | 'CAP CHIP 1U 25V(10%,X6S,0402)MUR_AEC'                         | 'CHIP0402'     | ''          | ''   | '20160526'
 '1UF'      | '25V'   | '10%'     | 'C0402'     | 'EMPTY'   | 'CH5104KEB06'(!)   = ''              | ''                 | ''       | 'CH5104KEB06'     |'C0402'| '(C0402-0201)'                                                       | 'NA'       | '25V'         | '10%'    | 'IO'       | 'CAP CHIP 1U 25V(10%,X6S,0402)MUR_AEC'                         | 'CHIP0402'     | ''          | ''   | '20160526'
 '2200PF'   | '50V'   | '10%'     | 'C0402'     | 'X7R'     | 'CH2226K1B14'(!)   = ''              | ''                 | ''       | 'CH2226K1B14'     |'C0402'| '(C0402-0201)'                                                       | '2200PF'   | '50V'         | '10%'    | 'DISCRETE' | 'CAP CHIP 2200P 50V(10%,X7R,0402)MUR_AEC'                      | 'CHIP0402'     | ''          | ''   | '20160526'
 '2200PF'   | '50V'   | '10%'     | 'C0402'     | 'EMPTY'   | 'CH2226K1B14'(!)   = ''              | ''                 | ''       | 'CH2226K1B14'     |'C0402'| '(C0402-0201)'                                                       | 'NA'       | '50V'         | '10%'    | 'IO'       | 'CAP CHIP 2200P 50V(10%,X7R,0402)MUR_AEC'                      | 'CHIP0402'     | ''          | ''   | '20160526'
 '22PF'     | '50V'   | '5%'      | 'C0402'     | 'NPO'     | 'CH0226J0B23'(!)   = ''              | ''                 | ''       | 'CH0226J0B23'     |'C0402'| '(C0402-0201)'                                                       | '22PF'     | '50V'         | '5%'     | 'DISCRETE' | 'CAP CHIP 22P 50V(5%,NPO,0402)MUR_AEC'                         | 'CHIP0402'     | ''          | ''   | '20160526'
 '22PF'     | '50V'   | '5%'      | 'C0402'     | 'EMPTY'   | 'CH0226J0B23'(!)   = ''              | ''                 | ''       | 'CH0226J0B23'     |'C0402'| '(C0402-0201)'                                                       | 'NA'       | '50V'         | '5%'     | 'IO'       | 'CAP CHIP 22P 50V(5%,NPO,0402)MUR_AEC'                         | 'CHIP0402'     | ''          | ''   | '20160526'
 '3300PF'   | '50V'   | '10%'     | 'C0402'     | 'X7R'     | 'CH2336K1B11'(!)   = ''              | ''                 | ''       | 'CH2336K1B11'     |'C0402'| '(C0402-0201)'                                                       | '3300PF'   | '50V'         | '10%'    | 'DISCRETE' | 'CAP CHIP 3300P 50V(10%,X7R,0402)MUR_AEC'                      | 'CHIP0402'     | ''          | ''   | '20160526'
 '3300PF'   | '50V'   | '10%'     | 'C0402'     | 'EMPTY'   | 'CH2336K1B11'(!)   = ''              | ''                 | ''       | 'CH2336K1B11'     |'C0402'| '(C0402-0201)'                                                       | 'NA'       | '50V'         | '10%'    | 'IO'       | 'CAP CHIP 3300P 50V(10%,X7R,0402)MUR_AEC'                      | 'CHIP0402'     | ''          | ''   | '20160526'
 '4.7UF'    | '6.3V'  | '10%'     | 'C0603'     | 'X6S'     | 'CH5471KE907'(!)   = 'End of Design' | 'Comp-Approve'     | ''       | 'CH5471KE907'     |'C0603'| '(SMC0603AW)'                                                        | '4.7UF'    | '6.3V'        | '10%'    | 'DISCRETE' | 'CAP CHIP 4.7U 6.3V(10%,X6S,0603)MUR_AEC'                      | 'CHIP0603'     | ''          | ''   | '20160526'
 '4.7UF'    | '6.3V'  | '10%'     | 'C0603'     | 'EMPTY'   | 'CH5471KE907'(!)   = 'End of Design' | 'Comp-Approve'     | ''       | 'CH5471KE907'     |'C0603'| '(SMC0603AW)'                                                        | 'NA'       | '6.3V'        | '10%'    | 'IO'       | 'CAP CHIP 4.7U 6.3V(10%,X6S,0603)MUR_AEC'                      | 'CHIP0603'     | ''          | ''   | '20160526'
 '4700PF'   | '25V'   | '10%'     | 'C0402'     | 'X7R'     | 'CH2474K1B11'(!)   = ''              | ''                 | ''       | 'CH2474K1B11'     |'C0402'| '(C0402-0201)'                                                       | '4700PF'   | '25V'         | '10%'    | 'DISCRETE' | 'CAP CHIP 4700P 25V(10%,X7R,0402)MUR_AEC'                      | 'CHIP0402'     | ''          | ''   | '20160526'
 '4700PF'   | '25V'   | '10%'     | 'C0402'     | 'EMPTY'   | 'CH2474K1B11'(!)   = ''              | ''                 | ''       | 'CH2474K1B11'     |'C0402'| '(C0402-0201)'                                                       | 'NA'       | '25V'         | '10%'    | 'IO'       | 'CAP CHIP 4700P 25V(10%,X7R,0402)MUR_AEC'                      | 'CHIP0402'     | ''          | ''   | '20160526'
 '470PF'    | '50V'   | '10%'     | 'C0402'     | 'X7R'     | 'CH1476K1B15'(!)   = ''              | ''                 | ''       | 'CH1476K1B15'     |'C0402'| '(C0402-0201)'                                                       | '470PF'    | '50V'         | '10%'    | 'DISCRETE' | 'CAP CHIP 470P 50V(10%,X7R,0402)MUR_AEC'                       | 'CHIP0402'     | ''          | ''   | '20160526'
 '470PF'    | '50V'   | '10%'     | 'C0402'     | 'EMPTY'   | 'CH1476K1B15'(!)   = ''              | ''                 | ''       | 'CH1476K1B15'     |'C0402'| '(C0402-0201)'                                                       | 'NA'       | '50V'         | '10%'    | 'IO'       | 'CAP CHIP 470P 50V(10%,X7R,0402)MUR_AEC'                       | 'CHIP0402'     | ''          | ''   | '20160526'
 '47PF'     | '50V'   | '5%'      | 'C0402'     | 'C0G'     | 'CH0476J0B15'(!)   = ''              | ''                 | ''       | 'CH0476J0B15'     |'C0402'| '(C0402-0201)'                                                       | '47PF'     | '50V'         | '5%'     | 'DISCRETE' | 'CAP CHIP 47P 50V(5%,C0G,0402)MUR_AEC'                         | 'CHIP0402'     | ''          | ''   | '20160526'
 '47PF'     | '50V'   | '5%'      | 'C0402'     | 'EMPTY'   | 'CH0476J0B15'(!)   = ''              | ''                 | ''       | 'CH0476J0B15'     |'C0402'| '(C0402-0201)'                                                       | 'NA'       | '50V'         | '5%'     | 'IO'       | 'CAP CHIP 47P 50V(5%,C0G,0402)MUR_AEC'                         | 'CHIP0402'     | ''          | ''   | '20160526'
 '27PF'     | '50V'   | '5%'      | 'C0402'     | 'C0G'     | 'CH0276J0B08'(!)   = ''              | ''                 | ''       | 'CH0276J0B08'     |'C0402'| '(C0402-0201)'                                                       | '27PF'     | '50V'         | '5%'     | 'DISCRETE' | 'CAP CHIP 27P 50V(5%,C0G,0402)MUR_AEC'                         | 'CHIP0402'     | ''          | ''   | '20160530'
 '27PF'     | '50V'   | '5%'      | 'C0402'     | 'EMPTY'   | 'CH0276J0B08'(!)   = ''              | ''                 | ''       | 'CH0276J0B08'     |'C0402'| '(C0402-0201)'                                                       | 'NA'       | '50V'         | '5%'     | 'IO'       | 'CAP CHIP 27P 50V(5%,C0G,0402)MUR_AEC'                         | 'CHIP0402'     | ''          | ''   | '20160530'
 '1UF'      | '10V'   | '10%'     | 'C0402'     | 'X7S'     | 'CH5102K6B02'(!)   = ''              | ''                 | ''       | 'CH5102K6B02'     |'C0402'| '(C0402-0201)'                                                       | '1UF'      | '10V'         | '10%'    | 'DISCRETE' | 'CAP CHIP 1U 10V(10%,X7S,0402)MUR_AEC'                         | 'CHIP0402'     | ''          | ''   | '20160530'
 '1UF'      | '10V'   | '10%'     | 'C0402'     | 'EMPTY'   | 'CH5102K6B02'(!)   = ''              | ''                 | ''       | 'CH5102K6B02'     |'C0402'| '(C0402-0201)'                                                       | 'NA'       | '10V'         | '10%'    | 'IO'       | 'CAP CHIP 1U 10V(10%,X7S,0402)MUR_AEC'                         | 'CHIP0402'     | ''          | ''   | '20160530'
 '4.7UF'    | '16V'   | '10%'     | 'C0603'     | 'X6S'     | 'CH5473KE901'(!)   = ''              | ''                 | ''       | 'CH5473KE901'     |'C0603'| '(SMC0603AW)'                                                        | '4.7UF'    | '16V'         | '10%'    | 'DISCRETE' | 'CAP CHIP 4.7U 16V(10%,X6S,0603)MUR_AEC'                       | 'CHIP0603'     | ''          | ''   | '20160530'
 '4.7UF'    | '16V'   | '10%'     | 'C0603'     | 'EMPTY'   | 'CH5473KE901'(!)   = ''              | ''                 | ''       | 'CH5473KE901'     |'C0603'| '(SMC0603AW)'                                                        | 'NA'       | '16V'         | '10%'    | 'IO'       | 'CAP CHIP 4.7U 16V(10%,X6S,0603)MUR_AEC'                       | 'CHIP0603'     | ''          | ''   | '20160530'
 '33PF'     | '50V'   | '5%'      | 'C0402'     | 'C0G'     | 'CH0336J0B14'(!)   = ''              | ''                 | ''       | 'CH0336J0B14'     |'C0402'| '(C0402-0201)'                                                       | '33PF'     | '50V'         | '5%'     | 'DISCRETE' | 'CAP CHIP 33P 50V(5%,C0G,0402)MUR_AEC'                         | 'CHIP0402'     | ''          | ''   | '20160530'
 '33PF'     | '50V'   | '5%'      | 'C0402'     | 'EMPTY'   | 'CH0336J0B14'(!)   = ''              | ''                 | ''       | 'CH0336J0B14'     |'C0402'| '(C0402-0201)'                                                       | 'NA'       | '50V'         | '5%'     | 'IO'       | 'CAP CHIP 33P 50V(5%,C0G,0402)MUR_AEC'                         | 'CHIP0402'     | ''          | ''   | '20160530'
 '0.01UF'   | '50V'   | '10%'     | 'C0603'     | 'X7R'     | 'CH3106K1915'(!)   = 'End of Design' | 'Comp-Approve'     | ''       | 'CH3106K1915'     |'C0603'| '(SMC0603AW)'                                                        | '0.01UF'   | '50V'         | '10%'    | 'DISCRETE' | 'CAP CHIP 0.01U 50V(10%,X7R,0603)MUR_AEC'                      | 'CHIP0603'     | ''          | ''   | '20160530'
 '0.01UF'   | '50V'   | '10%'     | 'C0603'     | 'EMPTY'   | 'CH3106K1915'(!)   = 'End of Design' | 'Comp-Approve'     | ''       | 'CH3106K1915'     |'C0603'| '(SMC0603AW)'                                                        | 'NA'       | '50V'         | '10%'    | 'IO'       | 'CAP CHIP 0.01U 50V(10%,X7R,0603)MUR_AEC'                      | 'CHIP0603'     | ''          | ''   | '20160530'
 '10UF'     | '16V'   | '10%'     | 'C1206'     | 'X7R'     | 'CH6103K1203'(!)   = ''              | ''                 | ''       | 'CH6103K1203'     |'C1206_H76'| '(SMC1206AW)'                                                        | '10UF'     | '16V'         | '10%'    | 'DISCRETE' | 'CAP CHIP 10U 16V(10%,X7R,1206)MUR_AEC'                        | 'CHIP1206'     | ''          | ''   | '20160531'
 '10UF'     | '16V'   | '10%'     | 'C1206'     | 'EMPTY'   | 'CH6103K1203'(!)   = ''              | ''                 | ''       | 'CH6103K1203'     |'C1206_H76'| '(SMC1206AW)'                                                        | 'NA'       | '16V'         | '10%'    | 'IO'       | 'CAP CHIP 10U 16V(10%,X7R,1206)MUR_AEC'                        | 'CHIP1206'     | ''          | ''   | '20160531'
 '10UF'     | '16V'   | '10%'     | 'C0805'     | 'X7S'     | 'CH6103K6A01'(!)   = ''              | ''                 | ''       | 'CH6103K6A01'     |'C0805_H57'| '(SMC0805AW)'                                                        | '10UF'     | '16V'         | '10%'    | 'DISCRETE' | 'CAP CHIP 10U 16V(10%,X7S,0805)MUR_AEC'                        | 'CHIP0805'     | ''          | ''   | '20160531'
 '10UF'     | '16V'   | '10%'     | 'C0805'     | 'EMPTY'   | 'CH6103K6A01'(!)   = ''              | ''                 | ''       | 'CH6103K6A01'     |'C0805_H57'| '(SMC0805AW)'                                                        | 'NA'       | '16V'         | '10%'    | 'IO'       | 'CAP CHIP 10U 16V(10%,X7S,0805)MUR_AEC'                        | 'CHIP0805'     | ''          | ''   | '20160531'
 '10UF'     | '25V'   | '10%'     | 'C1206'     | 'X7S'     | 'CH6104K6201'(!)   = 'End of Design' | 'Comp-Approve'     | ''       | 'CH6104K6201'     |'C1206_H76'| '(SMC1206AW)'                                                        | '10UF'     | '25V'         | '10%'    | 'DISCRETE' | 'CAP CHIP 10U 25V(10%,X7S,1206)MUR_AEC'                        | 'CHIP1206'     | ''          | ''   | '20160531'
 '10UF'     | '25V'   | '10%'     | 'C1206'     | 'EMPTY'   | 'CH6104K6201'(!)   = 'End of Design' | 'Comp-Approve'     | ''       | 'CH6104K6201'     |'C1206_H76'| '(SMC1206AW)'                                                        | 'NA'       | '25V'         | '10%'    | 'IO'       | 'CAP CHIP 10U 25V(10%,X7S,1206)MUR_AEC'                        | 'CHIP1206'     | ''          | ''   | '20160531'
 '10UF'     | '6.3V'  | '10%'     | 'C0805'     | 'X7R'     | 'CH6101K1A02'(!)   = ''              | ''                 | ''       | 'CH6101K1A02'     |'C0805_H57'| '(SMC0805AW)'                                                        | '10UF'     | '6.3V'        | '10%'    | 'DISCRETE' | 'CAP CHIP 10U 6.3V(10%,X7R,0805)MUR_AEC'                       | 'CHIP0805'     | ''          | ''   | '20160531'
 '10UF'     | '6.3V'  | '10%'     | 'C0805'     | 'EMPTY'   | 'CH6101K1A02'(!)   = ''              | ''                 | ''       | 'CH6101K1A02'     |'C0805_H57'| '(SMC0805AW)'                                                        | 'NA'       | '6.3V'        | '10%'    | 'IO'       | 'CAP CHIP 10U 6.3V(10%,X7R,0805)MUR_AEC'                       | 'CHIP0805'     | ''          | ''   | '20160531'
 '2.2UF'    | '10V'   | '10%'     | 'C0805'     | 'X7R'     | 'CH5222K1A02'(!)   = 'End of Design' | 'Comp-Approve'     | ''       | 'CH5222K1A02'     |'C0805_H57'| '(SMC0805AW)'                                                        | '2.2UF'    | '10V'         | '10%'    | 'DISCRETE' | 'CAP CHIP 2.2U 10V(10%,X7R,0805)MUR_AEC'                       | 'CHIP0805'     | ''          | ''   | '20160531'
 '2.2UF'    | '10V'   | '10%'     | 'C0805'     | 'EMPTY'   | 'CH5222K1A02'(!)   = 'End of Design' | 'Comp-Approve'     | ''       | 'CH5222K1A02'     |'C0805_H57'| '(SMC0805AW)'                                                        | 'NA'       | '10V'         | '10%'    | 'IO'       | 'CAP CHIP 2.2U 10V(10%,X7R,0805)MUR_AEC'                       | 'CHIP0805'     | ''          | ''   | '20160531'
 '22UF'     | '10V'   | '20%'     | 'C0805'     | 'X6S'     | 'CH6222MEA04'(!)   = ''              | ''                 | ''       | 'CH6222MEA04'     |'C0805_H57'| '(SMC0805AW)'                                                        | '22UF'     | '10V'         | '20%'    | 'DISCRETE' | 'CAP CHIP 22U 10V(20%,X6S,0805)MUR_AEC'                        | 'CHIP0805'     | ''          | ''   | '20160531'
 '22UF'     | '10V'   | '20%'     | 'C0805'     | 'EMPTY'   | 'CH6222MEA04'(!)   = ''              | ''                 | ''       | 'CH6222MEA04'     |'C0805_H57'| '(SMC0805AW)'                                                        | 'NA'       | '10V'         | '20%'    | 'IO'       | 'CAP CHIP 22U 10V(20%,X6S,0805)MUR_AEC'                        | 'CHIP0805'     | ''          | ''   | '20160531'
 '22UF'     | '25V'   | '10%'     | 'C1206'     | 'X5R'     | 'CH6224K9204'(!)   = ''              | ''                 | ''       | 'CH6224K9204'     |'C1206_H76'| '(SMC1206AW)'                                                        | '22UF'     | '25V'         | '10%'    | 'DISCRETE' | 'CAP CHIP 22U 25V(10%,X5R,1206)MUR_AEC'                        | 'CHIP1206'     | ''          | ''   | '20160531'
 '22UF'     | '25V'   | '10%'     | 'C1206'     | 'EMPTY'   | 'CH6224K9204'(!)   = ''              | ''                 | ''       | 'CH6224K9204'     |'C1206_H76'| '(SMC1206AW)'                                                        | 'NA'       | '25V'         | '10%'    | 'IO'       | 'CAP CHIP 22U 25V(10%,X5R,1206)MUR_AEC'                        | 'CHIP1206'     | ''          | ''   | '20160531'
 '4.7UF'    | '16V'   | '10%'     | 'C0805'     | 'X7R'     | 'CH5473K1A05'(!)   = 'End of Design' | 'Comp-Approve'     | ''       | 'CH5473K1A05'     |'C0805_H57'| '(SMC0805AW)'                                                        | '4.7UF'    | '16V'         | '10%'    | 'DISCRETE' | 'CAP CHIP 4.7UF 16V(10%,X7R,0805)MUR_AEC'                      | 'CHIP0805'     | ''          | ''   | '20160531'
 '4.7UF'    | '16V'   | '10%'     | 'C0805'     | 'EMPTY'   | 'CH5473K1A05'(!)   = 'End of Design' | 'Comp-Approve'     | ''       | 'CH5473K1A05'     |'C0805_H57'| '(SMC0805AW)'                                                        | 'NA'       | '16V'         | '10%'    | 'IO'       | 'CAP CHIP 4.7UF 16V(10%,X7R,0805)MUR_AEC'                      | 'CHIP0805'     | ''          | ''   | '20160531'
 '0.022UF'  | '25V'   | '10%'     | 'C0402'     | 'X7R'     | 'CH3224K1B06'(!)   = ''              | ''                 | ''       | 'CH3224K1B06'     |'C0402'| '(C0402-0201)'                                                       | '0.022UF'  | '25V'         | '10%'    | 'DISCRETE' | 'CAP CHIP 0.022U 25V(10%,X7R,0402)MUR_AEC'                     | 'CHIP0402'     | ''          | ''   | '20160602'
 '0.022UF'  | '25V'   | '10%'     | 'C0402'     | 'EMPTY'   | 'CH3224K1B06'(!)   = ''              | ''                 | ''       | 'CH3224K1B06'     |'C0402'| '(C0402-0201)'                                                       | 'NA'       | '25V'         | '10%'    | 'IO'       | 'CAP CHIP 0.022U 25V(10%,X7R,0402)MUR_AEC'                     | 'CHIP0402'     | ''          | ''   | '20160602'
 '47UF'     | '4V'    | '20%'     | 'C0805'     | 'X6S'     | 'CH647KMEA04'(!)   = ''              | ''                 | ''       | 'CH647KMEA04'     |'C0805_H57'| '(C0805_H57_M,C0805_BHS)'                                            | '47UF'     | '4V'          | '20%'    | 'DISCRETE' | 'CAP CHIP 47U 4V(+-20%,X6S,0805)MUR'                           | 'CHIP0805'     | ''          | ''   | '20160616'
 '47UF'     | '4V'    | '20%'     | 'C0805'     | 'EMPTY'   | 'CH647KMEA04'(!)   = ''              | ''                 | ''       | 'CH647KMEA04'     |'C0805_H57'| '(C0805_H57_M,C0805_BHS)'                                            | 'NA'       | '4V'          | '20%'    | 'IO'       | 'CAP CHIP 47U 4V(+-20%,X6S,0805)MUR'                           | 'CHIP0805'     | ''          | ''   | '20160616'
 '1UF'      | '16V'   | '10%'     | 'C0603'     | 'X7R'     | 'CH5103K1909'(!)   = 'End of Design' | 'Comp-Approve'     | ''       | 'CH5103K1909'     |'C0603'| '(SMC0603AW,C0603_M)'                                                | '1UF'      | '16V'         | '10%'    | 'DISCRETE' | 'CAP CHIP 1U 16V(+-10%,X7R,0603)MUR'                           | 'CHIP0603'     | ''          | ''   | '20160616'
 '1UF'      | '16V'   | '10%'     | 'C0603'     | 'EMPTY'   | 'CH5103K1909'(!)   = 'End of Design' | 'Comp-Approve'     | ''       | 'CH5103K1909'     |'C0603'| '(SMC0603AW,C0603_M)'                                                | 'NA'       | '16V'         | '10%'    | 'IO'       | 'CAP CHIP 1U 16V(+-10%,X7R,0603)MUR'                           | 'CHIP0603'     | ''          | ''   | '20160616'
 '0.1UF'    | '16V'   | '10%'     | 'C0402'     | 'X7R'     | 'CH4103K1B14'(!)   = 'End of Design' | 'Comp-Approve'     | ''       | 'CH4103K1B14'     |'C0402'| '(C0402_OCTAGONXA,C0402_M,C0402-0201,C0402_OCTAGONXA_BOUND22)'       | '0.1UF'    | '16V'         | '10%'    | 'DISCRETE' | 'CAP CHIP 0.1U 16V(10%,X7R,0402)MUR'                           | 'CHIP0402'     | ''          | ''   | '20160616'
 '0.1UF'    | '16V'   | '10%'     | 'C0402'     | 'EMPTY'   | 'CH4103K1B14'(!)   = 'End of Design' | 'Comp-Approve'     | ''       | 'CH4103K1B14'     |'C0402'| '(C0402_OCTAGONXA,C0402_M,C0402-0201,C0402_OCTAGONXA_BOUND22)'       | 'NA'       | '16V'         | '10%'    | 'IO'       | 'CAP CHIP 0.1U 16V(10%,X7R,0402)MUR'                           | 'CHIP0402'     | ''          | ''   | '20160616'
 '47UF'     | '4V'    | '20%'     | 'C0805'     | 'X6S'     | 'CH647KMEA08'(!)   = ''              | ''                 | ''       | 'CH647KMEA08'     |'C0805_H57'| '(SMC0805AW)'                                                        | '47UF'     | '4V'          | '20%'    | 'DISCRETE' | 'CAP CHIP 47U 4V(20%,X6S,0805)MUR_AEC'                         | 'CHIP0805'     | ''          | ''   | '20160624'
 '47UF'     | '4V'    | '20%'     | 'C0805'     | 'EMPTY'   | 'CH647KMEA08'(!)   = ''              | ''                 | ''       | 'CH647KMEA08'     |'C0805_H57'| '(SMC0805AW)'                                                        | 'NA'       | '4V'          | '20%'    | 'IO'       | 'CAP CHIP 47U 4V(20%,X6S,0805)MUR_AEC'                         | 'CHIP0805'     | ''          | ''   | '20160624'
 '22UF'     | '6.3V'  | '20%'     | 'C0805'     | 'X7T'     | 'CH6221MJA02'(!)   = ''              | ''                 | ''       | 'CH6221MJA02'     |'C0805_H57'| '(SMC0805AW)'                                                        | '22UF'     | '6.3V'        | '20%'    | 'DISCRETE' | 'CAP CHIP 22U 6.3V(20%,X7T,0805)MUR_AEC'                       | 'CHIP0805'     | ''          | ''   | '20160624'
 '22UF'     | '6.3V'  | '20%'     | 'C0805'     | 'EMPTY'   | 'CH6221MJA02'(!)   = ''              | ''                 | ''       | 'CH6221MJA02'     |'C0805_H57'| '(SMC0805AW)'                                                        | 'NA'       | '6.3V'        | '20%'    | 'IO'       | 'CAP CHIP 22U 6.3V(20%,X7T,0805)MUR_AEC'                       | 'CHIP0805'     | ''          | ''   | '20160624'
 '22UF'     | '25V'   | '10%'     | 'C1206'     | 'X6S'     | 'CH6224KE200'(!)   = 'End of Design' | 'Comp-Approve'     | ''       | 'CH6224KE200'     |'C1206_H76'| '(SMC1206AW)'                                                        | '22UF'     | '25V'         | '10%'    | 'DISCRETE' | 'CAP CHIP 22U 25V(+-10%,X6S,1206)'                             | 'CHIP1206'     | ''          | ''   | '20160624'
 '22UF'     | '25V'   | '10%'     | 'C1206'     | 'EMPTY'   | 'CH6224KE200'(!)   = 'End of Design' | 'Comp-Approve'     | ''       | 'CH6224KE200'     |'C1206_H76'| '(SMC1206AW)'                                                        | 'NA'       | '25V'         | '10%'    | 'IO'       | 'CAP CHIP 22U 25V(+-10%,X6S,1206)'                             | 'CHIP1206'     | ''          | ''   | '20160624'
 '6.8PF'    | '50V'   | '0.5PF'   | 'C0402'     | 'C0G'     | 'CH-686D0B02'(!)   = ''              | ''                 | ''       | 'CH-686D0B02'     |'C0402'| '(C0402-0201)'                                                       | '6.8PF'    | '50V'         | '0.5PF'  | 'DISCRETE' | 'CAP CHIP 6.8P 50V(0.5PF,C0G,0402)MUR_AEC'                     | 'CHIP0402'     | ''          | ''   | '20160803'
 '6.8PF'    | '50V'   | '0.5PF'   | 'C0402'     | 'EMPTY'   | 'CH-686D0B02'(!)   = ''              | ''                 | ''       | 'CH-686D0B02'     |'C0402'| '(C0402-0201)'                                                       | 'NA'       | '50V'         | '0.5PF'  | 'IO'       | 'CAP CHIP 6.8P 50V(0.5PF,C0G,0402)MUR_AEC'                     | 'CHIP0402'     | ''          | ''   | '20160803'
 '5.6PF'    | '50V'   | '0.5PF'   | 'C0402'     | 'C0G'     | 'CH-566D0B02'(!)   = ''              | 'End of Life'      | ''       | 'CH-566D0B02'     |'C0402_EOL'| '(C0402-0201)'                                                       | '5.6PF'    | '50V'         | '0.5PF'  | 'DISCRETE' | 'CAP CHIP 5.6P 50V(0.5PF,C0G,0402)MUR_AEC'                     | 'CHIP0402'     | ''          | ''   | '20160803'
 '5.6PF'    | '50V'   | '0.5PF'   | 'C0402'     | 'EMPTY'   | 'CH-566D0B02'(!)   = ''              | 'End of Life'      | ''       | 'CH-566D0B02'     |'C0402_EOL'| '(C0402-0201)'                                                       | 'NA'       | '50V'         | '0.5PF'  | 'IO'       | 'CAP CHIP 5.6P 50V(0.5PF,C0G,0402)MUR_AEC'                     | 'CHIP0402'     | ''          | ''   | '20160803'
 '4.7PF'    | '50V'   | '0.25P'   | 'C0402'     | 'C0G'     | 'CH-476C0B02'(!)   = ''              | 'End of Life'      | ''       | 'CH-476C0B02'     |'C0402_EOL'| '(C0402-0201)'                                                       | '4.7PF'    | '50V'         | '0.25P'  | 'DISCRETE' | 'CAP CHIP 4.7P 50V(0.25P,C0G 0402)MUR_AEC'                     | 'CHIP0402'     | ''          | ''   | '20160803'
 '4.7PF'    | '50V'   | '0.25P'   | 'C0402'     | 'EMPTY'   | 'CH-476C0B02'(!)   = ''              | 'End of Life'      | ''       | 'CH-476C0B02'     |'C0402_EOL'| '(C0402-0201)'                                                       | 'NA'       | '50V'         | '0.25P'  | 'IO'       | 'CAP CHIP 4.7P 50V(0.25P,C0G 0402)MUR_AEC'                     | 'CHIP0402'     | ''          | ''   | '20160803'
 '4.7PF'    | '50V'   | '0.05P'   | 'C0402'     | 'C0G'     | 'CH-476T0B01'(!)   = ''              | ''                 | ''       | 'CH-476T0B01'     |'C0402'| '(C0402-0201)'                                                       | '4.7PF'    | '50V'         | '0.05P'  | 'DISCRETE' | 'CAP CHIP 4.7P 50V(0.05P,C0G,0402)MUR_AEC'                     | 'CHIP0402'     | ''          | ''   | '20160810'
 '4.7PF'    | '50V'   | '0.05P'   | 'C0402'     | 'EMPTY'   | 'CH-476T0B01'(!)   = ''              | ''                 | ''       | 'CH-476T0B01'     |'C0402'| '(C0402-0201)'                                                       | 'NA'       | '50V'         | '0.05P'  | 'IO'       | 'CAP CHIP 4.7P 50V(0.05P,C0G,0402)MUR_AEC'                     | 'CHIP0402'     | ''          | ''   | '20160810'
 '5.6P'     | '50V'   | '0.1P'    | 'C0402'     | 'C0G'     | 'CH-566B0B02'(!)   = ''              | ''                 | ''       | 'CH-566B0B02'     |'C0402'| '(C0402-0201)'                                                       | '5.6P'     | '50V'         | '0.1P'   | 'DISCRETE' | 'CAP CHIP 5.6P 50V(0.1P,C0G,0402)MUR_AEC'                      | 'CHIP0402'     | ''          | ''   | '20160810'
 '5.6P'     | '50V'   | '0.1P'    | 'C0402'     | 'EMPTY'   | 'CH-566B0B02'(!)   = ''              | ''                 | ''       | 'CH-566B0B02'     |'C0402'| '(C0402-0201)'                                                       | 'NA'       | '50V'         | '0.1P'   | 'IO'       | 'CAP CHIP 5.6P 50V(0.1P,C0G,0402)MUR_AEC'                      | 'CHIP0402'     | ''          | ''   | '20160810'
 '22UF'     | '4V'    | '20%'     | 'C0402'     | 'X5R'     | 'SP_CH622KM9B02_1'(!) = 'End of Design' | 'Comp-Approve'     | ''       | 'CH622KM9B02'     |'C0402_SMDC25_SM30'| '(SMC0402AW)'                                                        | '22UF'     | '4V'          | '20%'    | 'DISCRETE' | 'CAP CHIP 22UF 4V (+-20%, X5R,0402)_AMD FOOTPRINT SMDC25_SM30' | 'CHIP0402'     | ''          | ''   | '20160815'
 '22UF'     | '4V'    | '20%'     | 'C0402'     | 'EMPTY'   | 'SP_CH622KM9B02_1'(!) = 'End of Design' | 'Comp-Approve'     | ''       | 'CH622KM9B02'     |'C0402_SMDC25_SM30'| '(SMC0402AW)'                                                        | 'NA'       | '4V'          | '20%'    | 'IO'       | 'CAP CHIP 22UF 4V (+-20%, X5R,0402)_AMD FOOTPRINT SMDC25_SM30' | 'CHIP0402'     | ''          | ''   | '20160815'
 '47UF'     | '2.5V'  | '20%'     | 'C0603'     | 'X6S'     | 'CH647LME901'(!)   = 'End of Design' | 'Comp-Approve'     | ''       | 'CH647LME901'     |'C0603'| '(SMC0603AW)'                                                        | '47UF'     | '2.5V'        | '20%'    | 'DISCRETE' | 'CAP CHIP 47U 2.5V(+-20%,X6S,0603)'                            | 'CHIP0603'     | ''          | ''   | '20160823'
 '47UF'     | '2.5V'  | '20%'     | 'C0603'     | 'EMPTY'   | 'CH647LME901'(!)   = 'End of Design' | 'Comp-Approve'     | ''       | 'CH647LME901'     |'C0603'| '(SMC0603AW)'                                                        | 'NA'       | '2.5V'        | '20%'    | 'IO'       | 'CAP CHIP 47U 2.5V(+-20%,X6S,0603)'                            | 'CHIP0603'     | ''          | ''   | '20160823'
 '0.1UF'    | '16V'   | '10%'     | 'C0402'     | 'X7R'     | 'SP_CH4103K1B08_3'(!) = ''              | ''                 | ''       | 'CH4103K1B08'     |'C0402_SMDC25_SM30'| '(SMC0402AW)'                                                        | '0.1UF'    | '16V'         | '10%'    | 'DISCRETE' | 'CAP CHIP 0.1U 16V(10%.X7R.0402)_AMD FOOTPRINT SMDC25_SM30'    | 'CHIP0402'     | ''          | ''   | '20160829'
 '0.1UF'    | '16V'   | '10%'     | 'C0402'     | 'EMPTY'   | 'SP_CH4103K1B08_3'(!) = ''              | ''                 | ''       | 'CH4103K1B08'     |'C0402_SMDC25_SM30'| '(SMC0402AW)'                                                        | 'NA'       | '16V'         | '10%'    | 'IO'       | 'CAP CHIP 0.1U 16V(10%.X7R.0402)_AMD FOOTPRINT SMDC25_SM30'    | 'CHIP0402'     | ''          | ''   | '20160829'
 '0.68UF'   | '16V'   | '10%'     | 'C0603'     | 'X7R'     | 'CH4683K1901'(!)   = ''              | ''                 | ''       | 'CH4683K1901'     |'C0603'| '(SMC0603AW)'                                                        | '0.68UF'   | '16V'         | '10%'    | 'DISCRETE' | 'CAP CHIP 0.68U 16V(+-10%,X7R,0603)WTC'                        | 'CHIP0603'     | ''          | ''   | '20160830'
 '0.68UF'   | '16V'   | '10%'     | 'C0603'     | 'EMPTY'   | 'CH4683K1901'(!)   = ''              | ''                 | ''       | 'CH4683K1901'     |'C0603'| '(SMC0603AW)'                                                        | 'NA'       | '16V'         | '10%'    | 'IO'       | 'CAP CHIP 0.68U 16V(+-10%,X7R,0603)WTC'                        | 'CHIP0603'     | ''          | ''   | '20160830'
 '4.7UF'    | '25V'   | '10%'     | 'C0603'     | 'X6S'     | 'CH5474KE906'(!)   = ''              | ''                 | ''       | 'CH5474KE906'     |'C0603'| '(SMC0603AW)'                                                        | '4.7UF'    | '25V'         | '10%'    | 'DISCRETE' | 'CAP CHIP 4.7UF 25V(+-10%,X6S,0603)'                           | 'CHIP0603'     | ''          | ''   | '20160830'
 '4.7UF'    | '25V'   | '10%'     | 'C0603'     | 'EMPTY'   | 'CH5474KE906'(!)   = ''              | ''                 | ''       | 'CH5474KE906'     |'C0603'| '(SMC0603AW)'                                                        | 'NA'       | '25V'         | '10%'    | 'IO'       | 'CAP CHIP 4.7UF 25V(+-10%,X6S,0603)'                           | 'CHIP0603'     | ''          | ''   | '20160830'
 '33PF'     | '50V'   | '1%'      | 'C0402'     | 'C0G'     | 'CH0336F0B00'(!)   = ''              | ''                 | ''       | 'CH0336F0B00'     |'C0402'| '(C0402-0201)'                                                       | '33PF'     | '50V'         | '1%'     | 'DISCRETE' | 'CAP CHIP 33P 50V(+-1%,C0G,0402)'                              | 'CHIP0402'     | ''          | ''   | '20160906'
 '33PF'     | '50V'   | '1%'      | 'C0402'     | 'EMPTY'   | 'CH0336F0B00'(!)   = ''              | ''                 | ''       | 'CH0336F0B00'     |'C0402'| '(C0402-0201)'                                                       | 'NA'       | '50V'         | '1%'     | 'IO'       | 'CAP CHIP 33P 50V(+-1%,C0G,0402)'                              | 'CHIP0402'     | ''          | ''   | '20160906'
 '22UF'     | '6.3V'  | '20%'     | 'C0402'     | 'X5R'     | 'CH6221M9B01'(!)   = 'End of Design' | 'Comp-Approve'     | ''       | 'CH6221M9B01'     |'C0402'| '(C0402_OCTAGONXA,C0402-0201)'                                       | '22UF'     | '6.3V'        | '20%'    | 'DISCRETE' | 'CAP CHIP 22U 6.3V(+-20%,X5R,0402)'                            | 'CHIP0402'     | ''          | ''   | '20160906'
 '22UF'     | '6.3V'  | '20%'     | 'C0402'     | 'EMPTY'   | 'CH6221M9B01'(!)   = 'End of Design' | 'Comp-Approve'     | ''       | 'CH6221M9B01'     |'C0402'| '(C0402_OCTAGONXA,C0402-0201)'                                       | 'NA'       | '6.3V'        | '20%'    | 'IO'       | 'CAP CHIP 22U 6.3V(+-20%,X5R,0402)'                            | 'CHIP0402'     | ''          | ''   | '20160906'
 '22UF'     | '6.3V'  | '20%'     | 'C0402'     | 'X5R'     | 'SP_CH6221M9B01'(!) = ''              | ''                 | ''       | 'SP_CH6221M9B01'  |'C0402_SMDC25_SM30'| '(SMC0402AW)'                                                        | '22UF'     | '6.3V'        | '20%'    | 'DISCRETE' | 'CAP CHIP 22U 6.3V(+-20%,X5R,0402)_AMD FOOTPRINT SMDC25_SM30'  | 'CHIP0402'     | ''          | ''   | '20160906'
 '22UF'     | '6.3V'  | '20%'     | 'C0402'     | 'EMPTY'   | 'SP_CH6221M9B01'(!) = ''              | ''                 | ''       | 'SP_CH6221M9B01'  |'C0402_SMDC25_SM30'| '(SMC0402AW)'                                                        | 'NA'       | '6.3V'        | '20%'    | 'IO'       | 'CAP CHIP 22U 6.3V(+-20%,X5R,0402)_AMD FOOTPRINT SMDC25_SM30'  | 'CHIP0402'     | ''          | ''   | '20160906'
 '10UF'     | '4V'    | '20%'     | 'C0402'     | 'X5R'     | 'CH610KM9B00'(!)   = 'End of Design' | 'Comp-Approve'     | ''       | 'CH610KM9B00'     |'C0402'| '(C0402-0201)'                                                       | '10UF'     | '4V'          | '20%'    | 'DISCRETE' | 'CAP CHIP 10UF 4V(+-20%,X5R,0402)'                             | 'CHIP0402'     | ''          | ''   | '20161017'
 '10UF'     | '4V'    | '20%'     | 'C0402'     | 'EMPTY'   | 'CH610KM9B00'(!)   = 'End of Design' | 'Comp-Approve'     | ''       | 'CH610KM9B00'     |'C0402'| '(C0402-0201)'                                                       | 'NA'       | '4V'          | '20%'    | 'IO'       | 'CAP CHIP 10UF 4V(+-20%,X5R,0402)'                             | 'CHIP0402'     | ''          | ''   | '20161017'
 '10UF'     | '2.5V'  | '20%'     | 'C0402'     | 'X6S'     | 'CH610LMEB00'(!)   = ''              | ''                 | ''       | 'CH610LMEB00'     |'C0402'| '(C0402-0201)'                                                       | '10UF'     | '2.5V'        | '20%'    | 'DISCRETE' | 'CAP CHIP 10U 2.5V(+-20%,X6S,0402)MUR_AEC'                     | 'CHIP0402'     | ''          | ''   | '20161017'
 '10UF'     | '2.5V'  | '20%'     | 'C0402'     | 'EMPTY'   | 'CH610LMEB00'(!)   = ''              | ''                 | ''       | 'CH610LMEB00'     |'C0402'| '(C0402-0201)'                                                       | 'NA'       | '2.5V'        | '20%'    | 'IO'       | 'CAP CHIP 10U 2.5V(+-20%,X6S,0402)MUR_AEC'                     | 'CHIP0402'     | ''          | ''   | '20161017'
 '0.01UF'   | '16V'   | '10%'     | 'C0402'     | 'X7R'     | 'CH3103K1B24'(!)   = 'End of Design' | 'Comp-Release Qty' | ''       | 'CH3103K1B24'     |'C0402'| '(C0402-0201)'                                                       | '0.01UF'   | '16V'         | '10%'    | 'DISCRETE' | 'CAP CHIP 0.01U 16V(10%,X7R,0402)MUR_AEC'                      | 'CHIP0402'     | ''          | ''   | '20161017'
 '0.01UF'   | '16V'   | '10%'     | 'C0402'     | 'EMPTY'   | 'CH3103K1B24'(!)   = 'End of Design' | 'Comp-Release Qty' | ''       | 'CH3103K1B24'     |'C0402'| '(C0402-0201)'                                                       | 'NA'       | '16V'         | '10%'    | 'IO'       | 'CAP CHIP 0.01U 16V(10%,X7R,0402)MUR_AEC'                      | 'CHIP0402'     | ''          | ''   | '20161017'
 '6.8P'     | '50V'   | '0.05P'   | 'C0402'     | 'C0G'     | 'CH-686T0B01'(!)   = ''              | ''                 | ''       | 'CH-686T0B01'     |'C0402'| '(C0402-0201)'                                                       | '6.8P'     | '50V'         | '6.8P'   | 'DISCRETE' | 'CAP CHIP 6.8P 50V(0.05P,C0G,0402)MUR_AEC'                     | 'CHIP0402'     | ''          | ''   | '20161227'
 '6.8P'     | '50V'   | '0.05P'   | 'C0402'     | 'EMPTY'   | 'CH-686T0B01'(!)   = ''              | ''                 | ''       | 'CH-686T0B01'     |'C0402'| '(C0402-0201)'                                                       | 'NA'       | '50V'         | '6.8P'   | 'IO'       | 'CAP CHIP 6.8P 50V(0.05P,C0G,0402)MUR_AEC'                     | 'CHIP0402'     | ''          | ''   | '20161227'
 '2.2UF'    | '6.3V'  | '20%'     | 'C0402'     | 'X6S'     | 'CH5221MEB00'(!)   = ''              | ''                 | ''       | 'CH5221MEB00'     |'C0402'| '(C0402_OCTAGONXA,C0402-0201)'                                       | '2.2UF'    | '6.3V'        | '20%'    | 'DISCRETE' | 'CAP CHIP 2.2U 6.3V(+-20%,X6S,0402)'                           | 'CHIP0402'     | ''          | ''   | '20170330'
 '2.2UF'    | '6.3V'  | '20%'     | 'C0402'     | 'EMPTY'   | 'CH5221MEB00'(!)   = ''              | ''                 | ''       | 'CH5221MEB00'     |'C0402'| '(C0402_OCTAGONXA,C0402-0201)'                                       | 'NA'       | '6.3V'        | '20%'    | 'IO'       | 'CAP CHIP 2.2U 6.3V(+-20%,X6S,0402)'                           | 'CHIP0402'     | ''          | ''   | '20170330'
 '10UF'     | '6.3V'  | '20%'     | 'C0402'     | 'X6S'     | 'CH6101MEB01'(!)   = ''              | ''                 | ''       | 'CH6101MEB01'     |'C0402'| '(C0402_OCTAGONXA,C0402-0201)'                                       | '10UF'     | '6.3V'        | '20%'    | 'DISCRETE' | 'CAP CHIP 10UF 6.3V(+-20%,X6S,0402)'                           | 'CHIP0402'     | ''          | ''   | '20170330'
 '10UF'     | '6.3V'  | '20%'     | 'C0402'     | 'EMPTY'   | 'CH6101MEB01'(!)   = ''              | ''                 | ''       | 'CH6101MEB01'     |'C0402'| '(C0402_OCTAGONXA,C0402-0201)'                                       | 'NA'       | '6.3V'        | '20%'    | 'IO'       | 'CAP CHIP 10UF 6.3V(+-20%,X6S,0402)'                           | 'CHIP0402'     | ''          | ''   | '20170330'
 '47UF'     | '10V'   | '20%'     | 'C0805'     | 'X5R'     | 'CH6472M9A00'(!)   = 'End of Design' | 'Comp-Approve'     | ''       | 'CH6472M9A00'     |'C0805_H61'| '(SMC0805AW)'                                                        | '47UF'     | '10V'         | '20%'    | 'DISCRETE' | 'CAP CHIP 47U 10V(+-20%,X5R,0805)H1.25'                        | 'CHIP0805'     | ''          | ''   | '20170331'
 '47UF'     | '10V'   | '20%'     | 'C0805'     | 'EMPTY'   | 'CH6472M9A00'(!)   = 'End of Design' | 'Comp-Approve'     | ''       | 'CH6472M9A00'     |'C0805_H61'| '(SMC0805AW)'                                                        | 'NA'       | '10V'         | '20%'    | 'IO'       | 'CAP CHIP 47U 10V(+-20%,X5R,0805)H1.25'                        | 'CHIP0805'     | ''          | ''   | '20170331'
 '1000PF'   | '16V'   | '10%'     | 'C0201'     | 'X7R'     | 'CH2103K1E10'(!)   = ''              | ''                 | ''       | 'CH2103K1E10'     |'C0201'| '(SMC0201AW)'                                                        | '1000PF'   | '16V'         | '10%'    | 'DISCRETE' | 'CAP CHIP 1000P 16V(10%,X7R,0201)SAM'                          | 'CHIP0201'     | ''          | ''   | '20170427'
 '1000PF'   | '16V'   | '10%'     | 'C0201'     | 'EMPTY'   | 'CH2103K1E10'(!)   = ''              | ''                 | ''       | 'CH2103K1E10'     |'C0201'| '(SMC0201AW)'                                                        | 'NA'       | '16V'         | '10%'    | 'IO'       | 'CAP CHIP 1000P 16V(10%,X7R,0201)SAM'                          | 'CHIP0201'     | ''          | ''   | '20170427'
 '1000PF'   | '16V'   | '10%'     | 'C0201'     | 'X7R'     | 'CH2103K1E11'(!)   = ''              | ''                 | ''       | 'CH2103K1E11'     |'C0201'| '(SMC0201AW)'                                                        | '1000PF'   | '16V'         | '10%'    | 'DISCRETE' | 'CAP CHIP 1000P 16V(10%,X7R,0201)WTC'                          | 'CHIP0201'     | ''          | ''   | '20170427'
 '1000PF'   | '16V'   | '10%'     | 'C0201'     | 'EMPTY'   | 'CH2103K1E11'(!)   = ''              | ''                 | ''       | 'CH2103K1E11'     |'C0201'| '(SMC0201AW)'                                                        | 'NA'       | '16V'         | '10%'    | 'IO'       | 'CAP CHIP 1000P 16V(10%,X7R,0201)WTC'                          | 'CHIP0201'     | ''          | ''   | '20170427'
 '1UF'      | '4V'    | '20%'     | 'C0201'     | 'X6S'     | 'CH510KMEE04'(!)   = ''              | ''                 | ''       | 'CH510KMEE04'     |'C0201'| '(SMC0201AW)'                                                        | '1UF'      | '4V'          | '20%'    | 'DISCRETE' | 'CAP CHIP 1U 4V(+-20%,X6S,0201)TAY'                            | 'CHIP0201'     | ''          | ''   | '20170427'
 '1UF'      | '4V'    | '20%'     | 'C0201'     | 'EMPTY'   | 'CH510KMEE04'(!)   = ''              | ''                 | ''       | 'CH510KMEE04'     |'C0201'| '(SMC0201AW)'                                                        | 'NA'       | '4V'          | '20%'    | 'IO'       | 'CAP CHIP 1U 4V(+-20%,X6S,0201)TAY'                            | 'CHIP0201'     | ''          | ''   | '20170427'
 '1UF'      | '4V'    | '20%'     | 'C0201'     | 'X6S'     | 'CH510KMEE03'(!)   = ''              | ''                 | ''       | 'CH510KMEE03'     |'C0201'| '(SMC0201AW)'                                                        | '1UF'      | '4V'          | '20%'    | 'DISCRETE' | 'CAP CHIP 1U 4V(+-20%,X6S,0201)MUR'                            | 'CHIP0201'     | ''          | ''   | '20170427'
 '1UF'      | '4V'    | '20%'     | 'C0201'     | 'EMPTY'   | 'CH510KMEE03'(!)   = ''              | ''                 | ''       | 'CH510KMEE03'     |'C0201'| '(SMC0201AW)'                                                        | 'NA'       | '4V'          | '20%'    | 'IO'       | 'CAP CHIP 1U 4V(+-20%,X6S,0201)MUR'                            | 'CHIP0201'     | ''          | ''   | '20170427'
 '0.1UF'    | '6.3V'  | '10%'     | 'C0201'     | 'X6S'     | 'CH4101KEE03'(!)   = ''              | ''                 | ''       | 'CH4101KEE03'     |'C0201'| '(SMC0201AW)'                                                        | '0.1UF'    | '6.3V'        | '10%'    | 'DISCRETE' | 'CAP CHIP 0.1UF 6.3V(10%,X6S,0201)TAY'                         | 'CHIP0201'     | ''          | ''   | '20170427'
 '0.1UF'    | '6.3V'  | '10%'     | 'C0201'     | 'EMPTY'   | 'CH4101KEE03'(!)   = ''              | ''                 | ''       | 'CH4101KEE03'     |'C0201'| '(SMC0201AW)'                                                        | 'NA'       | '6.3V'        | '10%'    | 'IO'       | 'CAP CHIP 0.1UF 6.3V(10%,X6S,0201)TAY'                         | 'CHIP0201'     | ''          | ''   | '20170427'
 '0.1UF'    | '6.3V'  | '10%'     | 'C0201'     | 'X6S'     | 'CH4101KEE02'(!)   = ''              | ''                 | ''       | 'CH4101KEE02'     |'C0201'| '(SMC0201AW)'                                                        | '0.1UF'    | '6.3V'        | '10%'    | 'DISCRETE' | 'CAP CHIP 0.1UF 6.3V(10%,X6S,0201)SAM'                         | 'CHIP0201'     | ''          | ''   | '20170427'
 '0.1UF'    | '6.3V'  | '10%'     | 'C0201'     | 'EMPTY'   | 'CH4101KEE02'(!)   = ''              | ''                 | ''       | 'CH4101KEE02'     |'C0201'| '(SMC0201AW)'                                                        | 'NA'       | '6.3V'        | '10%'    | 'IO'       | 'CAP CHIP 0.1UF 6.3V(10%,X6S,0201)SAM'                         | 'CHIP0201'     | ''          | ''   | '20170427'
 '0.01UF'   | '16V'   | '10%'     | 'C0201'     | 'X7R'     | 'CH3103K1E02'(!)   = ''              | ''                 | ''       | 'CH3103K1E02'     |'C0201'| '(SMC0201AW)'                                                        | '0.01UF'   | '16V'         | '10%'    | 'DISCRETE' | 'CAP CHIP 0.01U 16V(+-10%,X7R,0201)YGO'                        | 'CHIP0201'     | ''          | ''   | '20170427'
 '0.01UF'   | '16V'   | '10%'     | 'C0201'     | 'EMPTY'   | 'CH3103K1E02'(!)   = ''              | ''                 | ''       | 'CH3103K1E02'     |'C0201'| '(SMC0201AW)'                                                        | 'NA'       | '16V'         | '10%'    | 'IO'       | 'CAP CHIP 0.01U 16V(+-10%,X7R,0201)YGO'                        | 'CHIP0201'     | ''          | ''   | '20170427'
 '2200PF'   | '50V'   | '10%'     | 'C0402'     | 'X7R'     | 'CH2226K1B15'(!)   = ''              | ''                 | ''       | 'CH2226K1B15'     |'C0402'| '(C0402-0201)'                                                       | '2200PF'   | '50V'         | '10%'    | 'DISCRETE' | 'CAP CHIP 2200P 50V(+-10%,X7R,0402)SAM'                        | 'CHIP0402'     | ''          | ''   | '20170427'
 '2200PF'   | '50V'   | '10%'     | 'C0402'     | 'EMPTY'   | 'CH2226K1B15'(!)   = ''              | ''                 | ''       | 'CH2226K1B15'     |'C0402'| '(C0402-0201)'                                                       | 'NA'       | '50V'         | '10%'    | 'IO'       | 'CAP CHIP 2200P 50V(+-10%,X7R,0402)SAM'                        | 'CHIP0402'     | ''          | ''   | '20170427'
 '100PF'    | '50V'   | '5%'      | 'C0402'     | 'NPO'     | 'CH1106J0B23'(!)   = ''              | ''                 | ''       | 'CH1106J0B23'     |'C0402'| '(C0402-0201)'                                                       | '100PF'    | '50V'         | '5%'     | 'DISCRETE' | 'CAP CHIP 100P 50V(+-5%,NPO,0402)YGO'                          | 'CHIP0402'     | ''          | ''   | '20170427'
 '100PF'    | '50V'   | '5%'      | 'C0402'     | 'EMPTY'   | 'CH1106J0B23'(!)   = ''              | ''                 | ''       | 'CH1106J0B23'     |'C0402'| '(C0402-0201)'                                                       | 'NA'       | '50V'         | '5%'     | 'IO'       | 'CAP CHIP 100P 50V(+-5%,NPO,0402)YGO'                          | 'CHIP0402'     | ''          | ''   | '20170427'
 '100PF'    | '50V'   | '5%'      | 'C0402'     | 'NPO'     | 'CH1106J0B22'(!)   = ''              | ''                 | ''       | 'CH1106J0B22'     |'C0402'| '(C0402-0201)'                                                       | '100PF'    | '50V'         | '5%'     | 'DISCRETE' | 'CAP CHIP 100P 50V(+-5%,NPO,0402)WTC'                          | 'CHIP0402'     | ''          | ''   | '20170427'
 '100PF'    | '50V'   | '5%'      | 'C0402'     | 'EMPTY'   | 'CH1106J0B22'(!)   = ''              | ''                 | ''       | 'CH1106J0B22'     |'C0402'| '(C0402-0201)'                                                       | 'NA'       | '50V'         | '5%'     | 'IO'       | 'CAP CHIP 100P 50V(+-5%,NPO,0402)WTC'                          | 'CHIP0402'     | ''          | ''   | '20170427'
 '1000PF'   | '50V'   | '5%'      | 'C0402'     | 'X7R'     | 'CH2106J1B08'(!)   = ''              | ''                 | ''       | 'CH2106J1B08'     |'C0402'| '(C0402-0201)'                                                       | '1000PF'   | '50V'         | '5%'     | 'DISCRETE' | 'CAP CHIP 1000P 50V(+-5%,X7R,0402)WTC'                         | 'CHIP0402'     | ''          | ''   | '20170427'
 '1000PF'   | '50V'   | '5%'      | 'C0402'     | 'EMPTY'   | 'CH2106J1B08'(!)   = ''              | ''                 | ''       | 'CH2106J1B08'     |'C0402'| '(C0402-0201)'                                                       | 'NA'       | '50V'         | '5%'     | 'IO'       | 'CAP CHIP 1000P 50V(+-5%,X7R,0402)WTC'                         | 'CHIP0402'     | ''          | ''   | '20170427'
 '1000PF'   | '50V'   | '5%'      | 'C0402'     | 'X7R'     | 'CH2106J1B05'(!)   = ''              | ''                 | ''       | 'CH2106J1B05'     |'C0402'| '(C0402-0201)'                                                       | '1000PF'   | '50V'         | '5%'     | 'DISCRETE' | 'CAP CHIP 1000P 50V(+-5%,X7R,0402)SAM'                         | 'CHIP0402'     | ''          | ''   | '20170427'
 '1000PF'   | '50V'   | '5%'      | 'C0402'     | 'EMPTY'   | 'CH2106J1B05'(!)   = ''              | ''                 | ''       | 'CH2106J1B05'     |'C0402'| '(C0402-0201)'                                                       | 'NA'       | '50V'         | '5%'     | 'IO'       | 'CAP CHIP 1000P 50V(+-5%,X7R,0402)SAM'                         | 'CHIP0402'     | ''          | ''   | '20170427'
 '0.01UF'   | '50V'   | '10%'     | 'C0402'     | 'X7R'     | 'CH3106K1B11'(!)   = ''              | ''                 | ''       | 'CH3106K1B11'     |'C0402'| '(C0402-0201)'                                                       | '0.01UF'   | '50V'         | '10%'    | 'DISCRETE' | 'CAP CHIP 0.01U 50V(+-10%,X7R,0402)WTC'                        | 'CHIP0402'     | ''          | ''   | '20170427'
 '0.01UF'   | '50V'   | '10%'     | 'C0402'     | 'EMPTY'   | 'CH3106K1B11'(!)   = ''              | ''                 | ''       | 'CH3106K1B11'     |'C0402'| '(C0402-0201)'                                                       | 'NA'       | '50V'         | '10%'    | 'IO'       | 'CAP CHIP 0.01U 50V(+-10%,X7R,0402)WTC'                        | 'CHIP0402'     | ''          | ''   | '20170427'
 '0.01UF'   | '50V'   | '10%'     | 'C0402'     | 'X7R'     | 'CH3106K1B06'(!)   = ''              | ''                 | ''       | 'CH3106K1B06'     |'C0402'| '(C0402-0201)'                                                       | '0.01UF'   | '50V'         | '10%'    | 'DISCRETE' | 'CAP CHIP 0.01U 50V(+-10%,X7R,0402)SAM'                        | 'CHIP0402'     | ''          | ''   | '20170427'
 '0.01UF'   | '50V'   | '10%'     | 'C0402'     | 'EMPTY'   | 'CH3106K1B06'(!)   = ''              | ''                 | ''       | 'CH3106K1B06'     |'C0402'| '(C0402-0201)'                                                       | 'NA'       | '50V'         | '10%'    | 'IO'       | 'CAP CHIP 0.01U 50V(+-10%,X7R,0402)SAM'                        | 'CHIP0402'     | ''          | ''   | '20170427'
 '0.047UF'  | '25V'   | '10%'     | 'C0402'     | 'X7R'     | 'CH3474K1B09'(!)   = ''              | ''                 | ''       | 'CH3474K1B09'     |'C0402'| '(C0402-0201)'                                                       | '0.047UF'  | '25V'         | '10%'    | 'DISCRETE' | 'CAP CHIP 0.047U 25V(+-10%,X7R,0402)WTC'                       | 'CHIP0402'     | ''          | ''   | '20170427'
 '0.047UF'  | '25V'   | '10%'     | 'C0402'     | 'EMPTY'   | 'CH3474K1B09'(!)   = ''              | ''                 | ''       | 'CH3474K1B09'     |'C0402'| '(C0402-0201)'                                                       | 'NA'       | '25V'         | '10%'    | 'IO'       | 'CAP CHIP 0.047U 25V(+-10%,X7R,0402)WTC'                       | 'CHIP0402'     | ''          | ''   | '20170427'
 '0.1UF'    | '25V'   | '10%'     | 'C0402'     | 'X7R'     | 'CH4104K9B08'(!)   = 'End of Design' | 'Comp-Approve'     | ''       | 'CH4104K9B08'     |'C0402'| '(C0402-0201)'                                                       | '0.1UF'    | '25V'         | '10%'    | 'DISCRETE' | 'CAP CHIP 0.1U 25V(+-10%,X7R,0402)SAM'                         | 'CHIP0402'     | ''          | ''   | '20170427'
 '0.1UF'    | '25V'   | '10%'     | 'C0402'     | 'EMPTY'   | 'CH4104K9B08'(!)   = 'End of Design' | 'Comp-Approve'     | ''       | 'CH4104K9B08'     |'C0402'| '(C0402-0201)'                                                       | 'NA'       | '25V'         | '10%'    | 'IO'       | 'CAP CHIP 0.1U 25V(+-10%,X7R,0402)SAM'                         | 'CHIP0402'     | ''          | ''   | '20170427'
 '0.1UF'    | '25V'   | '10%'     | 'C0402'     | 'X7R'     | 'CH4104K1B09'(!)   = ''              | ''                 | ''       | 'CH4104K1B09'     |'C0402'| '(C0402-0201)'                                                       | '0.1UF'    | '25V'         | '10%'    | 'DISCRETE' | 'CAP CHIP 0.1U 25V(+-10%,X7R,0402)WTC'                         | 'CHIP0402'     | ''          | ''   | '20170427'
 '0.1UF'    | '25V'   | '10%'     | 'C0402'     | 'EMPTY'   | 'CH4104K1B09'(!)   = ''              | ''                 | ''       | 'CH4104K1B09'     |'C0402'| '(C0402-0201)'                                                       | 'NA'       | '25V'         | '10%'    | 'IO'       | 'CAP CHIP 0.1U 25V(+-10%,X7R,0402)WTC'                         | 'CHIP0402'     | ''          | ''   | '20170427'
 '1UF'      | '6.3V'  | '10%'     | 'C0402'     | 'X5R'     | 'CH5101K9B23'(!)   = ''              | ''                 | ''       | 'CH5101K9B23'     |'C0402'| '(C0402-0201)'                                                       | '1UF'      | '6.3V'        | '10%'    | 'DISCRETE' | 'CAP CHIP 1U 6.3V(+-10%,X5R,0402)SAM'                          | 'CHIP0402'     | ''          | ''   | '20170427'
 '1UF'      | '6.3V'  | '10%'     | 'C0402'     | 'EMPTY'   | 'CH5101K9B23'(!)   = ''              | ''                 | ''       | 'CH5101K9B23'     |'C0402'| '(C0402-0201)'                                                       | 'NA'       | '6.3V'        | '10%'    | 'IO'       | 'CAP CHIP 1U 6.3V(+-10%,X5R,0402)SAM'                          | 'CHIP0402'     | ''          | ''   | '20170427'
 '1UF'      | '6.3V'  | '10%'     | 'C0402'     | 'X5R'     | 'CH5101K9B17'(!)   = ''              | ''                 | ''       | 'CH5101K9B17'     |'C0402'| '(C0402-0201)'                                                       | '1UF'      | '6.3V'        | '10%'    | 'DISCRETE' | 'CAP CHIP 1U 6.3V(+-10%,X5R,0402)WTC'                          | 'CHIP0402'     | ''          | ''   | '20170427'
 '1UF'      | '6.3V'  | '10%'     | 'C0402'     | 'EMPTY'   | 'CH5101K9B17'(!)   = ''              | ''                 | ''       | 'CH5101K9B17'     |'C0402'| '(C0402-0201)'                                                       | 'NA'       | '6.3V'        | '10%'    | 'IO'       | 'CAP CHIP 1U 6.3V(+-10%,X5R,0402)WTC'                          | 'CHIP0402'     | ''          | ''   | '20170427'
 '1UF'      | '6.3V'  | '10%'     | 'C0402'     | 'X6S'     | 'CH5101KEB03'(!)   = ''              | ''                 | ''       | 'CH5101KEB03'     |'C0402'| '(C0402-0201)'                                                       | '1UF'      | '6.3V'        | '10%'    | 'DISCRETE' | 'CAP CHIP 1U 6.3V(+-10%,X6S,0402)SAM'                          | 'CHIP0402'     | ''          | ''   | '20170427'
 '1UF'      | '6.3V'  | '10%'     | 'C0402'     | 'EMPTY'   | 'CH5101KEB03'(!)   = ''              | ''                 | ''       | 'CH5101KEB03'     |'C0402'| '(C0402-0201)'                                                       | 'NA'       | '6.3V'        | '10%'    | 'IO'       | 'CAP CHIP 1U 6.3V(+-10%,X6S,0402)SAM'                          | 'CHIP0402'     | ''          | ''   | '20170427'
 '1UF'      | '6.3V'  | '10%'     | 'C0402'     | 'X6S'     | 'CH5101KEB02'(!)   = 'End of Design' | 'Comp-Approve'     | ''       | 'CH5101KEB02'     |'C0402'| '(C0402_OCTAGONXA,C0402-0201)'                                       | '1UF'      | '6.3V'        | '10%'    | 'DISCRETE' | 'CAP CHIP 1U 6.3V(+-10%,X6S,0402)MUR'                          | 'CHIP0402'     | ''          | ''   | '20170427'
 '1UF'      | '6.3V'  | '10%'     | 'C0402'     | 'EMPTY'   | 'CH5101KEB02'(!)   = 'End of Design' | 'Comp-Approve'     | ''       | 'CH5101KEB02'     |'C0402'| '(C0402_OCTAGONXA,C0402-0201)'                                       | 'NA'       | '6.3V'        | '10%'    | 'IO'       | 'CAP CHIP 1U 6.3V(+-10%,X6S,0402)MUR'                          | 'CHIP0402'     | ''          | ''   | '20170427'
 '1UF'      | '25V'   | '10%'     | 'C0402'     | 'X6S'     | 'CH5104KEB07'(!)   = 'End of Design' | 'Comp-Approve'     | ''       | 'CH5104KEB07'     |'C0402'| '(C0402-0201)'                                                       | '1UF'      | '25V'         | '10%'    | 'DISCRETE' | 'CAP CHIP 1UF 25V(+-10%,X6S,0402)WTC'                          | 'CHIP0402'     | ''          | ''   | '20170427'
 '1UF'      | '25V'   | '10%'     | 'C0402'     | 'EMPTY'   | 'CH5104KEB07'(!)   = 'End of Design' | 'Comp-Approve'     | ''       | 'CH5104KEB07'     |'C0402'| '(C0402-0201)'                                                       | 'NA'       | '25V'         | '10%'    | 'IO'       | 'CAP CHIP 1UF 25V(+-10%,X6S,0402)WTC'                          | 'CHIP0402'     | ''          | ''   | '20170427'
 '10UF'     | '16V'   | '20%'     | 'C0603'     | 'X6S'     | 'CH6103ME905'(!)   = ''              | ''                 | ''       | 'CH6103ME905'     |'C0603'| '(SMC0603AW)'                                                        | '10UF'     | '16V'         | '20%'    | 'DISCRETE' | 'CAP CHIP 10U 16V(+-20%,X6S,0603)WTC'                          | 'CHIP0603'     | ''          | ''   | '20170426'
 '10UF'     | '16V'   | '20%'     | 'C0603'     | 'EMPTY'   | 'CH6103ME905'(!)   = ''              | ''                 | ''       | 'CH6103ME905'     |'C0603'| '(SMC0603AW)'                                                        | 'NA'       | '16V'         | '20%'    | 'IO'       | 'CAP CHIP 10U 16V(+-20%,X6S,0603)WTC'                          | 'CHIP0603'     | ''          | ''   | '20170426'
 '10UF'     | '16V'   | '20%'     | 'C0603'     | 'X6S'     | 'CH6103ME904'(!)   = ''              | ''                 | ''       | 'CH6103ME904'     |'C0603'| '(SMC0603AW)'                                                        | '10UF'     | '16V'         | '20%'    | 'DISCRETE' | 'CAP CHIP 10UF 16V(+-20%,X6S,0603)MUR'                         | 'CHIP0603'     | ''          | ''   | '20170426'
 '10UF'     | '16V'   | '20%'     | 'C0603'     | 'EMPTY'   | 'CH6103ME904'(!)   = ''              | ''                 | ''       | 'CH6103ME904'     |'C0603'| '(SMC0603AW)'                                                        | 'NA'       | '16V'         | '20%'    | 'IO'       | 'CAP CHIP 10UF 16V(+-20%,X6S,0603)MUR'                         | 'CHIP0603'     | ''          | ''   | '20170426'
 '10UF'     | '6.3V'  | '20%'     | 'C0603'     | 'X6S'     | 'CH6101ME904'(!)   = ''              | ''                 | ''       | 'CH6101ME904'     |'C0603'| '(SMC0603AW)'                                                        | '10UF'     | '6.3V'        | '20%'    | 'DISCRETE' | 'CAP CHIP 10U 6.3V(+-20%,X6S,0603)SAM'                         | 'CHIP0603'     | ''          | ''   | '20170426'
 '10UF'     | '6.3V'  | '20%'     | 'C0603'     | 'EMPTY'   | 'CH6101ME904'(!)   = ''              | ''                 | ''       | 'CH6101ME904'     |'C0603'| '(SMC0603AW)'                                                        | 'NA'       | '6.3V'        | '20%'    | 'IO'       | 'CAP CHIP 10U 6.3V(+-20%,X6S,0603)SAM'                         | 'CHIP0603'     | ''          | ''   | '20170426'
 '4.7UF'    | '6.3V'  | '10%'     | 'C0603'     | 'X6S'     | 'CH5471KE904'(!)   = 'End of Design' | 'Comp-Approve'     | ''       | 'CH5471KE904'     |'C0603'| '(SMC0603AW)'                                                        | '4.7UF'    | '6.3V'        | '10%'    | 'DISCRETE' | 'CAP CHIP 4.7U 6.3V(+-10%,X6S,0603)SAM'                        | 'CHIP0603'     | ''          | ''   | '20170426'
 '4.7UF'    | '6.3V'  | '10%'     | 'C0603'     | 'EMPTY'   | 'CH5471KE904'(!)   = 'End of Design' | 'Comp-Approve'     | ''       | 'CH5471KE904'     |'C0603'| '(SMC0603AW)'                                                        | 'NA'       | '6.3V'        | '10%'    | 'IO'       | 'CAP CHIP 4.7U 6.3V(+-10%,X6S,0603)SAM'                        | 'CHIP0603'     | ''          | ''   | '20170426'
 '0.033UF'  | '50V'   | '10%'     | 'C0603'     | 'X7R'     | 'CH3336K1906'(!)   = 'End of Design' | 'Comp-Approve'     | ''       | 'CH3336K1906'     |'C0603'| '(SMC0603AW)'                                                        | '0.033UF'  | '50V'         | '10%'    | 'DISCRETE' | 'CAP CHIP 0.033U 50V(+-10%,X7R,0603)WTC'                       | 'CHIP0603'     | ''          | ''   | '20170426'
 '0.033UF'  | '50V'   | '10%'     | 'C0603'     | 'EMPTY'   | 'CH3336K1906'(!)   = 'End of Design' | 'Comp-Approve'     | ''       | 'CH3336K1906'     |'C0603'| '(SMC0603AW)'                                                        | 'NA'       | '50V'         | '10%'    | 'IO'       | 'CAP CHIP 0.033U 50V(+-10%,X7R,0603)WTC'                       | 'CHIP0603'     | ''          | ''   | '20170426'
 '22UF'     | '6.3V'  | '20%'     | 'C0603'     | 'X6S'     | 'CH6221ME902'(!)   = 'End of Design' | 'Comp-Approve'     | ''       | 'CH6221ME902'     |'C0603'| '(SMC0603AW)'                                                        | '22UF'     | '6.3V'        | '20%'    | 'DISCRETE' | 'CAP CHIP 22U 6.3V(+-20%,X6S,0603)WTC'                         | 'CHIP0603'     | ''          | ''   | '20170426'
 '22UF'     | '6.3V'  | '20%'     | 'C0603'     | 'EMPTY'   | 'CH6221ME902'(!)   = 'End of Design' | 'Comp-Approve'     | ''       | 'CH6221ME902'     |'C0603'| '(SMC0603AW)'                                                        | 'NA'       | '6.3V'        | '20%'    | 'IO'       | 'CAP CHIP 22U 6.3V(+-20%,X6S,0603)WTC'                         | 'CHIP0603'     | ''          | ''   | '20170426'
 '22UF'     | '6.3V'  | '20%'     | 'C0603'     | 'X6S'     | 'CH6221ME901'(!)   = ''              | ''                 | ''       | 'CH6221ME901'     |'C0603'| '(SMC0603AW)'                                                        | '22UF'     | '6.3V'        | '20%'    | 'DISCRETE' | 'CAP CHIP 22U 6.3V(+-20%,X6S,0603)MUR'                         | 'CHIP0603'     | ''          | ''   | '20170426'
 '22UF'     | '6.3V'  | '20%'     | 'C0603'     | 'EMPTY'   | 'CH6221ME901'(!)   = ''              | ''                 | ''       | 'CH6221ME901'     |'C0603'| '(SMC0603AW)'                                                        | 'NA'       | '6.3V'        | '20%'    | 'IO'       | 'CAP CHIP 22U 6.3V(+-20%,X6S,0603)MUR'                         | 'CHIP0603'     | ''          | ''   | '20170426'
 '10UF'     | '6.3V'  | '20%'     | 'C0603'     | 'X5R'     | 'CH6101M9921'(!)   = ''              | ''                 | ''       | 'CH6101M9921'     |'C0603'| '(SMC0603AW)'                                                        | '10UF'     | '6.3V'        | '20%'    | 'DISCRETE' | 'CAP CHIP 10U 6.3V(+-20%,X5R,0603)SAM'                         | 'CHIP0603'     | ''          | ''   | '20170427'
 '10UF'     | '6.3V'  | '20%'     | 'C0603'     | 'EMPTY'   | 'CH6101M9921'(!)   = ''              | ''                 | ''       | 'CH6101M9921'     |'C0603'| '(SMC0603AW)'                                                        | 'NA'       | '6.3V'        | '20%'    | 'IO'       | 'CAP CHIP 10U 6.3V(+-20%,X5R,0603)SAM'                         | 'CHIP0603'     | ''          | ''   | '20170427'
 '10UF'     | '6.3V'  | '20%'     | 'C0603'     | 'X5R'     | 'CH6101M9914'(!)   = 'End of Design' | 'Comp-Approve'     | ''       | 'CH6101M9914'     |'C0603'| '(SMC0603AW)'                                                        | '10UF'     | '6.3V'        | '20%'    | 'DISCRETE' | 'CAP CHIP 10U 6.3V(+-20%,X5R,0603)YGO'                         | 'CHIP0603'     | ''          | ''   | '20170427'
 '10UF'     | '6.3V'  | '20%'     | 'C0603'     | 'EMPTY'   | 'CH6101M9914'(!)   = 'End of Design' | 'Comp-Approve'     | ''       | 'CH6101M9914'     |'C0603'| '(SMC0603AW)'                                                        | 'NA'       | '6.3V'        | '20%'    | 'IO'       | 'CAP CHIP 10U 6.3V(+-20%,X5R,0603)YGO'                         | 'CHIP0603'     | ''          | ''   | '20170427'
 '22PF'     | '50V'   | '5%'      | 'C0402'     | 'NPO'     | 'CH0226J0B22'(!)   = ''              | ''                 | ''       | 'CH0226J0B22'     |'C0402'| '(C0402-0201)'                                                       | '22PF'     | '50V'         | '5%'     | 'DISCRETE' | 'CAP CHIP 22P 50V(+-5%,NPO,0402)SAM'                           | 'CHIP0402'     | ''          | ''   | '20170427'
 '22PF'     | '50V'   | '5%'      | 'C0402'     | 'EMPTY'   | 'CH0226J0B22'(!)   = ''              | ''                 | ''       | 'CH0226J0B22'     |'C0402'| '(C0402-0201)'                                                       | 'NA'       | '50V'         | '5%'     | 'IO'       | 'CAP CHIP 22P 50V(+-5%,NPO,0402)SAM'                           | 'CHIP0402'     | ''          | ''   | '20170427'
 '0.1UF'    | '16V'   | '10%'     | 'C0402'     | 'X7R'     | 'CH4103K1B19'(!)   = 'End of Design' | 'Comp-Approve'     | ''       | 'CH4103K1B19'     |'C0402'| '(C0402-0201)'                                                       | '0.1UF'    | '16V'         | '10%'    | 'DISCRETE' | 'CAP CHIP 0.1U 16V(10%,X7R,0402)SAM'                           | 'CHIP0402'     | ''          | ''   | '20170427'
 '0.1UF'    | '16V'   | '10%'     | 'C0402'     | 'EMPTY'   | 'CH4103K1B19'(!)   = 'End of Design' | 'Comp-Approve'     | ''       | 'CH4103K1B19'     |'C0402'| '(C0402-0201)'                                                       | 'NA'       | '16V'         | '10%'    | 'IO'       | 'CAP CHIP 0.1U 16V(10%,X7R,0402)SAM'                           | 'CHIP0402'     | ''          | ''   | '20170427'
 '10UF'     | '10V'   | '20%'     | 'C0402'     | 'X5R'     | 'CH6102M9B11'(!)   = ''              | ''                 | ''       | 'CH6102M9B11'     |'C0402'| '(C0402-0201)'                                                       | '10UF'     | '10V'         | '20%'    | 'DISCRETE' | 'CAP CHIP 10U 10V(+-20%, X5R,0402)YGO'                         | 'CHIP0402'     | ''          | ''   | '20170427'
 '10UF'     | '10V'   | '20%'     | 'C0402'     | 'EMPTY'   | 'CH6102M9B11'(!)   = ''              | ''                 | ''       | 'CH6102M9B11'     |'C0402'| '(C0402-0201)'                                                       | 'NA'       | '10V'         | '20%'    | 'IO'       | 'CAP CHIP 10U 10V(+-20%, X5R,0402)YGO'                         | 'CHIP0402'     | ''          | ''   | '20170427'
 '10PF'     | '50V'   | '5%'      | 'C0402'     | 'C0G'     | 'CH0106J0B17'(!)   = ''              | ''                 | ''       | 'CH0106J0B17'     |'C0402'| '(C0402-0201)'                                                       | '10PF'     | '50V'         | '5%'     | 'DISCRETE' | 'CAP CHIP 10P 50V(+-5%,C0G,0402)MUR'                           | 'CHIP0402'     | ''          | ''   | '20170427'
 '10PF'     | '50V'   | '5%'      | 'C0402'     | 'EMPTY'   | 'CH0106J0B17'(!)   = ''              | ''                 | ''       | 'CH0106J0B17'     |'C0402'| '(C0402-0201)'                                                       | 'NA'       | '50V'         | '5%'     | 'IO'       | 'CAP CHIP 10P 50V(+-5%,C0G,0402)MUR'                           | 'CHIP0402'     | ''          | ''   | '20170427'
 '10PF'     | '50V'   | '5%'      | 'C0402'     | 'C0G'     | 'CH0106J0B18'(!)   = ''              | ''                 | ''       | 'CH0106J0B18'     |'C0402'| '(C0402-0201)'                                                       | '10PF'     | '50V'         | '5%'     | 'DISCRETE' | 'CAP CHIP 10P 50V(+-5%,C0G,0402)YGO'                           | 'CHIP0402'     | ''          | ''   | '20170427'
 '10PF'     | '50V'   | '5%'      | 'C0402'     | 'EMPTY'   | 'CH0106J0B18'(!)   = ''              | ''                 | ''       | 'CH0106J0B18'     |'C0402'| '(C0402-0201)'                                                       | 'NA'       | '50V'         | '5%'     | 'IO'       | 'CAP CHIP 10P 50V(+-5%,C0G,0402)YGO'                           | 'CHIP0402'     | ''          | ''   | '20170427'
 '12PF'     | '50V'   | '5%'      | 'C0402'     | 'C0G'     | 'CH0126J0B15'(!)   = ''              | ''                 | ''       | 'CH0126J0B15'     |'C0402'| '(C0402-0201)'                                                       | '12PF'     | '50V'         | '5%'     | 'DISCRETE' | 'CAP CHIP 12P 50V(+-5%,C0G,0402)WTC'                           | 'CHIP0402'     | ''          | ''   | '20170427'
 '12PF'     | '50V'   | '5%'      | 'C0402'     | 'EMPTY'   | 'CH0126J0B15'(!)   = ''              | ''                 | ''       | 'CH0126J0B15'     |'C0402'| '(C0402-0201)'                                                       | 'NA'       | '50V'         | '5%'     | 'IO'       | 'CAP CHIP 12P 50V(+-5%,C0G,0402)WTC'                           | 'CHIP0402'     | ''          | ''   | '20170427'
 '12PF'     | '50V'   | '5%'      | 'C0402'     | 'NP0'     | 'CH0126J0B10'(!)   = ''              | ''                 | ''       | 'CH0126J0B10'     |'C0402'| '(C0402-0201)'                                                       | '12PF'     | '50V'         | '5%'     | 'DISCRETE' | 'CAP CHIP 12P 50V(+-5%,NP0,0402)TAY'                           | 'CHIP0402'     | ''          | ''   | '20170427'
 '12PF'     | '50V'   | '5%'      | 'C0402'     | 'EMPTY'   | 'CH0126J0B10'(!)   = ''              | ''                 | ''       | 'CH0126J0B10'     |'C0402'| '(C0402-0201)'                                                       | 'NA'       | '50V'         | '5%'     | 'IO'       | 'CAP CHIP 12P 50V(+-5%,NP0,0402)TAY'                           | 'CHIP0402'     | ''          | ''   | '20170427'
 '2200PF'   | '50V'   | '10%'     | 'C0402'     | 'X7R'     | 'CH2226K1B12'(!)   = ''              | ''                 | ''       | 'CH2226K1B12'     |'C0402'| '(C0402-0201)'                                                       | '2200PF'   | '50V'         | '10%'    | 'DISCRETE' | 'CAP CHIP 2200P 50V(+-10%,X7R,0402)TAY'                        | 'CHIP0402'     | ''          | ''   | '20170427'
 '2200PF'   | '50V'   | '10%'     | 'C0402'     | 'EMPTY'   | 'CH2226K1B12'(!)   = ''              | ''                 | ''       | 'CH2226K1B12'     |'C0402'| '(C0402-0201)'                                                       | 'NA'       | '50V'         | '10%'    | 'IO'       | 'CAP CHIP 2200P 50V(+-10%,X7R,0402)TAY'                        | 'CHIP0402'     | ''          | ''   | '20170427'
 '0.22UF'   | '16V'   | '10%'     | 'C0402'     | 'X7R'     | 'CH4223K1B05'(!)   = 'End of Design' | 'Comp-Approve'     | ''       | 'CH4223K1B05'     |'C0402'| '(C0402-0201)'                                                       | '0.22UF'   | '16V'         | '10%'    | 'DISCRETE' | 'CAP CHIP 0.22U 16V(10%,X7R,0402)SAM'                          | 'CHIP0402'     | ''          | ''   | '20170427'
 '0.22UF'   | '16V'   | '10%'     | 'C0402'     | 'EMPTY'   | 'CH4223K1B05'(!)   = 'End of Design' | 'Comp-Approve'     | ''       | 'CH4223K1B05'     |'C0402'| '(C0402-0201)'                                                       | 'NA'       | '16V'         | '10%'    | 'IO'       | 'CAP CHIP 0.22U 16V(10%,X7R,0402)SAM'                          | 'CHIP0402'     | ''          | ''   | '20170427'
 '4.7UF'    | '6.3V'  | '20%'     | 'C0402'     | 'X6S'     | 'CH5471MEB04'(!)   = ''              | ''                 | ''       | 'CH5471MEB04'     |'C0402'| '(C0402-0201)'                                                       | '4.7UF'    | '6.3V'        | '20%'    | 'DISCRETE' | 'CAP CHIP 4.7UF 6.3V(+-20%,X6S,0402)TAY'                       | 'CHIP0402'     | ''          | ''   | '20170427'
 '4.7UF'    | '6.3V'  | '20%'     | 'C0402'     | 'EMPTY'   | 'CH5471MEB04'(!)   = ''              | ''                 | ''       | 'CH5471MEB04'     |'C0402'| '(C0402-0201)'                                                       | 'NA'       | '6.3V'        | '20%'    | 'IO'       | 'CAP CHIP 4.7UF 6.3V(+-20%,X6S,0402)TAY'                       | 'CHIP0402'     | ''          | ''   | '20170427'
 '1UF'      | '6.3V'  | '10%'     | 'C0402'     | 'X7R'     | 'CH5101K1B06'(!)   = ''              | ''                 | ''       | 'CH5101K1B06'     |'C0402'| '(C0402-0201)'                                                       | '1UF'      | '6.3V'        | '10%'    | 'DISCRETE' | 'CAP CHIP 1U,6.3V(+-10%,X7R,0402)SAM'                          | 'CHIP0402'     | ''          | ''   | '20170427'
 '1UF'      | '6.3V'  | '10%'     | 'C0402'     | 'EMPTY'   | 'CH5101K1B06'(!)   = ''              | ''                 | ''       | 'CH5101K1B06'     |'C0402'| '(C0402-0201)'                                                       | 'NA'       | '6.3V'        | '10%'    | 'IO'       | 'CAP CHIP 1U,6.3V(+-10%,X7R,0402)SAM'                          | 'CHIP0402'     | ''          | ''   | '20170427'
 '1500PF'   | '50V'   | '10%'     | 'C0402'     | 'X7R'     | 'CH2156K1B09'(!)   = ''              | ''                 | ''       | 'CH2156K1B09'     |'C0402'| '(C0402-0201)'                                                       | '1500PF'   | '50V'         | '10%'    | 'DISCRETE' | 'CAP CHIP 1500PF 50V(+-10%,X7R,0402)SAM'                       | 'CHIP0402'     | ''          | ''   | '20170427'
 '1500PF'   | '50V'   | '10%'     | 'C0402'     | 'EMPTY'   | 'CH2156K1B09'(!)   = ''              | ''                 | ''       | 'CH2156K1B09'     |'C0402'| '(C0402-0201)'                                                       | 'NA'       | '50V'         | '10%'    | 'IO'       | 'CAP CHIP 1500PF 50V(+-10%,X7R,0402)SAM'                       | 'CHIP0402'     | ''          | ''   | '20170427'
 '1500PF'   | '50V'   | '10%'     | 'C0402'     | 'X7R'     | 'CH2156K1B10'(!)   = ''              | ''                 | ''       | 'CH2156K1B10'     |'C0402'| '(C0402-0201)'                                                       | '1500PF'   | '50V'         | '10%'    | 'DISCRETE' | 'CAP CHIP 1500PF 50V(+-10%,X7R,0402)WTC'                       | 'CHIP0402'     | ''          | ''   | '20170427'
 '1500PF'   | '50V'   | '10%'     | 'C0402'     | 'EMPTY'   | 'CH2156K1B10'(!)   = ''              | ''                 | ''       | 'CH2156K1B10'     |'C0402'| '(C0402-0201)'                                                       | 'NA'       | '50V'         | '10%'    | 'IO'       | 'CAP CHIP 1500PF 50V(+-10%,X7R,0402)WTC'                       | 'CHIP0402'     | ''          | ''   | '20170427'
 '1200PF'   | '50V'   | '10%'     | 'C0402'     | 'X7R'     | 'CH2126K1B03'(!)   = 'End of Design' | 'End of Life'      | ''       | 'CH2126K1B03'     |'C0402_EOL'| '(C0402-0201)'                                                       | '1200PF'   | '50V'         | '10%'    | 'DISCRETE' | 'CAP CHIP 1200P 50V(+-10%,X7R,0402)SAM'                        | 'CHIP0402'     | ''          | ''   | '20170427'
 '1200PF'   | '50V'   | '10%'     | 'C0402'     | 'EMPTY'   | 'CH2126K1B03'(!)   = 'End of Design' | 'End of Life'      | ''       | 'CH2126K1B03'     |'C0402_EOL'| '(C0402-0201)'                                                       | 'NA'       | '50V'         | '10%'    | 'IO'       | 'CAP CHIP 1200P 50V(+-10%,X7R,0402)SAM'                        | 'CHIP0402'     | ''          | ''   | '20170427'
 '1200PF'   | '50V'   | '10%'     | 'C0402'     | 'X7R'     | 'CH2126K1B04'(!)   = ''              | ''                 | ''       | 'CH2126K1B04'     |'C0402'| '(C0402-0201)'                                                       | '1200PF'   | '50V'         | '10%'    | 'DISCRETE' | 'CAP CHIP 1200P 50V(+-10%,X7R,0402)WTC'                        | 'CHIP0402'     | ''          | ''   | '20170427'
 '1200PF'   | '50V'   | '10%'     | 'C0402'     | 'EMPTY'   | 'CH2126K1B04'(!)   = ''              | ''                 | ''       | 'CH2126K1B04'     |'C0402'| '(C0402-0201)'                                                       | 'NA'       | '50V'         | '10%'    | 'IO'       | 'CAP CHIP 1200P 50V(+-10%,X7R,0402)WTC'                        | 'CHIP0402'     | ''          | ''   | '20170427'
 '10UF'     | '10V'   | '20%'     | 'C0402'     | 'X5R'     | 'CH6102M9B12'(!)   = ''              | ''                 | ''       | 'CH6102M9B12'     |'C0402'| '(C0402-0201)'                                                       | '10UF'     | '10V'         | '20%'    | 'DISCRETE' | 'CAP CHIP 10U 10V(+-20%, X5R,0402)SAM'                         | 'CHIP0402'     | ''          | ''   | '20170427'
 '10UF'     | '10V'   | '20%'     | 'C0402'     | 'EMPTY'   | 'CH6102M9B12'(!)   = ''              | ''                 | ''       | 'CH6102M9B12'     |'C0402'| '(C0402-0201)'                                                       | 'NA'       | '10V'         | '20%'    | 'IO'       | 'CAP CHIP 10U 10V(+-20%, X5R,0402)SAM'                         | 'CHIP0402'     | ''          | ''   | '20170427'
 '0.01UF'   | '16V'   | '10%'     | 'C0402'     | 'X7R'     | 'CH3103K1B26'(!)   = ''              | ''                 | ''       | 'CH3103K1B26'     |'C0402'| '(C0402-0201)'                                                       | '0.01UF'   | '16V'         | '10%'    | 'DISCRETE' | 'CAP CHIP 0.01U 16V(10%,X7R,0402)YGO'                          | 'CHIP0402'     | ''          | ''   | '20170427'
 '0.01UF'   | '16V'   | '10%'     | 'C0402'     | 'EMPTY'   | 'CH3103K1B26'(!)   = ''              | ''                 | ''       | 'CH3103K1B26'     |'C0402'| '(C0402-0201)'                                                       | 'NA'       | '16V'         | '10%'    | 'IO'       | 'CAP CHIP 0.01U 16V(10%,X7R,0402)YGO'                          | 'CHIP0402'     | ''          | ''   | '20170427'
 '0.01UF'   | '16V'   | '10%'     | 'C0402'     | 'X7R'     | 'CH3103K1B25'(!)   = ''              | ''                 | ''       | 'CH3103K1B25'     |'C0402'| '(C0402-0201)'                                                       | '0.01UF'   | '16V'         | '10%'    | 'DISCRETE' | 'CAP CHIP 0.01U 16V(10%,X7R,0402)WTC'                          | 'CHIP0402'     | ''          | ''   | '20170427'
 '0.01UF'   | '16V'   | '10%'     | 'C0402'     | 'EMPTY'   | 'CH3103K1B25'(!)   = ''              | ''                 | ''       | 'CH3103K1B25'     |'C0402'| '(C0402-0201)'                                                       | 'NA'       | '16V'         | '10%'    | 'IO'       | 'CAP CHIP 0.01U 16V(10%,X7R,0402)WTC'                          | 'CHIP0402'     | ''          | ''   | '20170427'
 '1UF'      | '16V'   | '10%'     | 'C0402'     | 'X5R'     | 'CH5103K9B06'(!)   = ''              | ''                 | ''       | 'CH5103K9B06'     |'C0402'| '(C0402-0201)'                                                       | '1UF'      | '16V'         | '10%'    | 'DISCRETE' | 'CAP CHIP 1U 16V(10%,X5R,0402)SAM'                             | 'CHIP0402'     | ''          | ''   | '20170427'
 '1UF'      | '16V'   | '10%'     | 'C0402'     | 'EMPTY'   | 'CH5103K9B06'(!)   = ''              | ''                 | ''       | 'CH5103K9B06'     |'C0402'| '(C0402-0201)'                                                       | 'NA'       | '16V'         | '10%'    | 'IO'       | 'CAP CHIP 1U 16V(10%,X5R,0402)SAM'                             | 'CHIP0402'     | ''          | ''   | '20170427'
 '1UF'      | '16V'   | '10%'     | 'C0402'     | 'X5R'     | 'CH5103K9B09'(!)   = ''              | ''                 | ''       | 'CH5103K9B09'     |'C0402'| '(C0402-0201)'                                                       | '1UF'      | '16V'         | '10%'    | 'DISCRETE' | 'CAP CHIP 1UF 16V(10%,X5R,0402)WTC'                            | 'CHIP0402'     | ''          | ''   | '20170427'
 '1UF'      | '16V'   | '10%'     | 'C0402'     | 'EMPTY'   | 'CH5103K9B09'(!)   = ''              | ''                 | ''       | 'CH5103K9B09'     |'C0402'| '(C0402-0201)'                                                       | 'NA'       | '16V'         | '10%'    | 'IO'       | 'CAP CHIP 1UF 16V(10%,X5R,0402)WTC'                            | 'CHIP0402'     | ''          | ''   | '20170427'
 '10UF'     | '25V'   | '10%'     | 'C0805'     | 'X6S'     | 'CH6104KEA06'(!)   = 'End of Design' | 'Comp-Approve'     | ''       | 'CH6104KEA06'     |'C0805_H57'| '(SMC0805AW)'                                                        | '10UF'     | '25V'         | '10%'    | 'DISCRETE' | 'CAP CHIP 10U 25V(+-10%,X6S,0805)WTC'                          | 'CHIP0805'     | ''          | ''   | '20170502'
 '10UF'     | '25V'   | '10%'     | 'C0805'     | 'EMPTY'   | 'CH6104KEA06'(!)   = 'End of Design' | 'Comp-Approve'     | ''       | 'CH6104KEA06'     |'C0805_H57'| '(SMC0805AW)'                                                        | 'NA'       | '25V'         | '10%'    | 'IO'       | 'CAP CHIP 10U 25V(+-10%,X6S,0805)WTC'                          | 'CHIP0805'     | ''          | ''   | '20170502'
 '22UF'     | '6.3V'  | '20%'     | 'C0805'     | 'X5R'     | 'CH6221M9A34'(!)   = ''              | ''                 | ''       | 'CH6221M9A34'     |'C0805_H57'| '(SMC0805AW)'                                                        | '22UF'     | '6.3V'        | '20%'    | 'DISCRETE' | 'CAP CHIP 22U 6.3V(+-20%,X5R,0805)WTC'                         | 'CHIP0805'     | ''          | ''   | '20170502'
 '22UF'     | '6.3V'  | '20%'     | 'C0805'     | 'EMPTY'   | 'CH6221M9A34'(!)   = ''              | ''                 | ''       | 'CH6221M9A34'     |'C0805_H57'| '(SMC0805AW)'                                                        | 'NA'       | '6.3V'        | '20%'    | 'IO'       | 'CAP CHIP 22U 6.3V(+-20%,X5R,0805)WTC'                         | 'CHIP0805'     | ''          | ''   | '20170502'
 '22UF'     | '6.3V'  | '20%'     | 'C0805'     | 'X6S'     | 'CH6221MEA06'(!)   = ''              | ''                 | ''       | 'CH6221MEA06'     |'C0805_H57'| '(SMC0805AW)'                                                        | '22UF'     | '6.3V'        | '20%'    | 'DISCRETE' | 'CAP CHIP 22U 6.3V(+-20%,X6S,0805)SAM'                         | 'CHIP0805'     | ''          | ''   | '20170502'
 '22UF'     | '6.3V'  | '20%'     | 'C0805'     | 'EMPTY'   | 'CH6221MEA06'(!)   = ''              | ''                 | ''       | 'CH6221MEA06'     |'C0805_H57'| '(SMC0805AW)'                                                        | 'NA'       | '6.3V'        | '20%'    | 'IO'       | 'CAP CHIP 22U 6.3V(+-20%,X6S,0805)SAM'                         | 'CHIP0805'     | ''          | ''   | '20170502'
 '10UF'     | '25V'   | '10%'     | 'C1206'     | 'X7R'     | 'CH6104K1212'(!)   = 'End of Design' | 'Comp-Approve'     | ''       | 'CH6104K1212'     |'C1206_H76'| '(SMC1206AW)'                                                        | '10UF'     | '25V'         | '10%'    | 'DISCRETE' | 'CAP CHIP 10U 25V(+-10%,X7R,1206)WTC'                          | 'CHIP1206'     | ''          | ''   | '20170502'
 '10UF'     | '25V'   | '10%'     | 'C1206'     | 'EMPTY'   | 'CH6104K1212'(!)   = 'End of Design' | 'Comp-Approve'     | ''       | 'CH6104K1212'     |'C1206_H76'| '(SMC1206AW)'                                                        | 'NA'       | '25V'         | '10%'    | 'IO'       | 'CAP CHIP 10U 25V(+-10%,X7R,1206)WTC'                          | 'CHIP1206'     | ''          | ''   | '20170502'
 '22UF'     | '25V'   | '10%'     | 'C1206'     | 'X6S'     | 'CH6224KE202'(!)   = 'End of Design' | 'Comp-Approve'     | ''       | 'CH6224KE202'     |'C1206_H76'| '(SMC1206AW)'                                                        | '22UF'     | '25V'         | '10%'    | 'DISCRETE' | 'CAP CHIP 22U 25V(+-10%,X6S,1206)SAM'                          | 'CHIP1206'     | ''          | ''   | '20170502'
 '22UF'     | '25V'   | '10%'     | 'C1206'     | 'EMPTY'   | 'CH6224KE202'(!)   = 'End of Design' | 'Comp-Approve'     | ''       | 'CH6224KE202'     |'C1206_H76'| '(SMC1206AW)'                                                        | 'NA'       | '25V'         | '10%'    | 'IO'       | 'CAP CHIP 22U 25V(+-10%,X6S,1206)SAM'                          | 'CHIP1206'     | ''          | ''   | '20170502'
 '22UF'     | '10V'   | '20%'     | 'C0805'     | 'X6S'     | 'CH6222MEA02'(!)   = ''              | ''                 | ''       | 'CH6222MEA02'     |'C0805_H57'| '(SMC0805AW)'                                                        | '22UF'     | '10V'         | '20%'    | 'DISCRETE' | 'CAP CHIP 22U 10V(+-20%,X6S,0805)TAY'                          | 'CHIP0805'     | ''          | ''   | '20170503'
 '22UF'     | '10V'   | '20%'     | 'C0805'     | 'EMPTY'   | 'CH6222MEA02'(!)   = ''              | ''                 | ''       | 'CH6222MEA02'     |'C0805_H57'| '(SMC0805AW)'                                                        | 'NA'       | '10V'         | '20%'    | 'IO'       | 'CAP CHIP 22U 10V(+-20%,X6S,0805)TAY'                          | 'CHIP0805'     | ''          | ''   | '20170503'
 '10UF'     | '6.3V'  | '20%'     | 'C0805'     | 'X6S'     | 'CH6101MEA01'(!)   = ''              | 'End of Life'      | ''       | 'CH6101MEA01'     |'C0805_H57_EOL'| '(SMC0805AW)'                                                        | '10UF'     | '6.3V'        | '20%'    | 'DISCRETE' | 'CAP CHIP 10UF 6.3V(+-20%,X6S,0805)TAY'                        | 'CHIP0805'     | ''          | ''   | '20170503'
 '10UF'     | '6.3V'  | '20%'     | 'C0805'     | 'EMPTY'   | 'CH6101MEA01'(!)   = ''              | 'End of Life'      | ''       | 'CH6101MEA01'     |'C0805_H57_EOL'| '(SMC0805AW)'                                                        | 'NA'       | '6.3V'        | '20%'    | 'IO'       | 'CAP CHIP 10UF 6.3V(+-20%,X6S,0805)TAY'                        | 'CHIP0805'     | ''          | ''   | '20170503'
 '22UF'     | '6.3V'  | '20%'     | 'C0805'     | 'X5R'     | 'CH6221M9A27'(!)   = ''              | ''                 | ''       | 'CH6221M9A27'     |'C0805_H57'| '(SMC0805AW)'                                                        | '22UF'     | '6.3V'        | '20%'    | 'DISCRETE' | 'CAP CHIP 22U 6.3V(+-20%,X5R,0805)TAY'                         | 'CHIP0805'     | ''          | ''   | '20170503'
 '22UF'     | '6.3V'  | '20%'     | 'C0805'     | 'EMPTY'   | 'CH6221M9A27'(!)   = ''              | ''                 | ''       | 'CH6221M9A27'     |'C0805_H57'| '(SMC0805AW)'                                                        | 'NA'       | '6.3V'        | '20%'    | 'IO'       | 'CAP CHIP 22U 6.3V(+-20%,X5R,0805)TAY'                         | 'CHIP0805'     | ''          | ''   | '20170503'
 '10UF'     | '6.3V'  | '10%'     | 'C0805'     | 'X6S'     | 'CH6101KEA02'(!)   = 'End of Design' | 'Comp-Approve'     | ''       | 'CH6101KEA02'     |'C0805_H57'| '(SMC0805AW)'                                                        | '10UF'     | '6.3V'        | '10%'    | 'DISCRETE' | 'CAP CHIP 10UF,6.3V (+-10%,X6S,0805)MUR'                       | 'CHIP0805'     | ''          | ''   | '20170503'
 '10UF'     | '6.3V'  | '10%'     | 'C0805'     | 'EMPTY'   | 'CH6101KEA02'(!)   = 'End of Design' | 'Comp-Approve'     | ''       | 'CH6101KEA02'     |'C0805_H57'| '(SMC0805AW)'                                                        | 'NA'       | '6.3V'        | '10%'    | 'IO'       | 'CAP CHIP 10UF,6.3V (+-10%,X6S,0805)MUR'                       | 'CHIP0805'     | ''          | ''   | '20170503'
 '10UF'     | '6.3V'  | '20%'     | 'C0805'     | 'X6S'     | 'CH6101MEA02'(!)   = ''              | ''                 | ''       | 'CH6101MEA02'     |'C0805_H57'| '(SMC0805AW)'                                                        | '10UF'     | '6.3V'        | '20%'    | 'DISCRETE' | 'CAP CHIP 10UF 6.3V(+-20%,X6S,0805)MUR'                        | 'CHIP0805'     | ''          | ''   | '20170503'
 '10UF'     | '6.3V'  | '20%'     | 'C0805'     | 'EMPTY'   | 'CH6101MEA02'(!)   = ''              | ''                 | ''       | 'CH6101MEA02'     |'C0805_H57'| '(SMC0805AW)'                                                        | 'NA'       | '6.3V'        | '20%'    | 'IO'       | 'CAP CHIP 10UF 6.3V(+-20%,X6S,0805)MUR'                        | 'CHIP0805'     | ''          | ''   | '20170503'
 '22UF'     | '25V'   | '10%'     | 'C1206'     | 'X6S'     | 'CH6224KE201'(!)   = 'End of Design' | 'Comp-Approve'     | ''       | 'CH6224KE201'     |'C1206_H76'| '(SMC1206AW)'                                                        | '22UF'     | '25V'         | '10%'    | 'DISCRETE' | 'CAP CHIP 22U 25V(+-10%,X6S,1206)MUR'                          | 'CHIP1206'     | ''          | ''   | '20170503'
 '22UF'     | '25V'   | '10%'     | 'C1206'     | 'EMPTY'   | 'CH6224KE201'(!)   = 'End of Design' | 'Comp-Approve'     | ''       | 'CH6224KE201'     |'C1206_H76'| '(SMC1206AW)'                                                        | 'NA'       | '25V'         | '10%'    | 'IO'       | 'CAP CHIP 22U 25V(+-10%,X6S,1206)MUR'                          | 'CHIP1206'     | ''          | ''   | '20170503'
 '1UF'      | '25V'   | '10%'     | 'C0402'     | 'X6S'     | 'CH5104KEB03'(!)   = ''              | ''                 | ''       | 'CH5104KEB03'     |'C0402'| '(C0402_OCTAGONXA,C0402-0201,C0402_OCTAGONXA_BOUND22)'               | '1UF'      | '25V'         | '10%'    | 'DISCRETE' | 'CAP CHIP 1UF 25V(+-10%,X6S,0402)MUR'                          | 'CHIP0402'     | ''          | ''   | '20170509'
 '1UF'      | '25V'   | '10%'     | 'C0402'     | 'EMPTY'   | 'CH5104KEB03'(!)   = ''              | ''                 | ''       | 'CH5104KEB03'     |'C0402'| '(C0402_OCTAGONXA,C0402-0201,C0402_OCTAGONXA_BOUND22)'               | 'NA'       | '25V'         | '10%'    | 'IO'       | 'CAP CHIP 1UF 25V(+-10%,X6S,0402)MUR'                          | 'CHIP0402'     | ''          | ''   | '20170509'
 '16PF'     | '25V'   | '5%'      | 'C0402'     | 'NP0'     | 'CH0164J0B00'(!)   = ''              | ''                 | ''       | 'CH0164J0B00'     |'C0402'| '(C0402-0201)'                                                       | '16PF'     | '25V'         | '5%'     | 'DISCRETE' | 'CAP CHIP 16P 25V(+-5%,NP0,0402)'                              | 'CHIP0402'     | ''          | ''   | '20170509'
 '16PF'     | '25V'   | '5%'      | 'C0402'     | 'EMPTY'   | 'CH0164J0B00'(!)   = ''              | ''                 | ''       | 'CH0164J0B00'     |'C0402'| '(C0402-0201)'                                                       | 'NA'       | '25V'         | '5%'     | 'IO'       | 'CAP CHIP 16P 25V(+-5%,NP0,0402)'                              | 'CHIP0402'     | ''          | ''   | '20170509'
 '0.1UF'    | '16V'   | '10%'     | 'C0402'     | 'X7R'     | 'CH4103K1B13'(!)   = 'End of Design' | 'Comp-Approve'     | ''       | 'CH4103K1B13'     |'C0402'| '(C0402_OCTAGONXA,C0402_SMDC25_SM30,C0402-0201)'                     | '0.1UF'    | '16V'         | '10%'    | 'DISCRETE' | 'CAP CHIP 0.1U 16V(10%,X7R,0402)MUR'                           | 'CHIP0402'     | ''          | ''   | '20170524'
 '0.1UF'    | '16V'   | '10%'     | 'C0402'     | 'EMPTY'   | 'CH4103K1B13'(!)   = 'End of Design' | 'Comp-Approve'     | ''       | 'CH4103K1B13'     |'C0402'| '(C0402_OCTAGONXA,C0402_SMDC25_SM30,C0402-0201)'                     | 'NA'       | '16V'         | '10%'    | 'IO'       | 'CAP CHIP 0.1U 16V(10%,X7R,0402)MUR'                           | 'CHIP0402'     | ''          | ''   | '20170524'
 '22UF'     | '4V'    | '20%'     | 'C0402'     | 'X6S'     | 'CH622KMEB00'(!)   = 'End of Design' | 'Comp-Approve'     | ''       | 'CH622KMEB00'     |'C0402'| '(C0402_SMDC25_SM30,C0402-0201)'                                     | '22UF'     | '4V'          | '20%'    | 'DISCRETE' | 'CAP CHIP 22UF 4V(+-20%,X6S,0402)TAY'                          | 'CHIP0402'     | ''          | ''   | '20170524'
 '22UF'     | '4V'    | '20%'     | 'C0402'     | 'EMPTY'   | 'CH622KMEB00'(!)   = 'End of Design' | 'Comp-Approve'     | ''       | 'CH622KMEB00'     |'C0402'| '(C0402_SMDC25_SM30,C0402-0201)'                                     | 'NA'       | '4V'          | '20%'    | 'IO'       | 'CAP CHIP 22UF 4V(+-20%,X6S,0402)TAY'                          | 'CHIP0402'     | ''          | ''   | '20170524'
 '4.7PF'    | '50V'   | '0.25PF'  | 'C0402'     | 'C0G'     | 'CH-476C0B05'(!)   = 'End of Design' | 'Comp-Approve'     | ''       | 'CH-476C0B05'     |'C0402'| '(C0402-0201)'                                                       | '4.7PF'    | '50V'         | '0.25PF' | 'DISCRETE' | 'CAP CHIP 4.7P 50V(+-0.25P,C0G,0402)SAM'                       | 'CHIP0402'     | ''          | ''   | '20170526'
 '4.7PF'    | '50V'   | '0.25PF'  | 'C0402'     | 'EMPTY'   | 'CH-476C0B05'(!)   = 'End of Design' | 'Comp-Approve'     | ''       | 'CH-476C0B05'     |'C0402'| '(C0402-0201)'                                                       | 'NA'       | '50V'         | '0.25PF' | 'IO'       | 'CAP CHIP 4.7P 50V(+-0.25P,C0G,0402)SAM'                       | 'CHIP0402'     | ''          | ''   | '20170526'
 '4.7PF'    | '50V'   | '0.25PF'  | 'C0402'     | 'C0G'     | 'CH-476C0B04'(!)   = ''              | ''                 | ''       | 'CH-476C0B04'     |'C0402'| '(C0402-0201)'                                                       | '4.7PF'    | '50V'         | '0.25PF' | 'DISCRETE' | 'CAP CHIP 4.7P 50V(+-0.25P,C0G,0402)WTC'                       | 'CHIP0402'     | ''          | ''   | '20170526'
 '4.7PF'    | '50V'   | '0.25PF'  | 'C0402'     | 'EMPTY'   | 'CH-476C0B04'(!)   = ''              | ''                 | ''       | 'CH-476C0B04'     |'C0402'| '(C0402-0201)'                                                       | 'NA'       | '50V'         | '0.25PF' | 'IO'       | 'CAP CHIP 4.7P 50V(+-0.25P,C0G,0402)WTC'                       | 'CHIP0402'     | ''          | ''   | '20170526'
 '4.7PF'    | '50V'   | '0.25PF'  | 'C0402'     | 'C0G'     | 'CH-476C0B03'(!)   = ''              | ''                 | ''       | 'CH-476C0B03'     |'C0402'| '(C0402-0201)'                                                       | '4.7PF'    | '50V'         | '0.25PF' | 'DISCRETE' | 'CAP CHIP 4.7P 50V(+-0.25P,C0G,0402)MUR'                       | 'CHIP0402'     | ''          | ''   | '20170526'
 '4.7PF'    | '50V'   | '0.25PF'  | 'C0402'     | 'EMPTY'   | 'CH-476C0B03'(!)   = ''              | ''                 | ''       | 'CH-476C0B03'     |'C0402'| '(C0402-0201)'                                                       | 'NA'       | '50V'         | '0.25PF' | 'IO'       | 'CAP CHIP 4.7P 50V(+-0.25P,C0G,0402)MUR'                       | 'CHIP0402'     | ''          | ''   | '20170526'
 '22UF'     | '6.3V'  | '20%'     | 'C0402'     | 'X5R'     | 'CH6221M9B05'(!)   = ''              | ''                 | ''       | 'CH6221M9B05'     |'C0402'| '(C0402-0201)'                                                       | '22UF'     | '6.3V'        | '20%'    | 'DISCRETE' | 'CAP CHIP 22UF 6.3V(+-20%,X5R,0402)MUR'                        | 'CHIP0402'     | ''          | ''   | '20170626'
 '22UF'     | '6.3V'  | '20%'     | 'C0402'     | 'EMPTY'   | 'CH6221M9B05'(!)   = ''              | ''                 | ''       | 'CH6221M9B05'     |'C0402'| '(C0402-0201)'                                                       | 'NA'       | '6.3V'        | '20%'    | 'IO'       | 'CAP CHIP 22UF 6.3V(+-20%,X5R,0402)MUR'                        | 'CHIP0402'     | ''          | ''   | '20170626'
 '1UF'      | '10V'   | '10%'     | 'C0402'     | 'X6S'     | 'CH5102KEB02'(!)   = ''              | ''                 | ''       | 'CH5102KEB02'     |'C0402'| '(C0402-0201)'                                                       | '1UF'      | '10V'         | '10%'    | 'DISCRETE' | 'CAP CHIP 1UF 10V(+-10%,X6S,0402)MUR'                          | 'CHIP0402'     | ''          | ''   | '20170626'
 '1UF'      | '10V'   | '10%'     | 'C0402'     | 'EMPTY'   | 'CH5102KEB02'(!)   = ''              | ''                 | ''       | 'CH5102KEB02'     |'C0402'| '(C0402-0201)'                                                       | 'NA'       | '10V'         | '10%'    | 'IO'       | 'CAP CHIP 1UF 10V(+-10%,X6S,0402)MUR'                          | 'CHIP0402'     | ''          | ''   | '20170626'
 '6800PF'   | '100V'  | '10%'     | 'C0603'     | 'X7R'     | 'CH2688K1900'(!)   = ''              | ''                 | ''       | 'CH2688K1900'     |'C0603'| '(SMC0603AW)'                                                        | '6800PF'   | '100V'        | '10%'    | 'DISCRETE' | 'CAP CHIP 6800P 100V(+-10%,X7R,0603)MUR'                       | 'CHIP0603'     | ''          | ''   | '20170704'
 '6800PF'   | '100V'  | '10%'     | 'C0603'     | 'EMPTY'   | 'CH2688K1900'(!)   = ''              | ''                 | ''       | 'CH2688K1900'     |'C0603'| '(SMC0603AW)'                                                        | 'NA'       | '100V'        | '10%'    | 'IO'       | 'CAP CHIP 6800P 100V(+-10%,X7R,0603)MUR'                       | 'CHIP0603'     | ''          | ''   | '20170704'
 '0.47UF'   | '100V'  | '10%'     | 'C0805'     | 'X7R'     | 'CH4478K1A01'(!)   = 'End of Design' | 'Comp-Approve'     | ''       | 'CH4478K1A01'     |'C0805_H61'| '(SMC0805AW)'                                                        | '0.47UF'   | '100V'        | '10%'    | 'DISCRETE' | 'CAP CHIP 0.47U 100V(+-10%,X7R,0805)MUR'                       | 'CHIP0805'     | ''          | ''   | '20170705'
 '0.47UF'   | '100V'  | '10%'     | 'C0805'     | 'EMPTY'   | 'CH4478K1A01'(!)   = 'End of Design' | 'Comp-Approve'     | ''       | 'CH4478K1A01'     |'C0805_H61'| '(SMC0805AW)'                                                        | 'NA'       | '100V'        | '10%'    | 'IO'       | 'CAP CHIP 0.47U 100V(+-10%,X7R,0805)MUR'                       | 'CHIP0805'     | ''          | ''   | '20170705'
 '4.7UF'    | '100V'  | '10%'     | 'C1206'     | 'X7R'     | 'CH5478K1200'(!)   = ''              | ''                 | ''       | 'CH5478K1200'     |'C1206XB'| '(SMC1206AW)'                                                        | '4.7UF'    | '100V'        | '10%'    | 'DISCRETE' | 'CAP CHIP 4.7UF 100V(+-10%,X7R,1206)MUR'                       | 'CHIP1206'     | ''          | ''   | '20170705'
 '4.7UF'    | '100V'  | '10%'     | 'C1206'     | 'EMPTY'   | 'CH5478K1200'(!)   = ''              | ''                 | ''       | 'CH5478K1200'     |'C1206XB'| '(SMC1206AW)'                                                        | 'NA'       | '100V'        | '10%'    | 'IO'       | 'CAP CHIP 4.7UF 100V(+-10%,X7R,1206)MUR'                       | 'CHIP1206'     | ''          | ''   | '20170705'
 '68PF'     | '50V'   | '5%'      | 'C0402'     | 'COG'     | 'CH06806JB01'(!)   = ''              | ''                 | ''       | 'CH06806JB01'     |'C0402'| '(C0402-0201)'                                                       | '68PF'     | '50V'         | '5%'     | 'DISCRETE' | 'CAP CHIP 68P 50V(+-5%.COG.0402)'                              | 'CHIP0402'     | ''          | ''   | '20170725'
 '68PF'     | '50V'   | '5%'      | 'C0402'     | 'EMPTY'   | 'CH06806JB01'(!)   = ''              | ''                 | ''       | 'CH06806JB01'     |'C0402'| '(C0402-0201)'                                                       | 'NA'       | '50V'         | '5%'     | 'IO'       | 'CAP CHIP 68P 50V(+-5%.COG.0402)'                              | 'CHIP0402'     | ''          | ''   | '20170725'
 '22UF'     | '10V'   | '20%'     | 'C0603'     | 'X5R'     | 'CH6222M9901'(!)   = ''              | ''                 | ''       | 'CH6222M9901'     |'C0603'| '(SMC0603AW)'                                                        | '22UF'     | '10V'         | '20%'    | 'DISCRETE' | 'CAP CHIP 22UF 10V(+-20%,X5R,0603)'                            | 'CHIP0603'     | ''          | ''   | '20170801'
 '22UF'     | '10V'   | '20%'     | 'C0603'     | 'EMPTY'   | 'CH6222M9901'(!)   = ''              | ''                 | ''       | 'CH6222M9901'     |'C0603'| '(SMC0603AW)'                                                        | 'NA'       | '10V'         | '20%'    | 'IO'       | 'CAP CHIP 22UF 10V(+-20%,X5R,0603)'                            | 'CHIP0603'     | ''          | ''   | '20170801'
 '0.047UF'  | '100V'  | '10%'     | 'C0805'     | 'X7R'     | 'CH3478K1A01'(!)   = ''              | ''                 | ''       | 'CH3478K1A01'     |'C0805_H57'| '(SMC0805AW)'                                                        | '0.047UF'  | '100V'        | '10%'    | 'DISCRETE' | 'CAP CHIP 0.047UF 100V(+-10%,X7R,0805)MUR'                     | 'CHIP0805'     | ''          | ''   | '20170809'
 '0.047UF'  | '100V'  | '10%'     | 'C0805'     | 'EMPTY'   | 'CH3478K1A01'(!)   = ''              | ''                 | ''       | 'CH3478K1A01'     |'C0805_H57'| '(SMC0805AW)'                                                        | 'NA'       | '100V'        | '10%'    | 'IO'       | 'CAP CHIP 0.047UF 100V(+-10%,X7R,0805)MUR'                     | 'CHIP0805'     | ''          | ''   | '20170809'
 '0.0082UF' | '50V'   | '5%'      | 'C0603'     | 'C0G'     | 'CH2826J0900'(!)   = 'End of Design' | 'Comp-Approve'     | ''       | 'CH2826J0900'     |'C0603'| '(SMC0603AW)'                                                        | '0.0082UF' | '50V'         | '5%'     | 'DISCRETE' | 'CAP CHIP 0.0082U 50V(+-5%,C0G,0603)'                          | 'CHIP0603'     | ''          | ''   | '20170817'
 '0.0082UF' | '50V'   | '5%'      | 'C0603'     | 'EMPTY'   | 'CH2826J0900'(!)   = 'End of Design' | 'Comp-Approve'     | ''       | 'CH2826J0900'     |'C0603'| '(SMC0603AW)'                                                        | 'NA'       | '50V'         | '5%'     | 'IO'       | 'CAP CHIP 0.0082U 50V(+-5%,C0G,0603)'                          | 'CHIP0603'     | ''          | ''   | '20170817'
 '0.47UF'   | '16V'   | '10%'     | 'C0402'     | 'X7R'     | 'CH4473K1B01'(!)   = 'End of Design' | 'Comp-Approve'     | ''       | 'CH4473K1B01'     |'C0402'| '(C0402-0201)'                                                       | '0.47UF'   | '16V'         | '10%'    | 'DISCRETE' | 'CAP CHIP 0.47U 16V(+-10%,X7R,0402)MUR'                        | 'CHIP0402'     | ''          | ''   | '20170817'
 '0.47UF'   | '16V'   | '10%'     | 'C0402'     | 'EMPTY'   | 'CH4473K1B01'(!)   = 'End of Design' | 'Comp-Approve'     | ''       | 'CH4473K1B01'     |'C0402'| '(C0402-0201)'                                                       | 'NA'       | '16V'         | '10%'    | 'IO'       | 'CAP CHIP 0.47U 16V(+-10%,X7R,0402)MUR'                        | 'CHIP0402'     | ''          | ''   | '20170817'
 '820PF'    | '100V'  | '5%'      | 'C0603'     | 'C0G'     | 'CH1828J0900'(!)   = 'End of Design' | 'Comp-Release Qty' | ''       | 'CH1828J0900'     |'C0603'| '(SMC0603AW)'                                                        | '820PF'    | '100V'        | '5%'     | 'DISCRETE' | 'CAP CHIP 820P 100V(+-5%,C0G,0603)'                            | 'CHIP0603'     | ''          | ''   | '20170821'
 '820PF'    | '100V'  | '5%'      | 'C0603'     | 'EMPTY'   | 'CH1828J0900'(!)   = 'End of Design' | 'Comp-Release Qty' | ''       | 'CH1828J0900'     |'C0603'| '(SMC0603AW)'                                                        | 'NA'       | '100V'        | '5%'     | 'IO'       | 'CAP CHIP 820P 100V(+-5%,C0G,0603)'                            | 'CHIP0603'     | ''          | ''   | '20170821'
 '33NF'     | '25V'   | '10%'     | 'C0402'     | 'X7R'     | 'CH3334K1B02'(!)   = ''              | ''                 | ''       | 'CH3334K1B02'     |'C0402'| '(C0402-0201)'                                                       | '33NF'     | '25V'         | '10%'    | 'DISCRETE' | 'CAP CHIP 33NF 25V(+-10%,X7R,0402)MUR'                         | 'CHIP0402'     | ''          | ''   | '20170904'
 '33NF'     | '25V'   | '10%'     | 'C0402'     | 'EMPTY'   | 'CH3334K1B02'(!)   = ''              | ''                 | ''       | 'CH3334K1B02'     |'C0402'| '(C0402-0201)'                                                       | 'NA'       | '25V'         | '10%'    | 'IO'       | 'CAP CHIP 33NF 25V(+-10%,X7R,0402)MUR'                         | 'CHIP0402'     | ''          | ''   | '20170904'
 '0.039UF'  | '50V'   | '10%'     | 'C0603'     | 'X7R'     | 'CH3396K1900'(!)   = ''              | ''                 | ''       | 'CH3396K1900'     |'C0603'| '(SMC0603AW)'                                                        | '0.039UF'  | '50V'         | '10%'    | 'DISCRETE' | 'CAP CHIP 0.039U 50V(+-10%,X7R,0603)'                          | 'CHIP0603'     | ''          | ''   | '20170918'
 '0.039UF'  | '50V'   | '10%'     | 'C0603'     | 'EMPTY'   | 'CH3396K1900'(!)   = ''              | ''                 | ''       | 'CH3396K1900'     |'C0603'| '(SMC0603AW)'                                                        | 'NA'       | '50V'         | '10%'    | 'IO'       | 'CAP CHIP 0.039U 50V(+-10%,X7R,0603)'                          | 'CHIP0603'     | ''          | ''   | '20170918'
 '100NF'    | '50V'   | '10%'     | 'C0402'     | 'X7R'     | 'CH4106K1B01'(!)   = ''              | ''                 | ''       | 'CH4106K1B01'     |'C0402'| '(C0402_OCTAGONXA,C0402-0201)'                                       | '100NF'    | '50V'         | '10%'    | 'DISCRETE' | 'CAP CHIP 100NF 50V(+-10%,X7R,0402)'                           | 'CHIP0402'     | ''          | ''   | '20171109'
 '100NF'    | '50V'   | '10%'     | 'C0402'     | 'EMPTY'   | 'CH4106K1B01'(!)   = ''              | ''                 | ''       | 'CH4106K1B01'     |'C0402'| '(C0402_OCTAGONXA,C0402-0201)'                                       | 'NA'       | '50V'         | '10%'    | 'IO'       | 'CAP CHIP 100NF 50V(+-10%,X7R,0402)'                           | 'CHIP0402'     | ''          | ''   | '20171109'
 '0.22UF'   | '25V'   | '10%'     | 'C0402'     | 'X7R'     | 'CH4224K1B01'(!)   = 'End of Design' | 'Comp-Release Qty' | ''       | 'CH4224K1B01'     |'C0402'| '(C0402_OCTAGONXA,C0402-0201)'                                       | '0.22UF'   | '25V'         | '10%'    | 'DISCRETE' | 'CAP CHIP 0.22U 25V(10%,X7R,0402)'                             | 'CHIP0402'     | ''          | ''   | '20171109'
 '0.22UF'   | '25V'   | '10%'     | 'C0402'     | 'EMPTY'   | 'CH4224K1B01'(!)   = 'End of Design' | 'Comp-Release Qty' | ''       | 'CH4224K1B01'     |'C0402'| '(C0402_OCTAGONXA,C0402-0201)'                                       | 'NA'       | '25V'         | '10%'    | 'IO'       | 'CAP CHIP 0.22U 25V(10%,X7R,0402)'                             | 'CHIP0402'     | ''          | ''   | '20171109'
 '1UF'      | '16V'   | '10%'     | '0603'      | 'X7R'     | 'TMP_QCH5103K1900'(!) = 'End of Design' | 'Comp-Approve'     | ''       | 'CH5103K1900'     |'C0603'| '(SMC0603AW)'                                                        | '1UF'      | '16V'         | '10%'    | 'DISCRETE' | 'CHIP0603'                                                     | 'CHIP0603'     | ''          | ''   | ''        
 '1UF'      | '16V'   | '10%'     | '0603'      | 'EMPTY'   | 'TMP_QCH5103K1900'(!) = 'End of Design' | 'Comp-Approve'     | ''       | 'CH5103K1900'     |'C0603'| '(SMC0603AW)'                                                        | 'NA'       | '16V'         | '10%'    | 'IO'       | 'CHIP0603'                                                     | 'CHIP0603'     | ''          | ''   | ''        
 '10UF'     | '6.3V'  | '20%'     | '0603'      | 'X5R'     | 'CH6101M9905'(!)   = 'End of Design' | 'Comp-Release Qty' | ''       | 'CH6101M9905'     |'C0603'| '(SMC0603AW)'                                                        | '10UF'     | '6.3V'        | '20%'    | 'DISCRETE' | 'CAP CHIP 10U 6.3V(+-20%,X5R,0603)'                            | 'CHIP0603'     | ''          | ''   | '2010701' 
 '10UF'     | '6.3V'  | '20%'     | '0603'      | 'EMPTY'   | 'CH6101M9905'(!)   = 'End of Design' | 'Comp-Release Qty' | ''       | 'CH6101M9905'     |'C0603'| '(SMC0603AW)'                                                        | 'NA'       | '6.3V'        | '20%'    | 'IO'       | 'CAP CHIP 10U 6.3V(+-20%,X5R,0603)'                            | 'CHIP0603'     | ''          | ''   | '2010701' 
 '10UF  '   | '16V '  | '10%'     | '0805'      | 'X5R'     | 'CH6103K9A00'(!)   = 'End of Design' | 'Comp-Approve'     | ''       | 'CH6103K9A00'     |'C0805_H61'| '(SMC0805AW)'                                                        | '10UF   '  | '16V'         | '10%'    | 'DISCRETE' | 'CAP CHIP 10U 16V(10%,X5R,0805)H1.25'                          | 'CHIP0805'     | ''          | ''   | '20100827'
 '10UF  '   | '16V '  | '10%'     | '0805'      | 'EMPTY'   | 'CH6103K9A00'(!)   = 'End of Design' | 'Comp-Approve'     | ''       | 'CH6103K9A00'     |'C0805_H61'| '(SMC0805AW)'                                                        | 'NA'       | '16V'         | '10%'    | 'IO'       | 'CAP CHIP 10U 16V(10%,X5R,0805)H1.25'                          | 'CHIP0805'     | ''          | ''   | '20100827'
 '22UF'     | '6.3V'  | '20%'     | '0805'      | 'X6S'     | 'CH6221MEA01'(!)   = 'End of Design' | 'Comp-Approve'     | ''       | 'CH6221MEA01'     |'C0805_H57'| '(SMC0805AW)'                                                        | '22UF'     | '6.3V'        | '20%'    | 'DISCRETE' | 'CAP CHIP 22U 6.3V(+-20%,X6S,0805)H1.25'                       | 'CHIP0805'     | ''          | ''   | '20101116'
 '22UF'     | '6.3V'  | '20%'     | '0805'      | 'EMPTY'   | 'CH6221MEA01'(!)   = 'End of Design' | 'Comp-Approve'     | ''       | 'CH6221MEA01'     |'C0805_H57'| '(SMC0805AW)'                                                        | 'NA'       | '6.3V'        | '20%'    | 'IO'       | 'CAP CHIP 22U 6.3V(+-20%,X6S,0805)H1.25'                       | 'CHIP0805'     | ''          | ''   | '20101116'
 '1UF'      | '6.3V'  | '20%'     | 'C0201'     | 'X6S'     | 'CH5101MEE01'(!)   = ''              | ''                 | ''       | 'CH5101MEE01'     |'C0201'| '(SMC0201AW)'                                                        | '1UF'      | '6.3V'        | '20%'    | 'DISCRETE' | 'CAP CHIP 1U 6.3V(+-20%,X6S,0201)'                             | 'CHIP0201'     | ''          | ''   | '20171115'
 '1UF'      | '6.3V'  | '20%'     | 'C0201'     | 'EMPTY'   | 'CH5101MEE01'(!)   = ''              | ''                 | ''       | 'CH5101MEE01'     |'C0201'| '(SMC0201AW)'                                                        | 'NA'       | '6.3V'        | '20%'    | 'IO'       | 'CAP CHIP 1U 6.3V(+-20%,X6S,0201)'                             | 'CHIP0201'     | ''          | ''   | '20171115'
 '0.22UF'   | '6.3V'  | '10%'     | 'C0201'     | 'X6S'     | 'CH4221KEE00'(!)   = ''              | ''                 | ''       | 'CH4221KEE00'     |'C0201'| '(SMC0201AW)'                                                        | '0.22UF'   | '6.3V'        | '10%'    | 'DISCRETE' | 'CAP CHIP 0.22UF 6.3V(+-10%,X6S,0201)'                         | 'CHIP0201'     | ''          | ''   | '20171116'
 '0.22UF'   | '6.3V'  | '10%'     | 'C0201'     | 'EMPTY'   | 'CH4221KEE00'(!)   = ''              | ''                 | ''       | 'CH4221KEE00'     |'C0201'| '(SMC0201AW)'                                                        | 'NA'       | '6.3V'        | '10%'    | 'IO'       | 'CAP CHIP 0.22UF 6.3V(+-10%,X6S,0201)'                         | 'CHIP0201'     | ''          | ''   | '20171116'
 '10UF'     | '4V'    | '20%'     | 'C0805'     | 'X6S'     | 'CH610KMEA03'(!)   = 'End of Design' | 'Comp-Approve'     | ''       | 'CH610KMEA03'     |'C0805_H57'| '(SMC0805AW)'                                                        | '10UF'     | '4V'          | '20%'    | 'DISCRETE' | 'CAP CHIP 10U,4V(+-20%,X6S,0805)MUR'                           | 'CHIP0805'     | ''          | ''   | '20171120'
 '10UF'     | '4V'    | '20%'     | 'C0805'     | 'EMPTY'   | 'CH610KMEA03'(!)   = 'End of Design' | 'Comp-Approve'     | ''       | 'CH610KMEA03'     |'C0805_H57'| '(SMC0805AW)'                                                        | 'NA'       | '4V'          | '20%'    | 'IO'       | 'CAP CHIP 10U,4V(+-20%,X6S,0805)MUR'                           | 'CHIP0805'     | ''          | ''   | '20171120'
 '0.01UF'   | '10V'   | '10%'     | 'C0201'     | 'X7R'     | 'CH3102K1E01'(!)   = ''              | ''                 | ''       | 'CH3102K1E01'     |'C0201'| '(SMC0201AW)'                                                        | '0.01UF'   | '10V'         | '10%'    | 'DISCRETE' | 'CAP CHIP 0.01UF 10V(10%,X7R,0201)'                            | 'CHIP0201'     | ''          | ''   | '20171121'
 '0.01UF'   | '10V'   | '10%'     | 'C0201'     | 'EMPTY'   | 'CH3102K1E01'(!)   = ''              | ''                 | ''       | 'CH3102K1E01'     |'C0201'| '(SMC0201AW)'                                                        | 'NA'       | '10V'         | '10%'    | 'IO'       | 'CAP CHIP 0.01UF 10V(10%,X7R,0201)'                            | 'CHIP0201'     | ''          | ''   | '20171121'
 '4.7UF'    | '25V'   | '10%'     | 'C0603'     | 'X6S'     | 'CH5474KE905'(!)   = 'End of Design' | 'Comp-Approve'     | ''       | 'CH5474KE905'     |'C0603'| '(SMC0603AW)'                                                        | '4.7UF'    | '25V'         | '10%'    | 'DISCRETE' | 'CAP CHIP 4.7U 25V(+-10%,X6S,0603)WTC'                         | 'CHIP0603'     | ''          | ''   | '20171121'
 '4.7UF'    | '25V'   | '10%'     | 'C0603'     | 'EMPTY'   | 'CH5474KE905'(!)   = 'End of Design' | 'Comp-Approve'     | ''       | 'CH5474KE905'     |'C0603'| '(SMC0603AW)'                                                        | 'NA'       | '25V'         | '10%'    | 'IO'       | 'CAP CHIP 4.7U 25V(+-10%,X6S,0603)WTC'                         | 'CHIP0603'     | ''          | ''   | '20171121'
 '1000PF'   | '16V'   | '5%'      | 'C0201'     | 'X7R'     | 'CH2103J1E01'(!)   = ''              | ''                 | ''       | 'CH2103J1E01'     |'C0201'| '(SMC0201AW)'                                                        | '1000PF'   | '16V'         | '5%'     | 'DISCRETE' | 'CAP CHIP 1000P 16V(+-5%,X7R,0201)'                            | 'CHIP0201'     | ''          | ''   | '20171121'
 '1000PF'   | '16V'   | '5%'      | 'C0201'     | 'EMPTY'   | 'CH2103J1E01'(!)   = ''              | ''                 | ''       | 'CH2103J1E01'     |'C0201'| '(SMC0201AW)'                                                        | 'NA'       | '16V'         | '5%'     | 'IO'       | 'CAP CHIP 1000P 16V(+-5%,X7R,0201)'                            | 'CHIP0201'     | ''          | ''   | '20171121'
 '22UF'     | '16V'   | '20%'     | 'C0805'     | 'X6S'     | 'CH6223MEA01'(!)   = ''              | ''                 | ''       | 'CH6223MEA01'     |'C0805_H57'| '(SMC0805AW)'                                                        | '22UF'     | '16V'         | '20%'    | 'DISCRETE' | 'CAP CHIP 22UF 16V(+-20%,X6S,0805)MUR'                         | 'CHIP0805'     | ''          | ''   | '20171127'
 '22UF'     | '16V'   | '20%'     | 'C0805'     | 'EMPTY'   | 'CH6223MEA01'(!)   = ''              | ''                 | ''       | 'CH6223MEA01'     |'C0805_H57'| '(SMC0805AW)'                                                        | 'NA'       | '16V'         | '20%'    | 'IO'       | 'CAP CHIP 22UF 16V(+-20%,X6S,0805)MUR'                         | 'CHIP0805'     | ''          | ''   | '20171127'
 '47UF'     | '6.3V'  | '20%'     | 'C0805'     | 'X5R'     | 'CH6471M9A08'(!)   = ''              | ''                 | ''       | 'CH6471M9A08'     |'C0805_H57'| '(SMC0805AW)'                                                        | '47UF'     | '6.3V'        | '20%'    | 'DISCRETE' | 'CAP CHIP 47U 6.3V(+-20%,X5R,0805)MUR'                         | 'CHIP0805'     | ''          | ''   | '20171206'
 '47UF'     | '6.3V'  | '20%'     | 'C0805'     | 'EMPTY'   | 'CH6471M9A08'(!)   = ''              | ''                 | ''       | 'CH6471M9A08'     |'C0805_H57'| '(SMC0805AW)'                                                        | 'NA'       | '6.3V'        | '20%'    | 'IO'       | 'CAP CHIP 47U 6.3V(+-20%,X5R,0805)MUR'                         | 'CHIP0805'     | ''          | ''   | '20171206'
 '0.1UF'    | '25V'   | '10%'     | 'C0402'     | 'X7R'     | 'CH4104K1B11'(!)   = ''              | ''                 | ''       | 'CH4104K1B11'     |'C0402'| '(C0402-0201)'                                                       | '0.1UF'    | '25V'         | '10%'    | 'DISCRETE' | 'CAP CHIP 0.1U 25V(+-10%,X7R,0402)TAY'                         | 'CHIP0402'     | ''          | ''   | '20171212'
 '0.1UF'    | '25V'   | '10%'     | 'C0402'     | 'EMPTY'   | 'CH4104K1B11'(!)   = ''              | ''                 | ''       | 'CH4104K1B11'     |'C0402'| '(C0402-0201)'                                                       | 'NA'       | '25V'         | '10%'    | 'IO'       | 'CAP CHIP 0.1U 25V(+-10%,X7R,0402)TAY'                         | 'CHIP0402'     | ''          | ''   | '20171212'
 '10UF'     | '16V'   | '20%'     | 'C0603'     | 'X5R'     | 'CH6103M9900'(!)   = ''              | ''                 | ''       | 'CH6103M9900'     |'C0603_H40'| '(SMC0603AW)'                                                        | '10UF'     | '16V'         | '20%'    | 'DISCRETE' | 'CAP CHIP 10U 16V(+-20%,X5R,0603)'                             | 'CHIP0603'     | ''          | ''   | '20171221'
 '10UF'     | '16V'   | '20%'     | 'C0603'     | 'EMPTY'   | 'CH6103M9900'(!)   = ''              | ''                 | ''       | 'CH6103M9900'     |'C0603_H40'| '(SMC0603AW)'                                                        | 'NA'       | '16V'         | '20%'    | 'IO'       | 'CAP CHIP 10U 16V(+-20%,X5R,0603)'                             | 'CHIP0603'     | ''          | ''   | '20171221'
 '0.1UF'    | '25V'   | '10%'     | 'C0402'     | 'X6S'     | 'CH4104KEB00'(!)   = 'End of Design' | 'Comp-Approve'     | ''       | 'CH4104KEB00'     |'C0402'| '(C0402-0201)'                                                       | '0.1UF'    | '25V'         | '10%'    | 'DISCRETE' | 'CAP CHIP 0.1U 25V(+-10%,X6S,0402)'                            | 'CHIP0402'     | ''          | ''   | '20171221'
 '0.1UF'    | '25V'   | '10%'     | 'C0402'     | 'EMPTY'   | 'CH4104KEB00'(!)   = 'End of Design' | 'Comp-Approve'     | ''       | 'CH4104KEB00'     |'C0402'| '(C0402-0201)'                                                       | 'NA'       | '25V'         | '10%'    | 'IO'       | 'CAP CHIP 0.1U 25V(+-10%,X6S,0402)'                            | 'CHIP0402'     | ''          | ''   | '20171221'
 '1UF'      | '6.3V'  | '10%'     | 'C0201'     | 'X5R'     | 'CH5101K9E02'(!)   = 'End of Design' | 'Comp-Release Qty' | ''       | 'CH5101K9E02'     |'C0201'| '(SMC0201AW)'                                                        | '1UF'      | '6.3V'        | '10%'    | 'DISCRETE' | 'CAP CHIP 1U 6.3V(+-10%,X5R,0201)'                             | 'CHIP0201'     | ''          | ''   | '20171221'
 '1UF'      | '6.3V'  | '10%'     | 'C0201'     | 'EMPTY'   | 'CH5101K9E02'(!)   = 'End of Design' | 'Comp-Release Qty' | ''       | 'CH5101K9E02'     |'C0201'| '(SMC0201AW)'                                                        | 'NA'       | '6.3V'        | '10%'    | 'IO'       | 'CAP CHIP 1U 6.3V(+-10%,X5R,0201)'                             | 'CHIP0201'     | ''          | ''   | '20171221'
 '4.7UF'    | '10V'   | '10%'     | 'C0402'     | 'X5R'     | 'CH5472K9B02'(!)   = ''              | ''                 | ''       | 'CH5472K9B02'     |'C0402'| '(C0402-0201)'                                                       | '4.7UF'    | '10V'         | '10%'    | 'DISCRETE' | 'CAP CHIP 4.7U 10V(+-10%,X5R,0402)MUR'                         | 'CHIP0402'     | ''          | ''   | '20171222'
 '4.7UF'    | '10V'   | '10%'     | 'C0402'     | 'EMPTY'   | 'CH5472K9B02'(!)   = ''              | ''                 | ''       | 'CH5472K9B02'     |'C0402'| '(C0402-0201)'                                                       | 'NA'       | '10V'         | '10%'    | 'IO'       | 'CAP CHIP 4.7U 10V(+-10%,X5R,0402)MUR'                         | 'CHIP0402'     | ''          | ''   | '20171222'
 '270PF'    | '25V'   | '5%'      | 'C0402'     | 'NPO'     | 'CH12704JB07'(!)   = ''              | ''                 | ''       | 'CH12704JB07'     |'C0402'| '(C0402-0201)'                                                       | ' 270PF'   | '25V'         | '5%'     | 'DISCRETE' | 'CAP CHIP 270P 25V(+-5%,NPO,0402)'                             | 'CHIP0402'     | ''          | ''   | '20180126'
 '270PF'    | '25V'   | '5%'      | 'C0402'     | 'EMPTY'   | 'CH12704JB07'(!)   = ''              | ''                 | ''       | 'CH12704JB07'     |'C0402'| '(C0402-0201)'                                                       | 'NA'       | '25V'         | '5%'     | 'IO'       | 'CAP CHIP 270P 25V(+-5%,NPO,0402)'                             | 'CHIP0402'     | ''          | ''   | '20180126'
 '22UF'     | '4V'    | '20%'     | 'C0402'     | 'X6S'     | 'CH622KMEB01'(!)   = ''              | ''                 | ''       | 'CH622KMEB01'     |'C0402_H32'| '(C0402_OCTAGONXA,C0402-0201_H32)'                                   | '22UF'     | '4V'          | '20%'    | 'DISCRETE' | 'CAP CHIP 22UF 4V(+-20%,X6S,0402)MUR'                          | 'CHIP0402'     | ''          | ''   | '20180313'
 '22UF'     | '4V'    | '20%'     | 'C0402'     | 'EMPTY'   | 'CH622KMEB01'(!)   = ''              | ''                 | ''       | 'CH622KMEB01'     |'C0402_H32'| '(C0402_OCTAGONXA,C0402-0201_H32)'                                   | 'NA'       | '4V'          | '20%'    | 'IO'       | 'CAP CHIP 22UF 4V(+-20%,X6S,0402)MUR'                          | 'CHIP0402'     | ''          | ''   | '20180313'
 '1UF'      | '10V'   | '20%'     | 'C0201'     | 'X5R'     | 'CH5102M9E01'(!)   = ''              | ''                 | ''       | 'CH5102M9E01'     |'C0201'| '(SMC0201AW)'                                                        | '1UF'      | '10V'         | '20%'    | 'DISCRETE' | 'CAP CHIP 1UF 10V(+-20%,X5R,0201)'                             | 'CHIP0201'     | ''          | ''   | '20180320'
 '1UF'      | '10V'   | '20%'     | 'C0201'     | 'EMPTY'   | 'CH5102M9E01'(!)   = ''              | ''                 | ''       | 'CH5102M9E01'     |'C0201'| '(SMC0201AW)'                                                        | 'NA'       | '10V'         | '20%'    | 'IO'       | 'CAP CHIP 1UF 10V(+-20%,X5R,0201)'                             | 'CHIP0201'     | ''          | ''   | '20180320'
 '1UF'      | '25V'   | '10%'     | 'C0402'     | 'X7S'     | 'CH5104K6B00'(!)   = ''              | ''                 | ''       | 'CH5104K6B00'     |'C0402_H28'| '(C0402-0201_H28)'                                                   | '1UF'      | '25V'         | '10%'    | 'DISCRETE' | 'CAP CHIP 1U 25V (+-10%, X7S, 0402)MUR'                        | 'CHIP0402'     | ''          | ''   | '20180403'
 '1UF'      | '25V'   | '10%'     | 'C0402'     | 'EMPTY'   | 'CH5104K6B00'(!)   = ''              | ''                 | ''       | 'CH5104K6B00'     |'C0402_H28'| '(C0402-0201_H28)'                                                   | 'NA'       | '25V'         | '10%'    | 'IO'       | 'CAP CHIP 1U 25V (+-10%, X7S, 0402)MUR'                        | 'CHIP0402'     | ''          | ''   | '20180403'
 '0.1UF'    | '16V'   | '10%'     | 'C0201'     | 'X6S'     | 'CH4103KEE03'(!)   = ''              | ''                 | ''       | 'CH4103KEE03'     |'C0201'| '(C0201_HOME-PLATE_H22)'                                             | '0.1UF'    | '16V'         | '10%'    | 'DISCRETE' | 'CAP CHIP 0.1UF 16V(+-10%,X6S,0201)MUR'                        | 'CHIP0201'     | ''          | ''   | '20180403'
 '0.1UF'    | '16V'   | '10%'     | 'C0201'     | 'EMPTY'   | 'CH4103KEE03'(!)   = ''              | ''                 | ''       | 'CH4103KEE03'     |'C0201'| '(C0201_HOME-PLATE_H22)'                                             | 'NA'       | '16V'         | '10%'    | 'IO'       | 'CAP CHIP 0.1UF 16V(+-10%,X6S,0201)MUR'                        | 'CHIP0201'     | ''          | ''   | '20180403'
 '0.01U'    | '25V'   | '5%'      | 'C0402'     | 'X7R'     | 'CH3104J1B01'(!)   = ''              | ''                 | ''       | 'CH3104J1B01'     |'C0402'| '(C0402-0201)'                                                       | '0.01UF'   | '25V'         | '5%'     | 'DISCRETE' | 'CAP CHIP 0.01U 25V (+-5%,X7R,0402)MUR'                        | 'CHIP0402'     | ''          | ''   | '20180403'
 '0.01U'    | '25V'   | '5%'      | 'C0402'     | 'EMPTY'   | 'CH3104J1B01'(!)   = ''              | ''                 | ''       | 'CH3104J1B01'     |'C0402'| '(C0402-0201)'                                                       | 'NA'       | '25V'         | '5%'     | 'IO'       | 'CAP CHIP 0.01U 25V (+-5%,X7R,0402)MUR'                        | 'CHIP0402'     | ''          | ''   | '20180403'
 '22UF'     | '4V'    | '20%'     | 'C0402'     | 'X6S'     | 'CH622KMEB02'(!)   = 'End of Design' | 'Comp-Approve'     | ''       | 'CH622KMEB02'     |'C0402_H32'| '(C0402-0201_H32,C0402_OCTAGONXA)'                                   | '22UF'     | '4V'          | '20%'    | 'DISCRETE' | 'CAP CHIP 22UF 4V(+-20%,X6S,0402)'                             | 'CHIP0402'     | ''          | ''   | '20180409'
 '22UF'     | '4V'    | '20%'     | 'C0402'     | 'EMPTY'   | 'CH622KMEB02'(!)   = 'End of Design' | 'Comp-Approve'     | ''       | 'CH622KMEB02'     |'C0402_H32'| '(C0402-0201_H32,C0402_OCTAGONXA)'                                   | 'NA'       | '4V'          | '20%'    | 'IO'       | 'CAP CHIP 22UF 4V(+-20%,X6S,0402)'                             | 'CHIP0402'     | ''          | ''   | '20180409'
 '1000PF'   | '25V'   | '5%'      | 'C0402'     | 'NPO'     | 'CH2104J0B00'(!)   = ''              | ''                 | ''       | 'CH2104J0B00'     |'C0402'| '(C0402-0201)'                                                       | '1000PF'   | '25V'         | '5%'     | 'DISCRETE' | 'CAP CHIP 1000PF 25V (5%,NPO,0402)'                            | 'CHIP0402'     | ''          | ''   | '20180419'
 '1000PF'   | '25V'   | '5%'      | 'C0402'     | 'EMPTY'   | 'CH2104J0B00'(!)   = ''              | ''                 | ''       | 'CH2104J0B00'     |'C0402'| '(C0402-0201)'                                                       | 'NA'       | '25V'         | '5%'     | 'IO'       | 'CAP CHIP 1000PF 25V (5%,NPO,0402)'                            | 'CHIP0402'     | ''          | ''   | '20180419'
 '1.4UF'    | '50V'   | '5%'      | 'C1812'     | 'U2J'     | 'CH5146JF400'(!)   = 'End of Design' | 'P/N Release'      | ''       | 'CH5146JF400'     |'C1812_X3'| '(SMC1812AW)'                                                        | '1.4UF'    | '50V'         | '5%'     | 'DISCRETE' | 'CAP CHIP 1.4UF 50V(5%,U2J,1812)KEM'                           | 'CHIP1812'     | ''          | ''   | '20180423'
 '1.4UF'    | '50V'   | '5%'      | 'C1812'     | 'EMPTY'   | 'CH5146JF400'(!)   = 'End of Design' | 'P/N Release'      | ''       | 'CH5146JF400'     |'C1812_X3'| '(SMC1812AW)'                                                        | 'NA'       | '50V'         | '5%'     | 'IO'       | 'CAP CHIP 1.4UF 50V(5%,U2J,1812)KEM'                           | 'CHIP1812'     | ''          | ''   | '20180423'
 '10UF'     | '100V'  | '10%'     | 'C1210'     | 'X7S'     | 'CH6108K6300'(!)   = ''              | ''                 | ''       | 'CH6108K6300'     |'C1210_GRM32E'| '(SMC1210AW)'                                                        | '10UF'     | '100V'        | '10%'    | 'DISCRETE' | 'CAP CHIP 10UF 100V(+-10%,X7S,1210)MUR'                        | 'CHIP1210'     | ''          | ''   | '20180423'
 '10UF'     | '100V'  | '10%'     | 'C1210'     | 'EMPTY'   | 'CH6108K6300'(!)   = ''              | ''                 | ''       | 'CH6108K6300'     |'C1210_GRM32E'| '(SMC1210AW)'                                                        | 'NA'       | '100V'        | '10%'    | 'IO'       | 'CAP CHIP 10UF 100V(+-10%,X7S,1210)MUR'                        | 'CHIP1210'     | ''          | ''   | '20180423'
 '0.1UF'    | '6.3V'  | '10%'     | 'C0402'     | 'X7R'     | 'CH4101K1B01'(!)   = 'End of Design' | 'Comp-Approve'     | ''       | 'CH4101K1B01'     |'C0402'| '(C0402-0201)'                                                       | '0.1UF'    | '6.3V'        | '10%'    | 'DISCRETE' | 'CAP CHIP 0.1UF 6.3V(+-10%,X7R,0402)MUR'                       | 'CHIP0402'     | ''          | ''   | '20150729'
 '0.1UF'    | '6.3V'  | '10%'     | 'C0402'     | 'EMPTY'   | 'CH4101K1B01'(!)   = 'End of Design' | 'Comp-Approve'     | ''       | 'CH4101K1B01'     |'C0402'| '(C0402-0201)'                                                       | 'NA'       | '6.3V'        | '10%'    | 'IO'       | 'CAP CHIP 0.1UF 6.3V(+-10%,X7R,0402)MUR'                       | 'CHIP0402'     | ''          | ''   | '20150729'
 '0.22UF'   | '25V'   | '10%'     | 'C0402'     | 'X7R'     | 'CH4224K1B03'(!)   = 'End of Design' | 'Comp-Approve'     | ''       | 'CH4224K1B03'     |'C0402'| '(C0402-0201)'                                                       | '0.22UF'   | '25V'         | '10%'    | 'DISCRETE' | 'CAP CHIP 0.22UF 25V(10%,X7R,0402)MUR'                         | 'CHIP0402'     | ''          | ''   | '20180430'
 '0.22UF'   | '25V'   | '10%'     | 'C0402'     | 'EMPTY'   | 'CH4224K1B03'(!)   = 'End of Design' | 'Comp-Approve'     | ''       | 'CH4224K1B03'     |'C0402'| '(C0402-0201)'                                                       | 'NA'       | '25V'         | '10%'    | 'IO'       | 'CAP CHIP 0.22UF 25V(10%,X7R,0402)MUR'                         | 'CHIP0402'     | ''          | ''   | '20180430'
 '68PF'     | '50V'   | '5%'      | 'C0402'     | 'C0G'     | 'CH0686J0B11'(!)   = ''              | ''                 | ''       | 'CH0686J0B11'     |'C0402'| '(C0402-0201)'                                                       | '68PF'     | '50V'         | '5%'     | 'DISCRETE' | 'CAP CHIP 68P 50V(+-5%,C0G,0402)MUR'                           | 'CHIP0402'     | ''          | ''   | '20171026'
 '68PF'     | '50V'   | '5%'      | 'C0402'     | 'EMPTY'   | 'CH0686J0B11'(!)   = ''              | ''                 | ''       | 'CH0686J0B11'     |'C0402'| '(C0402-0201)'                                                       | 'NA'       | '50V'         | '5%'     | 'IO'       | 'CAP CHIP 68P 50V(+-5%,C0G,0402)MUR'                           | 'CHIP0402'     | ''          | ''   | '20171026'
 '1000PF'   | '100V'  | '5%'      | 'C1206'     | 'NPO'     | 'CH2108J0200'(!)   = ''              | ''                 | ''       | 'CH2108J0200'     |'C1206XC'| '(SMC1206AW)'                                                        | '1000PF'   | '100V'        | '5%'     | 'DISCRETE' | 'CAP CHIP 1000PF 100V(+-5%,NPO,1206)'                          | 'CHIP1206'     | ''          | ''   | '20180516'
 '1000PF'   | '100V'  | '5%'      | 'C1206'     | 'EMPTY'   | 'CH2108J0200'(!)   = ''              | ''                 | ''       | 'CH2108J0200'     |'C1206XC'| '(SMC1206AW)'                                                        | 'NA'       | '100V'        | '5%'     | 'IO'       | 'CAP CHIP 1000PF 100V(+-5%,NPO,1206)'                          | 'CHIP1206'     | ''          | ''   | '20180516'
 '1000PF'   | '100V'  | '10%'     | 'C0805'     | 'C0G'     | 'CH2108K0A00'(!)   = ''              | ''                 | ''       | 'CH2108K0A00'     |'C0805_H43'| '(SMC0805AW)'                                                        | '1000PF'   | '100V'        | '10%'    | 'DISCRETE' | 'CAP CHIP 1000PF 100V(+-10%,C0G,0805)KEM'                      | 'CHIP0805'     | ''          | ''   | '20180522'
 '1000PF'   | '100V'  | '10%'     | 'C0805'     | 'EMPTY'   | 'CH2108K0A00'(!)   = ''              | ''                 | ''       | 'CH2108K0A00'     |'C0805_H43'| '(SMC0805AW)'                                                        | 'NA'       | '100V'        | '10%'    | 'IO'       | 'CAP CHIP 1000PF 100V(+-10%,C0G,0805)KEM'                      | 'CHIP0805'     | ''          | ''   | '20180522'
 '1000PF'   | '100V'  | '10%'     | 'C0805'     | 'X7R'     | 'CH2108K1A00'(!)   = ''              | ''                 | ''       | 'CH2108K1A00'     |'C0805'| '(SMC0805AW)'                                                        | '1000PF'   | '100V'        | '10%'    | 'DISCRETE' | 'CAP CHIP 1000PF 100V(+-10%,X7R,0805)YGO'                      | 'CHIP0805'     | ''          | ''   | '20180522'
 '1000PF'   | '100V'  | '10%'     | 'C0805'     | 'EMPTY'   | 'CH2108K1A00'(!)   = ''              | ''                 | ''       | 'CH2108K1A00'     |'C0805'| '(SMC0805AW)'                                                        | 'NA'       | '100V'        | '10%'    | 'IO'       | 'CAP CHIP 1000PF 100V(+-10%,X7R,0805)YGO'                      | 'CHIP0805'     | ''          | ''   | '20180522'
 '1000PF'   | '100V'  | '1%'      | 'C0805'     | 'NPO'     | 'CH2108F0A00'(!)   = ''              | ''                 | ''       | 'CH2108F0A00'     |'C0805'| '(SMC0805AW)'                                                        | '1000PF'   | '100V'        | '1%'     | 'DISCRETE' | 'CAP CHIP 1000PF 100V(+-1%,NPO,0805)YGO'                       | 'CHIP0805'     | ''          | ''   | '20180523'
 '1000PF'   | '100V'  | '1%'      | 'C0805'     | 'EMPTY'   | 'CH2108F0A00'(!)   = ''              | ''                 | ''       | 'CH2108F0A00'     |'C0805'| '(SMC0805AW)'                                                        | 'NA'       | '100V'        | '1%'     | 'IO'       | 'CAP CHIP 1000PF 100V(+-1%,NPO,0805)YGO'                       | 'CHIP0805'     | ''          | ''   | '20180523'
 '5.6PF'    | '50V'   | '0.1PF'   | 'C0402'     | 'NP0'     | 'CH-566B0100'(!)   = ''              | ''                 | ''       | 'CH-566B0100'     |'C0402'| '(C0402-0201)'                                                       | '5.6PF'    | '50V'         | '0.1PF'  | 'DISCRETE' | 'CAP CHIP 5.6PF 50V(+-0.1PF,NP0,0402)'                         | 'CHIP0402'     | ''          | ''   | '20180528'
 '5.6PF'    | '50V'   | '0.1PF'   | 'C0402'     | 'EMPTY'   | 'CH-566B0100'(!)   = ''              | ''                 | ''       | 'CH-566B0100'     |'C0402'| '(C0402-0201)'                                                       | 'NA'       | '50V'         | '0.1PF'  | 'IO'       | 'CAP CHIP 5.6PF 50V(+-0.1PF,NP0,0402)'                         | 'CHIP0402'     | ''          | ''   | '20180528'
 '4.7UF'    | '16V'   | '10%'     | 'C0603'     | 'X6S'     | 'CH5473KE902'(!)   = ''              | ''                 | ''       | 'CH5473KE902'     |'C0603_H40'| '(SMC0603AW)'                                                        | '4.7UF'    | '16V'         | '10%'    | 'DISCRETE' | 'CAP CHIP 4.7UF 16V(+-10%,X6S,0603)'                           | 'CHIP0603'     | ''          | ''   | '20180627'
 '4.7UF'    | '16V'   | '10%'     | 'C0603'     | 'EMPTY'   | 'CH5473KE902'(!)   = ''              | ''                 | ''       | 'CH5473KE902'     |'C0603_H40'| '(SMC0603AW)'                                                        | 'NA'       | '16V'         | '10%'    | 'IO'       | 'CAP CHIP 4.7UF 16V(+-10%,X6S,0603)'                           | 'CHIP0603'     | ''          | ''   | '20180627'
 '10UF'     | '16V'   | '10%'     | 'C0805'     | 'X6S'     | 'CH6103KEA00'(!)   = ''              | ''                 | ''       | 'CH6103KEA00'     |'C0805_H57'| '(SMC0805AW)'                                                        | '10UF'     | '16V'         | '10%'    | 'DISCRETE' | 'CAP CHIP 10UF 16V(+-10%,X6S,0805)'                            | 'CHIP0805'     | ''          | ''   | '20180706'
 '10UF'     | '16V'   | '10%'     | 'C0805'     | 'EMPTY'   | 'CH6103KEA00'(!)   = ''              | ''                 | ''       | 'CH6103KEA00'     |'C0805_H57'| '(SMC0805AW)'                                                        | 'NA'       | '16V'         | '10%'    | 'IO'       | 'CAP CHIP 10UF 16V(+-10%,X6S,0805)'                            | 'CHIP0805'     | ''          | ''   | '20180706'
 '1NF'      | '50V'   | '10%'     | 'C0402'     | 'X7R'     | 'CH2106K1B23'(!)   = ''              | ''                 | ''       | 'CH2106K1B23'     |'C0402'| '(C0402-0201)'                                                       | '1NF'      | '50V'         | '10%'    | 'DISCRETE' | 'CAP CHIP 1N 50V(+-10%,X7R,0402)TAY'                           | 'CHIP0402'     | ''          | ''   | '20180710'
 '1NF'      | '50V'   | '10%'     | 'C0402'     | 'EMPTY'   | 'CH2106K1B23'(!)   = ''              | ''                 | ''       | 'CH2106K1B23'     |'C0402'| '(C0402-0201)'                                                       | 'NA'       | '50V'         | '10%'    | 'IO'       | 'CAP CHIP 1N 50V(+-10%,X7R,0402)TAY'                           | 'CHIP0402'     | ''          | ''   | '20180710'
 '0.01UF'   | '16V'   | '10%'     | 'C0402'     | 'X7R'     | 'CH3103K1B15'(!)   = 'End of Design' | 'Comp-Approve'     | ''       | 'CH3103K1B15'     |'C0402'| '(C0402_OCTAGON,C0402_SMDC25_SM30,C0402-0201)'                       | '0.01UF'   | '16V'         | '10%'    | 'DISCRETE' | 'CAP CHIP 0.01U 16V(10%,X7R,0402)'                             | 'CHIP0402'     | ''          | ''   | '20150911'
 '0.01UF'   | '16V'   | '10%'     | 'C0402'     | 'EMPTY'   | 'CH3103K1B15'(!)   = 'End of Design' | 'Comp-Approve'     | ''       | 'CH3103K1B15'     |'C0402'| '(C0402_OCTAGON,C0402_SMDC25_SM30,C0402-0201)'                       | 'NA'       | '16V'         | '10%'    | 'IO'       | 'CAP CHIP 0.01U 16V(10%,X7R,0402)'                             | 'CHIP0402'     | ''          | ''   | '20150911'
 '0.1UF'    | '100V'  | '10%'     | 'C0805'     | 'X7R'     | 'CH4108K1A06'(!)   = ''              | ''                 | ''       | 'CH4108K1A06'     |'C0805_H43'| '(SMC0805AW)'                                                        | '0.1UF'    | '100V'        | '10%'    | 'DISCRETE' | 'CAP CHIP 0.1UF 100V(+-10%,X7R,0805)WTC'                       | 'CHIP0805'     | ''          | ''   | '20180720'
 '0.1UF'    | '100V'  | '10%'     | 'C0805'     | 'EMPTY'   | 'CH4108K1A06'(!)   = ''              | ''                 | ''       | 'CH4108K1A06'     |'C0805_H43'| '(SMC0805AW)'                                                        | 'NA'       | '100V'        | '10%'    | 'IO'       | 'CAP CHIP 0.1UF 100V(+-10%,X7R,0805)WTC'                       | 'CHIP0805'     | ''          | ''   | '20180720'
 '0.1UF'    | '100V'  | '10%'     | 'C0805'     | 'X7R'     | 'CH4108K1A05'(!)   = ''              | ''                 | ''       | 'CH4108K1A05'     |'C0805_H57'| '(SMC0805AW)'                                                        | '0.1UF'    | '100V'        | '10%'    | 'DISCRETE' | 'CAP CHIP 0.1UF 100V(+-10%,X7R,0805)YGO'                       | 'CHIP0805'     | ''          | ''   | '20180723'
 '0.1UF'    | '100V'  | '10%'     | 'C0805'     | 'EMPTY'   | 'CH4108K1A05'(!)   = ''              | ''                 | ''       | 'CH4108K1A05'     |'C0805_H57'| '(SMC0805AW)'                                                        | 'NA'       | '100V'        | '10%'    | 'IO'       | 'CAP CHIP 0.1UF 100V(+-10%,X7R,0805)YGO'                       | 'CHIP0805'     | ''          | ''   | '20180723'
 '0.01UF'   | '1KV'   | '10%'     | 'C1206'     | 'X7R'     | 'CH310FK1204'(!)   = ''              | ''                 | ''       | 'CH310FK1204'     |'C1206_H66'| '(SMC1206AW)'                                                        | '0.01UF'   | '1KV'         | '10%'    | 'DISCRETE' | 'CAP CHIP 0.01U 1KV(+-10%,X7R,1206)YGO'                        | 'CHIP1206'     | ''          | ''   | '20180724'
 '0.01UF'   | '1KV'   | '10%'     | 'C1206'     | 'EMPTY'   | 'CH310FK1204'(!)   = ''              | ''                 | ''       | 'CH310FK1204'     |'C1206_H66'| '(SMC1206AW)'                                                        | 'NA'       | '1KV'         | '10%'    | 'IO'       | 'CAP CHIP 0.01U 1KV(+-10%,X7R,1206)YGO'                        | 'CHIP1206'     | ''          | ''   | '20180724'
 '0.1UF'    | '100V'  | '10%'     | 'C1206'     | 'X7R'     | 'CH4108K1208'(!)   = ''              | ''                 | ''       | 'CH4108K1208'     |'C1206_H76'| '(SMC1206AW)'                                                        | '0.1UF'    | '100V'        | '10%'    | 'DISCRETE' | 'CAP CHIP 0.1UF 100V(+-10%,X7R,1206)TAY'                       | 'CHIP1206'     | ''          | ''   | '20180731'
 '0.1UF'    | '100V'  | '10%'     | 'C1206'     | 'EMPTY'   | 'CH4108K1208'(!)   = ''              | ''                 | ''       | 'CH4108K1208'     |'C1206_H76'| '(SMC1206AW)'                                                        | 'NA'       | '100V'        | '10%'    | 'IO'       | 'CAP CHIP 0.1UF 100V(+-10%,X7R,1206)TAY'                       | 'CHIP1206'     | ''          | ''   | '20180731'
 '1U'       | '100V'  | '10%'     | 'C1206'     | 'X7R'     | 'CH5108K1204'(!)   = ''              | ''                 | ''       | 'CH5108K1204'     |'C1206_H76'| '(SMC1206AW)'                                                        | '1U'       | '100V'        | '10%'    | 'DISCRETE' | 'CAP CHIP 1U 100V(10%,X7R,1206)SAM'                            | 'CHIP1206'     | ''          | ''   | '20180801'
 '1U'       | '100V'  | '10%'     | 'C1206'     | 'EMPTY'   | 'CH5108K1204'(!)   = ''              | ''                 | ''       | 'CH5108K1204'     |'C1206_H76'| '(SMC1206AW)'                                                        | 'NA'       | '100V'        | '10%'    | 'IO'       | 'CAP CHIP 1U 100V(10%,X7R,1206)SAM'                            | 'CHIP1206'     | ''          | ''   | '20180801'
 '4.7U'     | '100V'  | '10%'     | 'C1206'     | 'X7S'     | 'CH5478K6200'(!)   = ''              | ''                 | ''       | 'CH5478K6200'     |'C1206XB'| '(SMC1206AW)'                                                        | '4.7U'     | '100V'        | '10%'    | 'DISCRETE' | 'CAP CHIP 4.7U 100V(10%,X7S,1206)MUR'                          | 'CHIP1206'     | ''          | ''   | '20180803'
 '4.7U'     | '100V'  | '10%'     | 'C1206'     | 'EMPTY'   | 'CH5478K6200'(!)   = ''              | ''                 | ''       | 'CH5478K6200'     |'C1206XB'| '(SMC1206AW)'                                                        | 'NA'       | '100V'        | '10%'    | 'IO'       | 'CAP CHIP 4.7U 100V(10%,X7S,1206)MUR'                          | 'CHIP1206'     | ''          | ''   | '20180803'
 '4700PF'   | '25V'   | '10%'     | 'C0402'     | 'X7R'     | 'CH2474K1B18'(!)   = ''              | ''                 | ''       | 'CH2474K1B18'     |'C0402'| '(C0402-0201)'                                                       | '4700PF'   | '25V'         | '10%'    | 'DISCRETE' | 'CAP CHIP 4700P 25V(+-10%,X7R,0402)WTC'                        | 'CHIP0402'     | ''          | ''   | '20180904'
 '4700PF'   | '25V'   | '10%'     | 'C0402'     | 'EMPTY'   | 'CH2474K1B18'(!)   = ''              | ''                 | ''       | 'CH2474K1B18'     |'C0402'| '(C0402-0201)'                                                       | 'NA'       | '25V'         | '10%'    | 'IO'       | 'CAP CHIP 4700P 25V(+-10%,X7R,0402)WTC'                        | 'CHIP0402'     | ''          | ''   | '20180904'
 '0.022UF'  | '25V'   | '10%'     | 'C0402'     | 'X7R'     | 'CH3224K1B09'(!)   = ''              | ''                 | ''       | 'CH3224K1B09'     |'C0402'| '(C0402-0201)'                                                       | '0.022UF'  | '25V'         | '10%'    | 'DISCRETE' | 'CAP CHIP 0.022U 25V(+-10%,X7R,0402)WTC'                       | 'CHIP0402'     | ''          | ''   | '20180904'
 '0.022UF'  | '25V'   | '10%'     | 'C0402'     | 'EMPTY'   | 'CH3224K1B09'(!)   = ''              | ''                 | ''       | 'CH3224K1B09'     |'C0402'| '(C0402-0201)'                                                       | 'NA'       | '25V'         | '10%'    | 'IO'       | 'CAP CHIP 0.022U 25V(+-10%,X7R,0402)WTC'                       | 'CHIP0402'     | ''          | ''   | '20180904'
 '0.047UF'  | '50V'   | '10%'     | 'C0402'     | 'X7R'     | 'CH3476K1B04'(!)   = ''              | ''                 | ''       | 'CH3476K1B04'     |'C0402_H28'| '(C0402-0201_H28)'                                                   | '0.047UF'  | '50V'         | '10%'    | 'DISCRETE' | 'CAP CHIP 0.047U 50V(+-10%,X7R,0402)WTC'                       | 'CHIP0402'     | ''          | ''   | '20180904'
 '0.047UF'  | '50V'   | '10%'     | 'C0402'     | 'EMPTY'   | 'CH3476K1B04'(!)   = ''              | ''                 | ''       | 'CH3476K1B04'     |'C0402_H28'| '(C0402-0201_H28)'                                                   | 'NA'       | '50V'         | '10%'    | 'IO'       | 'CAP CHIP 0.047U 50V(+-10%,X7R,0402)WTC'                       | 'CHIP0402'     | ''          | ''   | '20180904'
 '0.039UF'  | '50V'   | '10%'     | 'C0603'     | 'X7R'     | 'CH3396K1904'(!)   = ''              | ''                 | ''       | 'CH3396K1904'     |'C0603'| '(SMC0603AW)'                                                        | '0.039UF'  | '50V'         | '10%'    | 'DISCRETE' | 'CAP CHIP 0.039U 50V(+-10%,X7R,0603)WTC'                       | 'CHIP0603'     | ''          | ''   | '20180904'
 '0.039UF'  | '50V'   | '10%'     | 'C0603'     | 'EMPTY'   | 'CH3396K1904'(!)   = ''              | ''                 | ''       | 'CH3396K1904'     |'C0603'| '(SMC0603AW)'                                                        | 'NA'       | '50V'         | '10%'    | 'IO'       | 'CAP CHIP 0.039U 50V(+-10%,X7R,0603)WTC'                       | 'CHIP0603'     | ''          | ''   | '20180904'
 '0.68UF'   | '16V'   | '10%'     | 'C0603'     | 'X7R'     | 'CH4683K1902'(!)   = ''              | ''                 | ''       | 'CH4683K1902'     |'C0603'| '(SMC0603AW)'                                                        | '0.68UF'   | '16V'         | '10%'    | 'DISCRETE' | 'CAP CHIP 0.68U 16V(+-10%,X7R,0603)SAM'                        | 'CHIP0603'     | ''          | ''   | '20160810'
 '0.68UF'   | '16V'   | '10%'     | 'C0603'     | 'EMPTY'   | 'CH4683K1902'(!)   = ''              | ''                 | ''       | 'CH4683K1902'     |'C0603'| '(SMC0603AW)'                                                        | 'NA'       | '16V'         | '10%'    | 'IO'       | 'CAP CHIP 0.68U 16V(+-10%,X7R,0603)SAM'                        | 'CHIP0603'     | ''          | ''   | '20160810'
 '4700PF'   | '25V'   | '10%'     | 'C0402'     | 'X7R'     | 'CH2474K1B12'(!)   = ''              | ''                 | ''       | 'CH2474K1B12'     |'C0402'| '(C0402-0201)'                                                       | '4700PF'   | '25V'         | '10%'    | 'DISCRETE' | 'CAP CHIP 4700P 25V(+-10%,X7R,0402)SAM'                        | 'CHIP0402'     | ''          | ''   | '20180917'
 '4700PF'   | '25V'   | '10%'     | 'C0402'     | 'EMPTY'   | 'CH2474K1B12'(!)   = ''              | ''                 | ''       | 'CH2474K1B12'     |'C0402'| '(C0402-0201)'                                                       | 'NA'       | '25V'         | '10%'    | 'IO'       | 'CAP CHIP 4700P 25V(+-10%,X7R,0402)SAM'                        | 'CHIP0402'     | ''          | ''   | '20180917'
 '470NF'    | '50V'   | '5%'      | 'C1812'     | 'U2J'     | 'CH4476JF400'(!)   = 'End of Design' | 'Comp-Release Qty' | ''       | 'CH4476JF400'     |'C1812XB'| '(SMC0603AW)'                                                        | '470NF'    | '50V'         | '5%'     | 'DISCRETE' | 'CAP CHIP 470NF 50V(+-5%,U2J,1812)'                            | 'CHIP1812'     | ''          | ''   | '20180927'
 '470NF'    | '50V'   | '5%'      | 'C1812'     | 'EMPTY'   | 'CH4476JF400'(!)   = 'End of Design' | 'Comp-Release Qty' | ''       | 'CH4476JF400'     |'C1812XB'| '(SMC0603AW)'                                                        | 'NA'       | '50V'         | '5%'     | 'IO'       | 'CAP CHIP 470NF 50V(+-5%,U2J,1812)'                            | 'CHIP1812'     | ''          | ''   | '20180927'
 '470NF'    | '50V'   | '5%'      | 'C1812'     | 'U2J'     | 'CH4476JF401'(!)   = 'End of Design' | 'Comp-Approve'     | ''       | 'CH4476JF401'     |'C1812XB'| '(SMC0603AW)'                                                        | '470NF'    | '50V'         | '5%'     | 'DISCRETE' | 'CAP CHIP 470NF 50V(+-5%,U2J,1812)KEM'                         | 'CHIP1812'     | ''          | ''   | '20181008'
 '470NF'    | '50V'   | '5%'      | 'C1812'     | 'EMPTY'   | 'CH4476JF401'(!)   = 'End of Design' | 'Comp-Approve'     | ''       | 'CH4476JF401'     |'C1812XB'| '(SMC0603AW)'                                                        | 'NA'       | '50V'         | '5%'     | 'IO'       | 'CAP CHIP 470NF 50V(+-5%,U2J,1812)KEM'                         | 'CHIP1812'     | ''          | ''   | '20181008'
 '22UF'     | '16V'   | '20%'     | 'C0805'     | 'X5R'     | 'CH6223M9A00'(!)   = ''              | ''                 | ''       | 'CH6223M9A00'     |'C0805_H57'| '(SMC0805AW)'                                                        | '22UF'     | '16V'         | '20%'    | 'DISCRETE' | 'CAP CHIP 22UF 16V( +-20% ,X5R,0805)'                          | 'CHIP0805'     | ''          | ''   | '20181016'
 '22UF'     | '16V'   | '20%'     | 'C0805'     | 'EMPTY'   | 'CH6223M9A00'(!)   = ''              | ''                 | ''       | 'CH6223M9A00'     |'C0805_H57'| '(SMC0805AW)'                                                        | 'NA'       | '16V'         | '20%'    | 'IO'       | 'CAP CHIP 22UF 16V( +-20% ,X5R,0805)'                          | 'CHIP0805'     | ''          | ''   | '20181016'
 '2.2UF'    | '25V'   | '10%'     | 'C0603'     | 'X6S'     | 'CH5224KE900'(!)   = ''              | ''                 | ''       | 'CH5224KE900'     |'C0603_H40'| '(SMC0603AW)'                                                        | '2.2UF'    | '25V'         | '10%'    | 'DISCRETE' | 'CAP CHIP 2.2U 25V(+-10%,X6S,0603)MUR'                         | 'CHIP0603'     | ''          | ''   | '20181017'
 '2.2UF'    | '25V'   | '10%'     | 'C0603'     | 'EMPTY'   | 'CH5224KE900'(!)   = ''              | ''                 | ''       | 'CH5224KE900'     |'C0603_H40'| '(SMC0603AW)'                                                        | 'NA'       | '25V'         | '10%'    | 'IO'       | 'CAP CHIP 2.2U 25V(+-10%,X6S,0603)MUR'                         | 'CHIP0603'     | ''          | ''   | '20181017'
 '1UF'      | '100V'  | '10%'     | 'C0805'     | 'X7S'     | 'CH5108K6A01'(!)   = ''              | ''                 | ''       | 'CH5108K6A01'     |'C0805_H57'| '(SMC0805AW)'                                                        | '1UF'      | '100V'        | '10%'    | 'DISCRETE' | 'CAP CHIP 1UF 100V(+-10%,X7S,0805)'                            | 'CHIP0805'     | ''          | ''   | '20181018'
 '1UF'      | '100V'  | '10%'     | 'C0805'     | 'EMPTY'   | 'CH5108K6A01'(!)   = ''              | ''                 | ''       | 'CH5108K6A01'     |'C0805_H57'| '(SMC0805AW)'                                                        | 'NA'       | '100V'        | '10%'    | 'IO'       | 'CAP CHIP 1UF 100V(+-10%,X7S,0805)'                            | 'CHIP0805'     | ''          | ''   | '20181018'
 '0.1UF'    | '16V'   | '10%'     | 'C0201'     | 'X5R'     | 'CH4103K9E01'(!)   = ''              | ''                 | ''       | 'CH4103K9E01'     |'C0201'| '(SMC0201AW)'                                                        | '0.1UF'    | '16V'         | '10%'    | 'DISCRETE' | 'CAP CHIP 0.1U 16V(+-10%,X5R,0201)'                            | 'CHIP0201'     | ''          | ''   | '20181018'
 '0.1UF'    | '16V'   | '10%'     | 'C0201'     | 'EMPTY'   | 'CH4103K9E01'(!)   = ''              | ''                 | ''       | 'CH4103K9E01'     |'C0201'| '(SMC0201AW)'                                                        | 'NA'       | '16V'         | '10%'    | 'IO'       | 'CAP CHIP 0.1U 16V(+-10%,X5R,0201)'                            | 'CHIP0201'     | ''          | ''   | '20181018'
 '0.033UF'  | '100V'  | '10%'     | 'C0603'     | 'X7R'     | 'CH3338K1900'(!)   = ''              | ''                 | ''       | 'CH3338K1900'     |'C0603'| '(SMC0603AW)'                                                        | '0.033UF'  | '100V'        | '10%'    | 'DISCRETE' | 'CAP CHIP 0.033U 100V(+-10%,X7R,0603)'                         | 'CHIP0603'     | ''          | ''   | '20181018'
 '0.033UF'  | '100V'  | '10%'     | 'C0603'     | 'EMPTY'   | 'CH3338K1900'(!)   = ''              | ''                 | ''       | 'CH3338K1900'     |'C0603'| '(SMC0603AW)'                                                        | 'NA'       | '100V'        | '10%'    | 'IO'       | 'CAP CHIP 0.033U 100V(+-10%,X7R,0603)'                         | 'CHIP0603'     | ''          | ''   | '20181018'
 '0.1UF'    | '100V'  | '10%'     | 'C0603'     | 'X7R'     | 'CH4108K1901'(!)   = 'End of Design' | 'Comp-Approve'     | ''       | 'CH4108K1901'     |'C0603'| '(SMC0603AW)'                                                        | '0.1UF'    | '100V'        | '10%'    | 'DISCRETE' | 'CAP CHIP 0.1U 100V(+-10%,X7R,0603)'                           | 'CHIP0603'     | ''          | ''   | '20181018'
 '0.1UF'    | '100V'  | '10%'     | 'C0603'     | 'EMPTY'   | 'CH4108K1901'(!)   = 'End of Design' | 'Comp-Approve'     | ''       | 'CH4108K1901'     |'C0603'| '(SMC0603AW)'                                                        | 'NA'       | '100V'        | '10%'    | 'IO'       | 'CAP CHIP 0.1U 100V(+-10%,X7R,0603)'                           | 'CHIP0603'     | ''          | ''   | '20181018'
 '0.68UF'   | '6.3V'  | '10%'     | 'C0402'     | 'X5R'     | 'CH4681K9B00'(!)   = 'End of Design' | 'Comp-Release Qty' | ''       | 'CH4681K9B00'     |'C0402'| '(C0402-0201)'                                                       | '0.68UF'   | '6.3V'        | '10%'    | 'DISCRETE' | 'CAP CHIP 0.68UF 6.3V(+-10%,X5R,0402)'                         | 'CHIP0402'     | ''          | ''   | '20181026'
 '0.68UF'   | '6.3V'  | '10%'     | 'C0402'     | 'EMPTY'   | 'CH4681K9B00'(!)   = 'End of Design' | 'Comp-Release Qty' | ''       | 'CH4681K9B00'     |'C0402'| '(C0402-0201)'                                                       | 'NA'       | '6.3V'        | '10%'    | 'IO'       | 'CAP CHIP 0.68UF 6.3V(+-10%,X5R,0402)'                         | 'CHIP0402'     | ''          | ''   | '20181026'
 '2.7PF'    | '50V'   | '0.1P'    | 'C0201'     | 'C0G'     | 'CH-276B0E00'(!)   = ''              | ''                 | ''       | 'CH-276B0E00'     |'C0201'| '(SMC0201AW)'                                                        | '2.7PF'    | '50V'         | '0.1P'   | 'DISCRETE' | 'CAP CHIP 2.7P 50V(+-0.1P,C0G,0201)'                           | 'CHIP0201'     | ''          | ''   | '20181026'
 '2.7PF'    | '50V'   | '0.1P'    | 'C0201'     | 'EMPTY'   | 'CH-276B0E00'(!)   = ''              | ''                 | ''       | 'CH-276B0E00'     |'C0201'| '(SMC0201AW)'                                                        | 'NA'       | '50V'         | '0.1P'   | 'IO'       | 'CAP CHIP 2.7P 50V(+-0.1P,C0G,0201)'                           | 'CHIP0201'     | ''          | ''   | '20181026'
 '2.2U'     | '6.3V'  | '20%'     | 'C0402'     | 'X6S'     | 'CH5221MEB03'(!)   = ''              | ''                 | ''       | 'CH5221MEB03'     |'C0402'| '(C0402-0201)'                                                       | '2.2U'     | '6.3V'        | '20%'    | 'DISCRETE' | 'CAP CHIP 2.2U 6.3V(+-20%,X6S,0402)MUR'                        | 'CHIP0402'     | ''          | ''   | '20181122'
 '2.2U'     | '6.3V'  | '20%'     | 'C0402'     | 'EMPTY'   | 'CH5221MEB03'(!)   = ''              | ''                 | ''       | 'CH5221MEB03'     |'C0402'| '(C0402-0201)'                                                       | 'NA'       | '6.3V'        | '20%'    | 'IO'       | 'CAP CHIP 2.2U 6.3V(+-20%,X6S,0402)MUR'                        | 'CHIP0402'     | ''          | ''   | '20181122'
 '2200PF'   | '50V'   | '10%'     | 'C0402'     | 'X7R'     | 'CH2226K1B10'(!)   = ''              | ''                 | ''       | 'CH2226K1B10'     |'C0402_H28'| '(C0402-0201_H28)'                                                   | '2200PF'   | '50V'         | '10%'    | 'DISCRETE' | 'CAP CHIP 2200P 50V(+-10%,X7R,0402)WTC'                        | 'CHIP0402'     | ''          | ''   | '20181126'
 '2200PF'   | '50V'   | '10%'     | 'C0402'     | 'EMPTY'   | 'CH2226K1B10'(!)   = ''              | ''                 | ''       | 'CH2226K1B10'     |'C0402_H28'| '(C0402-0201_H28)'                                                   | 'NA'       | '50V'         | '10%'    | 'IO'       | 'CAP CHIP 2200P 50V(+-10%,X7R,0402)WTC'                        | 'CHIP0402'     | ''          | ''   | '20181126'
 '10UF'     | '16V'   | '10%'     | 'C0805'     | 'X6S'     | 'CH6103KEA01'(!)   = ''              | ''                 | ''       | 'CH6103KEA01'     |'C0805_H57'| '(SMC0805AW)'                                                        | '10UF'     | '16V'         | '10%'    | 'DISCRETE' | 'CAP CHIP 10UF 16V(+-10%,X6S,0805)MUR'                         | 'CHIP0805'     | ''          | ''   | '20181128'
 '10UF'     | '16V'   | '10%'     | 'C0805'     | 'EMPTY'   | 'CH6103KEA01'(!)   = ''              | ''                 | ''       | 'CH6103KEA01'     |'C0805_H57'| '(SMC0805AW)'                                                        | 'NA'       | '16V'         | '10%'    | 'IO'       | 'CAP CHIP 10UF 16V(+-10%,X6S,0805)MUR'                         | 'CHIP0805'     | ''          | ''   | '20181128'
 '3300P'    | '50V'   | '10%'     | 'C0402'     | 'X7R'     | 'CH2336K1B19'(!)   = ''              | ''                 | ''       | 'CH2336K1B19'     |'C0402'| '(C0402-0201)'                                                       | '3300P'    | '50V'         | '10%'    | 'DISCRETE' | 'CAP CHIP 3300P 50V(+-10%,X7R,0402)WTC'                        | 'CHIP0402'     | ''          | ''   | '20181130'
 '3300P'    | '50V'   | '10%'     | 'C0402'     | 'EMPTY'   | 'CH2336K1B19'(!)   = ''              | ''                 | ''       | 'CH2336K1B19'     |'C0402'| '(C0402-0201)'                                                       | 'NA'       | '50V'         | '10%'    | 'IO'       | 'CAP CHIP 3300P 50V(+-10%,X7R,0402)WTC'                        | 'CHIP0402'     | ''          | ''   | '20181130'
 '1PF'      | '25V'   | '0.1%'    | 'C0201'     | 'C0G'     | 'CH-104B0E01'(!)   = ''              | ''                 | ''       | 'CH-104B0E01'     |'C0201'| '(SMC0201AW)'                                                        | '1PF'      | '25V'         | '0.1%'   | 'DISCRETE' | 'CAP CHIP 1PF 25V(+-0.1PF,C0G,0201)'                           | 'CHIP0201'     | ''          | ''   | '20190121'
 '1PF'      | '25V'   | '0.1%'    | 'C0201'     | 'EMPTY'   | 'CH-104B0E01'(!)   = ''              | ''                 | ''       | 'CH-104B0E01'     |'C0201'| '(SMC0201AW)'                                                        | 'NA'       | '25V'         | '0.1%'   | 'IO'       | 'CAP CHIP 1PF 25V(+-0.1PF,C0G,0201)'                           | 'CHIP0201'     | ''          | ''   | '20190121'
 '330P'     | '50V'   | '+-2%'    | 'C0402'     | 'NPO'     | 'CH1336G0B00'(!)   = ''              | ''                 | ''       | 'CH1336G0B00'     |'C0402'| '(C0402-0201)'                                                       | '330P'     | '50V'         | '+-2%'   | 'DISCRETE' | 'CAP CHIP 330P 50V(+-2%,NPO,0402)'                             | 'CHIP0402'     | ''          | ''   | '20190124'
 '330P'     | '50V'   | '+-2%'    | 'C0402'     | 'EMPTY'   | 'CH1336G0B00'(!)   = ''              | ''                 | ''       | 'CH1336G0B00'     |'C0402'| '(C0402-0201)'                                                       | 'NA'       | '50V'         | '+-2%'   | 'IO'       | 'CAP CHIP 330P 50V(+-2%,NPO,0402)'                             | 'CHIP0402'     | ''          | ''   | '20190124'
 '0.1U'     | '16V'   | '10%'     | 'C0402'     | 'X7R'     | 'CH4103K1B20'(!)   = ''              | ''                 | ''       | 'CH4103K1B20'     |'C0402'| '(C0402-0201)'                                                       | '0.1U'     | '16V'         | '10%'    | 'DISCRETE' | 'CAP CHIP 0.1U 16V(10%,X7R,0402)TAY'                           | 'CHIP0402'     | ''          | ''   | '20190124'
 '0.1U'     | '16V'   | '10%'     | 'C0402'     | 'EMPTY'   | 'CH4103K1B20'(!)   = ''              | ''                 | ''       | 'CH4103K1B20'     |'C0402'| '(C0402-0201)'                                                       | 'NA'       | '16V'         | '10%'    | 'IO'       | 'CAP CHIP 0.1U 16V(10%,X7R,0402)TAY'                           | 'CHIP0402'     | ''          | ''   | '20190124'
 '3300P'    | '50V'   | '+-10%'   | 'C0402'     | 'X7R'     | 'CH2336K1B10'(!)   = ''              | ''                 | ''       | 'CH2336K1B10'     |'C0402'| '(C0402-0201)'                                                       | '3300P'    | '50V'         | '+-10%'  | 'DISCRETE' | 'CAP CHIP 3300P 50V(+-10%,X7R,0402)SAM'                        | 'CHIP0402'     | ''          | ''   | '20190124'
 '3300P'    | '50V'   | '+-10%'   | 'C0402'     | 'EMPTY'   | 'CH2336K1B10'(!)   = ''              | ''                 | ''       | 'CH2336K1B10'     |'C0402'| '(C0402-0201)'                                                       | 'NA'       | '50V'         | '+-10%'  | 'IO'       | 'CAP CHIP 3300P 50V(+-10%,X7R,0402)SAM'                        | 'CHIP0402'     | ''          | ''   | '20190124'
 '330N'     | '250V'  | '+-10%'   | 'C1812'     | 'X7R'     | 'CH433CK1400'(!)   = ''              | ''                 | ''       | 'CH433CK1400'     |'C1812XC'| '(SMC1812AW)'                                                        | '330N'     | '250V'        | '+-10%'  | 'DISCRETE' | 'CAP CHIP 330N 250V(+-10%,X7R,1812)'                           | 'CHIP1812'     | ''          | ''   | '20190128'
 '330N'     | '250V'  | '+-10%'   | 'C1812'     | 'EMPTY'   | 'CH433CK1400'(!)   = ''              | ''                 | ''       | 'CH433CK1400'     |'C1812XC'| '(SMC1812AW)'                                                        | 'NA'       | '250V'        | '+-10%'  | 'IO'       | 'CAP CHIP 330N 250V(+-10%,X7R,1812)'                           | 'CHIP1812'     | ''          | ''   | '20190128'
 '0.22UF'   | '25V'   | '10%'     | 'C0402'     | 'X7R'     | 'CH4224K1B09'(!)   = ''              | ''                 | ''       | 'CH4224K1B09'     |'C0402'| '(C0402-0201)'                                                       | '0.22UF'   | '25V'         | '10%'    | 'DISCRETE' | 'CAP CHIP 0.22U 25V(+-10%,X7R,0402)TAY'                        | 'CHIP0402'     | ''          | ''   | '20190219'
 '0.22UF'   | '25V'   | '10%'     | 'C0402'     | 'EMPTY'   | 'CH4224K1B09'(!)   = ''              | ''                 | ''       | 'CH4224K1B09'     |'C0402'| '(C0402-0201)'                                                       | 'NA'       | '25V'         | '10%'    | 'IO'       | 'CAP CHIP 0.22U 25V(+-10%,X7R,0402)TAY'                        | 'CHIP0402'     | ''          | ''   | '20190219'
 '1UF'      | '50V'   | '10%'     | 'C0603'     | 'X7R'     | 'CH5106K1900'(!)   = ''              | ''                 | ''       | 'CH5106K1900'     |'C0603_H40'| '(SMC0603AW)'                                                        | '1UF'      | '50V'         | '10%'    | 'DISCRETE' | 'CAP CHIP 1U 50V(+-10%,X7R,0603)YGO'                           | 'CHIP0603'     | ''          | ''   | '20190401'
 '1UF'      | '50V'   | '10%'     | 'C0603'     | 'EMPTY'   | 'CH5106K1900'(!)   = ''              | ''                 | ''       | 'CH5106K1900'     |'C0603_H40'| '(SMC0603AW)'                                                        | 'NA'       | '50V'         | '10%'    | 'IO'       | 'CAP CHIP 1U 50V(+-10%,X7R,0603)YGO'                           | 'CHIP0603'     | ''          | ''   | '20190401'
 '4.7UF'    | '50V'   | '10%'     | 'C0805'     | 'X5R'     | 'CH5476K9A02'(!)   = ''              | ''                 | ''       | 'CH5476K9A02'     |'C0805_H57'| '(SMC0805AW)'                                                        | '4.7UF'    | '50V'         | '10%'    | 'DISCRETE' | 'CAP CHIP 4.7UF 50V(+-10%,X5R,0805)MUR'                        | 'CHIP0805'     | ''          | ''   | '20190401'
 '4.7UF'    | '50V'   | '10%'     | 'C0805'     | 'EMPTY'   | 'CH5476K9A02'(!)   = ''              | ''                 | ''       | 'CH5476K9A02'     |'C0805_H57'| '(SMC0805AW)'                                                        | 'NA'       | '50V'         | '10%'    | 'IO'       | 'CAP CHIP 4.7UF 50V(+-10%,X5R,0805)MUR'                        | 'CHIP0805'     | ''          | ''   | '20190401'
 '1UF'      | '50V'   | '10%'     | 'C0805'     | 'X7R'     | 'CH5106K1A05'(!)   = ''              | ''                 | ''       | 'CH5106K1A05'     |'C0805_H57'| '(SMC0805AW)'                                                        | '1UF'      | '50V'         | '10%'    | 'DISCRETE' | 'CAP CHIP 1U 50V(+-10%,X7R,0805)SAM'                           | 'CHIP0805'     | ''          | ''   | '20190412'
 '1UF'      | '50V'   | '10%'     | 'C0805'     | 'EMPTY'   | 'CH5106K1A05'(!)   = ''              | ''                 | ''       | 'CH5106K1A05'     |'C0805_H57'| '(SMC0805AW)'                                                        | 'NA'       | '50V'         | '10%'    | 'IO'       | 'CAP CHIP 1U 50V(+-10%,X7R,0805)SAM'                           | 'CHIP0805'     | ''          | ''   | '20190412'
 '220P'     | '50V'   | '5%'      | 'C0402'     | 'COG'     | 'CH1226J0B03'(!)   = ''              | ''                 | ''       | 'CH1226J0B03'     |'C0402'| '(C0402-0201)'                                                       | '220P'     | '50V'         | '5%'     | 'DISCRETE' | 'CAP CHIP 220P 50V(+-5%,COG,0402)MUR'                          | 'CHIP0402'     | ''          | ''   | '20190422'
 '220P'     | '50V'   | '5%'      | 'C0402'     | 'EMPTY'   | 'CH1226J0B03'(!)   = ''              | ''                 | ''       | 'CH1226J0B03'     |'C0402'| '(C0402-0201)'                                                       | 'NA'       | '50V'         | '5%'     | 'IO'       | 'CAP CHIP 220P 50V(+-5%,COG,0402)MUR'                          | 'CHIP0402'     | ''          | ''   | '20190422'
 '3.9P'     | '50V'   | '0.1P'    | 'C0402'     | 'NPO'     | 'CH-3916TB01'(!)   = ''              | ''                 | ''       | 'CH-3916TB01'     |'C0402'| '(C0402-0201)'                                                       | '3.9P'     | '50V'         | '0.1P'   | 'DISCRETE' | 'CAP CHIP 3.9P 50V(+-0.1P,NPO,0402)'                           | 'CHIP0402'     | ''          | ''   | '20190426'
 '3.9P'     | '50V'   | '0.1P'    | 'C0402'     | 'EMPTY'   | 'CH-3916TB01'(!)   = ''              | ''                 | ''       | 'CH-3916TB01'     |'C0402'| '(C0402-0201)'                                                       | 'NA'       | '50V'         | '0.1P'   | 'IO'       | 'CAP CHIP 3.9P 50V(+-0.1P,NPO,0402)'                           | 'CHIP0402'     | ''          | ''   | '20190426'
 '10PF'     | '50V'   | '2%'      | 'C0402'     | 'NPO'     | 'CH01006GB02'(!)   = ''              | ''                 | ''       | 'CH01006GB02'     |'C0402'| '(C0402-0201)'                                                       | '10PF'     | '50V'         | '2%'     | 'DISCRETE' | 'CAP CHIP 10P 50V(+-2%,NPO,0402)'                              | 'CHIP0402'     | ''          | ''   | '20190605'
 '10PF'     | '50V'   | '2%'      | 'C0402'     | 'EMPTY'   | 'CH01006GB02'(!)   = ''              | ''                 | ''       | 'CH01006GB02'     |'C0402'| '(C0402-0201)'                                                       | 'NA'       | '50V'         | '2%'     | 'IO'       | 'CAP CHIP 10P 50V(+-2%,NPO,0402)'                              | 'CHIP0402'     | ''          | ''   | '20190605'
 '47UF'     | '2.5V'  | '20%'     | 'C0603'     | 'X6S'     | 'CH647LME900'(!)   = 'End of Design' | 'Comp-Approve'     | ''       | 'CH647LME900'     |'C0603'| '(SMC0603AW)'                                                        | '47UF'     | '2.5V'        | '20%'    | 'DISCRETE' | 'CAP CHIP 47U 2.5V(+-20%,X6S,0603)MUR'                         | 'CHIP0603'     | ''          | ''   | '20190605'
 '47UF'     | '2.5V'  | '20%'     | 'C0603'     | 'EMPTY'   | 'CH647LME900'(!)   = 'End of Design' | 'Comp-Approve'     | ''       | 'CH647LME900'     |'C0603'| '(SMC0603AW)'                                                        | 'NA'       | '2.5V'        | '20%'    | 'IO'       | 'CAP CHIP 47U 2.5V(+-20%,X6S,0603)MUR'                         | 'CHIP0603'     | ''          | ''   | '20190605'
 '2.2PF'    | '50V'   | '0.1P'    | 'C0402'     | 'NPO'     | 'CH-2216TB02'(!)   = ''              | ''                 | ''       | 'CH-2216TB02'     |'C0402'| '(C0402-0201)'                                                       | '2.2PF'    | '50V'         | '0.1P'   | 'DISCRETE' | 'CAP CHIP 2.2P 50V (+-0.1P NPO 0402)'                          | 'CHIP0402'     | ''          | ''   | '20190605'
 '2.2PF'    | '50V'   | '0.1P'    | 'C0402'     | 'EMPTY'   | 'CH-2216TB02'(!)   = ''              | ''                 | ''       | 'CH-2216TB02'     |'C0402'| '(C0402-0201)'                                                       | 'NA'       | '50V'         | '0.1P'   | 'IO'       | 'CAP CHIP 2.2P 50V (+-0.1P NPO 0402)'                          | 'CHIP0402'     | ''          | ''   | '20190605'
 '22UF'     | '4V'    | '20%'     | 'C0805'     | 'X6S'     | 'CH622KMEA04'(!)   = ''              | ''                 | ''       | 'CH622KMEA04'     |'C0805_H57'| '(SMC0805AW)'                                                        | '22UF'     | '4V'          | '20%'    | 'DISCRETE' | 'CAP CHIP 22U 4V(+-20%,X6S,0805)SAM'                           | 'CHIP0805'     | ''          | ''   | '20190611'
 '22UF'     | '4V'    | '20%'     | 'C0805'     | 'EMPTY'   | 'CH622KMEA04'(!)   = ''              | ''                 | ''       | 'CH622KMEA04'     |'C0805_H57'| '(SMC0805AW)'                                                        | 'NA'       | '4V'          | '20%'    | 'IO'       | 'CAP CHIP 22U 4V(+-20%,X6S,0805)SAM'                           | 'CHIP0805'     | ''          | ''   | '20190611'
 '22UF'     | '16V'   | '20%'     | 'C0805'     | 'X6S'     | 'CH6223MEA03'(!)   = ''              | ''                 | ''       | 'CH6223MEA03'     |'C0805_H57'| '(SMC0805AW)'                                                        | '22UF'     | '16V'         | '20%'    | 'DISCRETE' | 'CAP CHIP 22U 16V(20%,X6S,0805)SAM'                            | 'CHIP0805'     | ''          | ''   | '20190611'
 '22UF'     | '16V'   | '20%'     | 'C0805'     | 'EMPTY'   | 'CH6223MEA03'(!)   = ''              | ''                 | ''       | 'CH6223MEA03'     |'C0805_H57'| '(SMC0805AW)'                                                        | 'NA'       | '16V'         | '20%'    | 'IO'       | 'CAP CHIP 22U 16V(20%,X6S,0805)SAM'                            | 'CHIP0805'     | ''          | ''   | '20190611'
 '3300PF'   | '50V'   | '5%'      | 'C0402'     | 'X7R'     | 'CH23306JB16'(!)   = ''              | ''                 | ''       | 'CH23306JB16'     |'C0402'| '(C0402-0201)'                                                       | '3300PF'   | '50V'         | '5%'     | 'DISCRETE' | 'CAP CHIP 3300P 50V(+-5%,X7R,0402)'                            | 'CHIP0402'     | ''          | ''   | '20190712'
 '3300PF'   | '50V'   | '5%'      | 'C0402'     | 'EMPTY'   | 'CH23306JB16'(!)   = ''              | ''                 | ''       | 'CH23306JB16'     |'C0402'| '(C0402-0201)'                                                       | 'NA'       | '50V'         | '5%'     | 'IO'       | 'CAP CHIP 3300P 50V(+-5%,X7R,0402)'                            | 'CHIP0402'     | ''          | ''   | '20190712'
 '4.7UF'    | '25V'   | '10%'     | 'C0603'     | 'X5R'     | 'CH5474K9901'(!)   = ''              | ''                 | ''       | 'CH5474K9901'     |'C0603_H40'| '(SMC0603AW)'                                                        | '4.7UF'    | '25V'         | '10%'    | 'DISCRETE' | 'CAP CHIP 4.7U 25V(+-10%,X5R,0603)'                            | 'CHIP0603'     | ''          | ''   | '20190730'
 '4.7UF'    | '25V'   | '10%'     | 'C0603'     | 'EMPTY'   | 'CH5474K9901'(!)   = ''              | ''                 | ''       | 'CH5474K9901'     |'C0603_H40'| '(SMC0603AW)'                                                        | 'NA'       | '25V'         | '10%'    | 'IO'       | 'CAP CHIP 4.7U 25V(+-10%,X5R,0603)'                            | 'CHIP0603'     | ''          | ''   | '20190730'
 '1UF'      | '25V'   | '10%'     | 'C0402'     | 'X5R'     | 'CH5104K9B01'(!)   = ''              | ''                 | ''       | 'CH5104K9B01'     |'C0402'| '(C0402-0201))'                                                      | '1UF'      | '25V'         | '10%'    | 'DISCRETE' | 'CAP CHIP 1UF 25V(+-10%,X5R,0402)'                             | 'CHIP0402'     | ''          | ''   | '20190731'
 '1UF'      | '25V'   | '10%'     | 'C0402'     | 'EMPTY'   | 'CH5104K9B01'(!)   = ''              | ''                 | ''       | 'CH5104K9B01'     |'C0402'| '(C0402-0201))'                                                      | 'NA'       | '25V'         | '10%'    | 'IO'       | 'CAP CHIP 1UF 25V(+-10%,X5R,0402)'                             | 'CHIP0402'     | ''          | ''   | '20190731'
 '4.7UF'    | '6.3V'  | '10%'     | 'C0402'     | 'X5R'     | 'CH5471K9B00'(!)   = ''              | ''                 | ''       | 'CH5471K9B00'     |'C0402_H28'| '(C0402-0201_H28)'                                                   | '4.7UF'    | '6.3V'        | '10%'    | 'DISCRETE' | 'CAP CHIP 4.7UF 6.3V(+-10%,X5R,0402)'                          | 'CHIP0402'     | ''          | ''   | '20190731'
 '4.7UF'    | '6.3V'  | '10%'     | 'C0402'     | 'EMPTY'   | 'CH5471K9B00'(!)   = ''              | ''                 | ''       | 'CH5471K9B00'     |'C0402_H28'| '(C0402-0201_H28)'                                                   | 'NA'       | '6.3V'        | '10%'    | 'IO'       | 'CAP CHIP 4.7UF 6.3V(+-10%,X5R,0402)'                          | 'CHIP0402'     | ''          | ''   | '20190731'
 '22UF'     | '6.3V'  | '20%'     | 'C0603'     | 'X6S'     | 'CH6221ME907'(!)   = ''              | ''                 | ''       | 'CH6221ME907'     |'C0603_H40'| '(SMC0603AW)'                                                        | '22UF'     | '6.3V'        | '20%'    | 'DISCRETE' | 'CAP CHIP 22U 6.3V(+-20%,X6S,0603)SAM'                         | 'CHIP0603'     | ''          | ''   | '20190807'
 '22UF'     | '6.3V'  | '20%'     | 'C0603'     | 'EMPTY'   | 'CH6221ME907'(!)   = ''              | ''                 | ''       | 'CH6221ME907'     |'C0603_H40'| '(SMC0603AW)'                                                        | 'NA'       | '6.3V'        | '20%'    | 'IO'       | 'CAP CHIP 22U 6.3V(+-20%,X6S,0603)SAM'                         | 'CHIP0603'     | ''          | ''   | '20190807'
 '2.2UF'    | '25V'   | '10%'     | 'C0402'     | 'X5R'     | 'CH5224K9B01'(!)   = ''              | ''                 | ''       | 'CH5224K9B01'     |'C0402_H28'| '(C0402-0201_H28)'                                                   | '2.2UF'    | '25V'         | '10%'    | 'DISCRETE' | 'CAP CHIP 2.2U 25V(+-10%,X5R,0402)'                            | 'CHIP0402'     | ''          | ''   | '20150729'
 '2.2UF'    | '25V'   | '10%'     | 'C0402'     | 'EMPTY'   | 'CH5224K9B01'(!)   = ''              | ''                 | ''       | 'CH5224K9B01'     |'C0402_H28'| '(C0402-0201_H28)'                                                   | 'NA'       | '25V'         | '10%'    | 'IO'       | 'CAP CHIP 2.2U 25V(+-10%,X5R,0402)'                            | 'CHIP0402'     | ''          | ''   | '20150729'
 '0.1UF'    | '100V'  | '10%'     | 'C0603'     | 'X7R'     | 'CH4108K1904'(!)   = ''              | ''                 | ''       | 'CH4108K1904'     |'C0603'| '(SMC0603AW)'                                                        | '0.1UF'    | '100V'        | '10%'    | 'DISCRETE' | 'CAP CHIP 0.1U 100V(+-10%,X7R,0603)SAM'                        | 'CHIP0603'     | ''          | ''   | '20190828'
 '0.1UF'    | '100V'  | '10%'     | 'C0603'     | 'EMPTY'   | 'CH4108K1904'(!)   = ''              | ''                 | ''       | 'CH4108K1904'     |'C0603'| '(SMC0603AW)'                                                        | 'NA'       | '100V'        | '10%'    | 'IO'       | 'CAP CHIP 0.1U 100V(+-10%,X7R,0603)SAM'                        | 'CHIP0603'     | ''          | ''   | '20190828'
 '1.8PF'    | '50V'   | '0.25PF'  | 'C0402'     | 'NPO'     | 'CH-1806TB07'(!)   = 'End of Design' | 'Comp-Approve'     | ''       | 'CH-1806TB07'     |'C0402'| '(C0402-0201)'                                                       | '1.8PF'    | '50V'         | '0.25PF' | 'DISCRETE' | 'CAP CHIP 1.8P 50V(+-0.25P,NPO,0402)'                          | 'CHIP0402'     | ''          | ''   | '20190906'
 '1.8PF'    | '50V'   | '0.25PF'  | 'C0402'     | 'EMPTY'   | 'CH-1806TB07'(!)   = 'End of Design' | 'Comp-Approve'     | ''       | 'CH-1806TB07'     |'C0402'| '(C0402-0201)'                                                       | 'NA'       | '50V'         | '0.25PF' | 'IO'       | 'CAP CHIP 1.8P 50V(+-0.25P,NPO,0402)'                          | 'CHIP0402'     | ''          | ''   | '20190906'
 '47NF'     | '50V'   | '10%'     | 'C0402'     | 'X7R'     | 'CH3476K1B00'(!)   = ''              | ''                 | ''       | 'CH3476K1B00'     |'C0402'| '(C0402-0201,C0402_OCTAGONXA)'                                       | '47NF'     | '50V'         | '10%'    | 'DISCRETE' | 'CAP CHIP 47NF 50V(+-10%,X7R,0402)'                            | 'CHIP0402'     | ''          | ''   | '20190925'
 '47NF'     | '50V'   | '10%'     | 'C0402'     | 'EMPTY'   | 'CH3476K1B00'(!)   = ''              | ''                 | ''       | 'CH3476K1B00'     |'C0402'| '(C0402-0201,C0402_OCTAGONXA)'                                       | 'NA'       | '50V'         | '10%'    | 'IO'       | 'CAP CHIP 47NF 50V(+-10%,X7R,0402)'                            | 'CHIP0402'     | ''          | ''   | '20190925'
 '100NF'    | '50V'   | '10%'     | 'C0402'     | 'X7R'     | 'CH4106K1B21'(!)   = ''              | ''                 | ''       | 'CH4106K1B21'     |'C0402_H28'| '(C0402-0201_H28)'                                                   | '100NF'    | '50V'         | '10%'    | 'DISCRETE' | 'CAP CHIP 100NF 50V(+-10%,X7R,0402)WTC'                        | 'CHIP0402'     | ''          | ''   | '20191021'
 '100NF'    | '50V'   | '10%'     | 'C0402'     | 'EMPTY'   | 'CH4106K1B21'(!)   = ''              | ''                 | ''       | 'CH4106K1B21'     |'C0402_H28'| '(C0402-0201_H28)'                                                   | 'NA'       | '50V'         | '10%'    | 'IO'       | 'CAP CHIP 100NF 50V(+-10%,X7R,0402)WTC'                        | 'CHIP0402'     | ''          | ''   | '20191021'
 '100NF'    | '50V'   | '10%'     | 'C0402'     | 'X7R'     | 'CH4106K1B20'(!)   = ''              | ''                 | ''       | 'CH4106K1B20'     |'C0402'| '(C0402-0201)'                                                       | '100NF'    | '50V'         | '10%'    | 'DISCRETE' | 'CAP CHIP 100NF 50V(+-10%,X7R,0402)SAM'                        | 'CHIP0402'     | ''          | ''   | '20191025'
 '100NF'    | '50V'   | '10%'     | 'C0402'     | 'EMPTY'   | 'CH4106K1B20'(!)   = ''              | ''                 | ''       | 'CH4106K1B20'     |'C0402'| '(C0402-0201)'                                                       | 'NA'       | '50V'         | '10%'    | 'IO'       | 'CAP CHIP 100NF 50V(+-10%,X7R,0402)SAM'                        | 'CHIP0402'     | ''          | ''   | '20191025'
 '390PF'    | '50V'   | '5%'      | 'C0402'     | 'X7R'     | 'CH13906JB16'(!)   = ''              | ''                 | ''       | 'CH13906JB16'     |'C0402'| '(C0402-0201)'                                                       | '390PF'    | '50V'         | '5%'     | 'DISCRETE' | 'CAP CHIP 390P 50V(+-5%,X7R,0402)'                             | 'CHIP0402'     | ''          | ''   | '20191101'
 '390PF'    | '50V'   | '5%'      | 'C0402'     | 'EMPTY'   | 'CH13906JB16'(!)   = ''              | ''                 | ''       | 'CH13906JB16'     |'C0402'| '(C0402-0201)'                                                       | 'NA'       | '50V'         | '5%'     | 'IO'       | 'CAP CHIP 390P 50V(+-5%,X7R,0402)'                             | 'CHIP0402'     | ''          | ''   | '20191101'
 '0.01UF'   | '100V'  | '10%'     | 'C0603'     | 'X7R'     | 'CH3108K1904'(!)   = ''              | ''                 | ''       | 'CH3108K1904'     |'C0603'| '(SMC0603AW)'                                                        | '0.01UF'   | '100V'        | '10%'    | 'DISCRETE' | 'CAP CHIP 0.01U 100V(+-10%,X7R,0603)MUR'                       | 'CHIP0603'     | ''          | ''   | '20191104'
 '0.01UF'   | '100V'  | '10%'     | 'C0603'     | 'EMPTY'   | 'CH3108K1904'(!)   = ''              | ''                 | ''       | 'CH3108K1904'     |'C0603'| '(SMC0603AW)'                                                        | 'NA'       | '100V'        | '10%'    | 'IO'       | 'CAP CHIP 0.01U 100V(+-10%,X7R,0603)MUR'                       | 'CHIP0603'     | ''          | ''   | '20191104'
 '0.01UF'   | '100V'  | '10%'     | 'C0603'     | 'X7R'     | 'CH3108K1905'(!)   = ''              | ''                 | ''       | 'CH3108K1905'     |'C0603'| '(SMC0603AW)'                                                        | '0.01UF'   | '100V'        | '10%'    | 'DISCRETE' | 'CAP CHIP 0.01U 100V(+-10%,X7R,0603)SAM'                       | 'CHIP0603'     | ''          | ''   | '20191108'
 '0.01UF'   | '100V'  | '10%'     | 'C0603'     | 'EMPTY'   | 'CH3108K1905'(!)   = ''              | ''                 | ''       | 'CH3108K1905'     |'C0603'| '(SMC0603AW)'                                                        | 'NA'       | '100V'        | '10%'    | 'IO'       | 'CAP CHIP 0.01U 100V(+-10%,X7R,0603)SAM'                       | 'CHIP0603'     | ''          | ''   | '20191108'
 '10UF'     | '50V'   | '10%'     | 'C1210'     | 'X7R'     | 'CH6106K1303'(!)   = ''              | ''                 | ''       | 'CH6106K1303'     |'C1210_GRM32E'| '(SMC1210AW)'                                                        | '10UF'     | '50V'         | '10%'    | 'DISCRETE' | 'CAP CHIP 10U 50V(+-10%,X7R,1210)MUR'                          | 'CHIP1210'     | ''          | ''   | '20191128'
 '10UF'     | '50V'   | '10%'     | 'C1210'     | 'EMPTY'   | 'CH6106K1303'(!)   = ''              | ''                 | ''       | 'CH6106K1303'     |'C1210_GRM32E'| '(SMC1210AW)'                                                        | 'NA'       | '50V'         | '10%'    | 'IO'       | 'CAP CHIP 10U 50V(+-10%,X7R,1210)MUR'                          | 'CHIP1210'     | ''          | ''   | '20191128'
 '4700PF'   | '50V'   | '5%'      | 'C0402'     | 'C0G'     | 'CH2476J0B01'(!)   = ''              | ''                 | ''       | 'CH2476J0B01'     |'C0402_H28'| '(C0402-0201_H28)'                                                   | '4700PF'   | '50V'         | '5%'     | 'DISCRETE' | 'CAP CHIP 4700P 50V(+-5%,C0G,0402)MUR'                         | 'CHIP0402'     | ''          | ''   | '20191128'
 '4700PF'   | '50V'   | '5%'      | 'C0402'     | 'EMPTY'   | 'CH2476J0B01'(!)   = ''              | ''                 | ''       | 'CH2476J0B01'     |'C0402_H28'| '(C0402-0201_H28)'                                                   | 'NA'       | '50V'         | '5%'     | 'IO'       | 'CAP CHIP 4700P 50V(+-5%,C0G,0402)MUR'                         | 'CHIP0402'     | ''          | ''   | '20191128'
 '2200PF'   | '50V'   | '5%'      | 'C0402'     | 'C0G'     | 'CH2226J0B01'(!)   = ''              | ''                 | ''       | 'CH2226J0B01'     |'C0402'| '(C0402-0201)'                                                       | '2200PF'   | '50V'         | '5%'     | 'DISCRETE' | 'CAP CHIP 2200P 50V(+-5%,C0G,0402)MUR'                         | 'CHIP0402'     | ''          | ''   | '20191128'
 '2200PF'   | '50V'   | '5%'      | 'C0402'     | 'EMPTY'   | 'CH2226J0B01'(!)   = ''              | ''                 | ''       | 'CH2226J0B01'     |'C0402'| '(C0402-0201)'                                                       | 'NA'       | '50V'         | '5%'     | 'IO'       | 'CAP CHIP 2200P 50V(+-5%,C0G,0402)MUR'                         | 'CHIP0402'     | ''          | ''   | '20191128'
 '1.1PF'    | '25V'   | '0.05PF'  | 'C0201'     | 'C0G'     | 'CH-114T0E00'(!)   = ''              | ''                 | ''       | 'CH-114T0E00'     |'C0201'| '(SMC0201AW)'                                                        | '1.1PF'    | '25V'         | '0.05PF' | 'DISCRETE' | 'CAPCHIP1.1PF25V(+-0.05PF,C0G,0201)HQ MUR'                     | 'CHIP0201'     | ''          | ''   | '20191210'
 '1.1PF'    | '25V'   | '0.05PF'  | 'C0201'     | 'EMPTY'   | 'CH-114T0E00'(!)   = ''              | ''                 | ''       | 'CH-114T0E00'     |'C0201'| '(SMC0201AW)'                                                        | 'NA'       | '25V'         | '0.05PF' | 'IO'       | 'CAPCHIP1.1PF25V(+-0.05PF,C0G,0201)HQ MUR'                     | 'CHIP0201'     | ''          | ''   | '20191210'
 '4.7UF'    | '100V'  | '10%'     | 'C1210'     | 'X7S'     | 'CH5478K6304'(!)   = ''              | ''                 | ''       | 'CH5478K6304'     |'C1210_HMK325'| '(SMC1210AW)'                                                        | '4.7UF'    | '100V'        | '10%'    | 'DISCRETE' | 'CAP CHIP 4.7U 100V(+-10%,X7S,1210)TAY'                        | 'CHIP1210'     | ''          | ''   | '20191210'
 '4.7UF'    | '100V'  | '10%'     | 'C1210'     | 'EMPTY'   | 'CH5478K6304'(!)   = ''              | ''                 | ''       | 'CH5478K6304'     |'C1210_HMK325'| '(SMC1210AW)'                                                        | 'NA'       | '100V'        | '10%'    | 'IO'       | 'CAP CHIP 4.7U 100V(+-10%,X7S,1210)TAY'                        | 'CHIP1210'     | ''          | ''   | '20191210'
 '12PF'     | '25V'   | '5%'      | 'C0201'     | 'NPO'     | 'CH0124J0E02'(!)   = ''              | ''                 | ''       | 'CH0124J0E02'     |'C0201'| '(SMC0201AW)'                                                        | '12PF'     | '25V'         | '5%'     | 'DISCRETE' | 'CAP CHIP 12PF 25V(+-5%,NPO,0201)'                             | 'CHIP0201'     | ''          | ''   | '20191210'
 '12PF'     | '25V'   | '5%'      | 'C0201'     | 'EMPTY'   | 'CH0124J0E02'(!)   = ''              | ''                 | ''       | 'CH0124J0E02'     |'C0201'| '(SMC0201AW)'                                                        | 'NA'       | '25V'         | '5%'     | 'IO'       | 'CAP CHIP 12PF 25V(+-5%,NPO,0201)'                             | 'CHIP0201'     | ''          | ''   | '20191210'
 '180PF'    | '50V'   | '5%'      | 'C0201'     | 'C0G'     | 'CH1186J0E00'(!)   = ''              | ''                 | ''       | 'CH1186J0E00'     |'C0201'| '(SMC0201AW)'                                                        | '180PF'    | '50V'         | '5%'     | 'DISCRETE' | 'CAP CHIP 180PF 50V(+-5%,C0G,0201)'                            | 'CHIP0201'     | ''          | ''   | '20191210'
 '180PF'    | '50V'   | '5%'      | 'C0201'     | 'EMPTY'   | 'CH1186J0E00'(!)   = ''              | ''                 | ''       | 'CH1186J0E00'     |'C0201'| '(SMC0201AW)'                                                        | 'NA'       | '50V'         | '5%'     | 'IO'       | 'CAP CHIP 180PF 50V(+-5%,C0G,0201)'                            | 'CHIP0201'     | ''          | ''   | '20191210'
 '15PF'     | '25V'   | '5%'      | 'C0201'     | 'COG'     | 'CH0154J0E03'(!)   = ''              | ''                 | ''       | 'CH0154J0E03'     |'C0201'| '(SMC0201AW)'                                                        | '15PF'     | '25V'         | '5%'     | 'DISCRETE' | 'CAP CHIP 15P 25V(+-5%,COG,0201)'                              | 'CHIP0201'     | ''          | ''   | '20191210'
 '15PF'     | '25V'   | '5%'      | 'C0201'     | 'EMPTY'   | 'CH0154J0E03'(!)   = ''              | ''                 | ''       | 'CH0154J0E03'     |'C0201'| '(SMC0201AW)'                                                        | 'NA'       | '25V'         | '5%'     | 'IO'       | 'CAP CHIP 15P 25V(+-5%,COG,0201)'                              | 'CHIP0201'     | ''          | ''   | '20191210'
 '18PF'     | '25V'   | '5%'      | 'C0201'     | 'COG'     | 'CH0184J0E04'(!)   = ''              | ''                 | ''       | 'CH0184J0E04'     |'C0201'| '(SMC0201AW)'                                                        | '18PF'     | '25V'         | '5%'     | 'DISCRETE' | 'CAP CHIP 18P 25V(+-5%,COG,0201)'                              | 'CHIP0201'     | ''          | ''   | '20191216'
 '18PF'     | '25V'   | '5%'      | 'C0201'     | 'EMPTY'   | 'CH0184J0E04'(!)   = ''              | ''                 | ''       | 'CH0184J0E04'     |'C0201'| '(SMC0201AW)'                                                        | 'NA'       | '25V'         | '5%'     | 'IO'       | 'CAP CHIP 18P 25V(+-5%,COG,0201)'                              | 'CHIP0201'     | ''          | ''   | '20191216'
 '33PF'     | '25V'   | '5%'      | 'C0201'     | 'COG'     | 'CH0334J0E01'(!)   = ''              | ''                 | ''       | 'CH0334J0E01'     |'C0201'| '(SMC0201AW)'                                                        | '33PF'     | '25V'         | '5%'     | 'DISCRETE' | 'CAP CHIP 33P 25V(+-5%,COG,0201)'                              | 'CHIP0201'     | ''          | ''   | '20191217'
 '33PF'     | '25V'   | '5%'      | 'C0201'     | 'EMPTY'   | 'CH0334J0E01'(!)   = ''              | ''                 | ''       | 'CH0334J0E01'     |'C0201'| '(SMC0201AW)'                                                        | 'NA'       | '25V'         | '5%'     | 'IO'       | 'CAP CHIP 33P 25V(+-5%,COG,0201)'                              | 'CHIP0201'     | ''          | ''   | '20191217'
 '5PF'      | '25V'   | '0.25PF'  | 'C0201'     | 'NPO'     | 'CH-504T0E08'(!)   = 'End of Design' | 'Comp-Approve'     | ''       | 'CH-504T0E08'     |'C0201'| '(SMC0201AW)'                                                        | '5PF'      | '25V'         | '0.25PF' | 'DISCRETE' | 'CAP CHIP 5P 25V(+-0.25P,NPO,0201)'                            | 'CHIP0201'     | ''          | ''   | '20191212'
 '5PF'      | '25V'   | '0.25PF'  | 'C0201'     | 'EMPTY'   | 'CH-504T0E08'(!)   = 'End of Design' | 'Comp-Approve'     | ''       | 'CH-504T0E08'     |'C0201'| '(SMC0201AW)'                                                        | 'NA'       | '25V'         | '0.25PF' | 'IO'       | 'CAP CHIP 5P 25V(+-0.25P,NPO,0201)'                            | 'CHIP0201'     | ''          | ''   | '20191212'
 '6.8PF'    | '25V'   | '0.5PF'   | 'C0201'     | 'COG'     | 'CH-684T0E00'(!)   = ''              | ''                 | ''       | 'CH-684T0E00'     |'C0201'| '(SMC0201AW)'                                                        | '6.8PF'    | '25V'         | '0.5PF'  | 'DISCRETE' | 'CAP CHIP 6.8P 25V(+-0.5P,COG,0201)'                           | 'CHIP0201'     | ''          | ''   | '20191217'
 '6.8PF'    | '25V'   | '0.5PF'   | 'C0201'     | 'EMPTY'   | 'CH-684T0E00'(!)   = ''              | ''                 | ''       | 'CH-684T0E00'     |'C0201'| '(SMC0201AW)'                                                        | 'NA'       | '25V'         | '0.5PF'  | 'IO'       | 'CAP CHIP 6.8P 25V(+-0.5P,COG,0201)'                           | 'CHIP0201'     | ''          | ''   | '20191217'
 '1UF'      | '16V'   | '10%'     | 'C0402'     | 'X7R'     | 'CH5103K1B00'(!)   = 'End of Design' | 'Comp-Release Qty' | ''       | 'CH5103K1B00'     |'C0402_H28'| '(C0402-0201_H28)'                                                   | '1UF'      | '16V'         | '10%'    | 'DISCRETE' | 'CAP CHIP 1UF 16V(+-10%,X7R,0402)'                             | 'CHIP0402'     | ''          | ''   | '20191213'
 '1UF'      | '16V'   | '10%'     | 'C0402'     | 'EMPTY'   | 'CH5103K1B00'(!)   = 'End of Design' | 'Comp-Release Qty' | ''       | 'CH5103K1B00'     |'C0402_H28'| '(C0402-0201_H28)'                                                   | 'NA'       | '16V'         | '10%'    | 'IO'       | 'CAP CHIP 1UF 16V(+-10%,X7R,0402)'                             | 'CHIP0402'     | ''          | ''   | '20191213'
 '330PF'    | '50V'   | '5%'      | 'C0402'     | 'NPO'     | 'CH1336J0B01'(!)   = ''              | ''                 | ''       | 'CH1336J0B01'     |'C0402'| '(C0402-0201)'                                                       | '330PF'    | '50V'         | '5%'     | 'DISCRETE' | 'CAP CHIP 330P,50V(+-5%,NPO,0402)'                             | 'CHIP0402'     | ''          | ''   | '20191213'
 '330PF'    | '50V'   | '5%'      | 'C0402'     | 'EMPTY'   | 'CH1336J0B01'(!)   = ''              | ''                 | ''       | 'CH1336J0B01'     |'C0402'| '(C0402-0201)'                                                       | 'NA'       | '50V'         | '5%'     | 'IO'       | 'CAP CHIP 330P,50V(+-5%,NPO,0402)'                             | 'CHIP0402'     | ''          | ''   | '20191213'
 '5.0PF'    | '50V'   | '0.1PF'   | 'C0402'     | 'C0G'     | 'CH-506B0B00'(!)   = ''              | ''                 | ''       | 'CH-506B0B00'     |'C0402'| '(C0402-0201)'                                                       | '5.0PF'    | '50V'         | '0.1PF'  | 'DISCRETE' | 'CAP CHIP 5.0P 50V(+-0.1P,C0G,0402)'                           | 'CHIP0402'     | ''          | ''   | '20191213'
 '5.0PF'    | '50V'   | '0.1PF'   | 'C0402'     | 'EMPTY'   | 'CH-506B0B00'(!)   = ''              | ''                 | ''       | 'CH-506B0B00'     |'C0402'| '(C0402-0201)'                                                       | 'NA'       | '50V'         | '0.1PF'  | 'IO'       | 'CAP CHIP 5.0P 50V(+-0.1P,C0G,0402)'                           | 'CHIP0402'     | ''          | ''   | '20191213'
 '2.2UF'    | '16V'   | '20%'     | 'C0603'     | 'X7R'     | 'CH5223M1900'(!)   = ''              | ''                 | ''       | 'CH5223M1900'     |'C0603_H40'| '(SMC0603AW)'                                                        | '2.2UF'    | '16V'         | '20%'    | 'DISCRETE' | 'CAP CHIP 2.2UF 16V(20%,X7R,0603)'                             | 'CHIP0603'     | ''          | ''   | '20191216'
 '2.2UF'    | '16V'   | '20%'     | 'C0603'     | 'EMPTY'   | 'CH5223M1900'(!)   = ''              | ''                 | ''       | 'CH5223M1900'     |'C0603_H40'| '(SMC0603AW)'                                                        | 'NA'       | '16V'         | '20%'    | 'IO'       | 'CAP CHIP 2.2UF 16V(20%,X7R,0603)'                             | 'CHIP0603'     | ''          | ''   | '20191216'
 '47000PF'  | '100V'  | '5%'      | 'C1206'     | 'C0G'     | 'CH3478J0200'(!)   = ''              | ''                 | ''       | 'CH3478J0200'     |'C1206XG'| '(SMC1206AW)'                                                        | '47000PF'  | '100V'        | '5%'     | 'DISCRETE' | 'CAP CHIP 47000P 100V(+-5%,C0G,1206)MUR'                       | 'CHIP1206'     | ''          | ''   | '20191220'
 '47000PF'  | '100V'  | '5%'      | 'C1206'     | 'EMPTY'   | 'CH3478J0200'(!)   = ''              | ''                 | ''       | 'CH3478J0200'     |'C1206XG'| '(SMC1206AW)'                                                        | 'NA'       | '100V'        | '5%'     | 'IO'       | 'CAP CHIP 47000P 100V(+-5%,C0G,1206)MUR'                       | 'CHIP1206'     | ''          | ''   | '20191220'
 '27PF'     | '25V'   | '5%'      | 'C0201'     | 'NPO'     | 'CH0274J0E03'(!)   = ''              | ''                 | ''       | 'CH0274J0E03'     |'C0201'| '(SMC0201AW)'                                                        | '27PF'     | '25V'         | '5%'     | 'DISCRETE' | 'CAP CHIP 27PF 25V(+-5%,NPO,0201)'                             | 'CHIP0201'     | ''          | ''   | '20200109'
 '27PF'     | '25V'   | '5%'      | 'C0201'     | 'EMPTY'   | 'CH0274J0E03'(!)   = ''              | ''                 | ''       | 'CH0274J0E03'     |'C0201'| '(SMC0201AW)'                                                        | 'NA'       | '25V'         | '5%'     | 'IO'       | 'CAP CHIP 27PF 25V(+-5%,NPO,0201)'                             | 'CHIP0201'     | ''          | ''   | '20200109'
 '5600PF'   | '50V'   | '10%'     | 'C0402'     | 'X7R'     | 'CH2566K1B00'(!)   = 'End of Design' | 'Comp-Approve'     | ''       | 'CH2566K1B00'     |'C0402'| '(C0402-0201)'                                                       | '5600PF'   | '50V'         | '10%'    | 'DISCRETE' | 'CAP CHIP 5600PF 50V(+-10%,X7R,0402)'                          | 'CHIP0402'     | ''          | ''   | '20200107'
 '5600PF'   | '50V'   | '10%'     | 'C0402'     | 'EMPTY'   | 'CH2566K1B00'(!)   = 'End of Design' | 'Comp-Approve'     | ''       | 'CH2566K1B00'     |'C0402'| '(C0402-0201)'                                                       | 'NA'       | '50V'         | '10%'    | 'IO'       | 'CAP CHIP 5600PF 50V(+-10%,X7R,0402)'                          | 'CHIP0402'     | ''          | ''   | '20200107'
 '39PF'     | '50V'   | '5%'      | 'C0402'     | 'NPO'     | 'CH0396J0B04'(!)   = ''              | ''                 | ''       | 'CH0396J0B04'     |'C0402'| '(C0402-0201)'                                                       | '39PF'     | '50V'         | '5%'     | 'DISCRETE' | 'CAP CHIP 39P 50V(+-5%,NPO,0402)MUR'                           | 'CHIP0402'     | ''          | ''   | '20200218'
 '39PF'     | '50V'   | '5%'      | 'C0402'     | 'EMPTY'   | 'CH0396J0B04'(!)   = ''              | ''                 | ''       | 'CH0396J0B04'     |'C0402'| '(C0402-0201)'                                                       | 'NA'       | '50V'         | '5%'     | 'IO'       | 'CAP CHIP 39P 50V(+-5%,NPO,0402)MUR'                           | 'CHIP0402'     | ''          | ''   | '20200218'
 '8.2PF'    | '50V'   | '0.25PF'  | 'C0402'     | 'NPO'     | 'CH-826C0B05'(!)   = ''              | ''                 | ''       | 'CH-826C0B05'     |'C0402'| '(C0402-0201)'                                                       | '8.2PF'    | '50V'         | '0.25PF' | 'DISCRETE' | 'CAP CHIP 8.2P 50V(+-0.25P,NPO,0402)MUR'                       | 'CHIP0402'     | ''          | ''   | '20200218'
 '8.2PF'    | '50V'   | '0.25PF'  | 'C0402'     | 'EMPTY'   | 'CH-826C0B05'(!)   = ''              | ''                 | ''       | 'CH-826C0B05'     |'C0402'| '(C0402-0201)'                                                       | 'NA'       | '50V'         | '0.25PF' | 'IO'       | 'CAP CHIP 8.2P 50V(+-0.25P,NPO,0402)MUR'                       | 'CHIP0402'     | ''          | ''   | '20200218'
 '0.001UF'  | '50V'   | '10%'     | 'C0402'     | 'X7R'     | 'CH30106KB19'(!)   = 'End of Design' | 'Comp-Release Qty' | ''       | 'CH30106KB19'     |'C0402'| '(C0402-0201)'                                                       | '0.001UF'  | '50V'         | '10%'    | 'DISCRETE' | 'CAP CHIP 0.001U 50V(10%,X7R,0402)'                            | 'CHIP0402'     | ''          | ''   | '20200218'
 '0.001UF'  | '50V'   | '10%'     | 'C0402'     | 'EMPTY'   | 'CH30106KB19'(!)   = 'End of Design' | 'Comp-Release Qty' | ''       | 'CH30106KB19'     |'C0402'| '(C0402-0201)'                                                       | 'NA'       | '50V'         | '10%'    | 'IO'       | 'CAP CHIP 0.001U 50V(10%,X7R,0402)'                            | 'CHIP0402'     | ''          | ''   | '20200218'
 '0.22UF'   | '6.3V'  | '10%'     | 'C0201'     | 'X6S'     | 'CH4221KEE01'(!)   = ''              | ''                 | ''       | 'CH4221KEE01'     |'C0201'| '(SMC0201AW)'                                                        | '0.22UF'   | '6.3V'        | '10%'    | 'DISCRETE' | 'CAP CHIP 0.22UF 6.3V(+-10%,X6S,0201)MUR'                      | 'CHIP0201'     | ''          | ''   | '20200224'
 '0.22UF'   | '6.3V'  | '10%'     | 'C0201'     | 'EMPTY'   | 'CH4221KEE01'(!)   = ''              | ''                 | ''       | 'CH4221KEE01'     |'C0201'| '(SMC0201AW)'                                                        | 'NA'       | '6.3V'        | '10%'    | 'IO'       | 'CAP CHIP 0.22UF 6.3V(+-10%,X6S,0201)MUR'                      | 'CHIP0201'     | ''          | ''   | '20200224'
 '0.022UF'  | '250V'  | '20%'     | 'C0805'     | 'X7R'     | 'CH3220CMA17'(!)   = 'End of Design' | 'Comp-Approve'     | ''       | 'CH3220CMA17'     |'C0805_H57'| '(SMC0805AW)'                                                        | '0.022UF'  | '250V'        | '20%'    | 'DISCRETE' | 'CAP CHIP 0.022U 250V(+-20%,X7R,0805)'                         | 'CHIP0805'     | ''          | ''   | '20200303'
 '0.022UF'  | '250V'  | '20%'     | 'C0805'     | 'EMPTY'   | 'CH3220CMA17'(!)   = 'End of Design' | 'Comp-Approve'     | ''       | 'CH3220CMA17'     |'C0805_H57'| '(SMC0805AW)'                                                        | 'NA'       | '250V'        | '20%'    | 'IO'       | 'CAP CHIP 0.022U 250V(+-20%,X7R,0805)'                         | 'CHIP0805'     | ''          | ''   | '20200303'
 '47PF'     | '50V'   | '5%'      | 'C0402'     | 'NPO'     | 'CH0476J0B12'(!)   = ''              | ''                 | ''       | 'CH0476J0B12'     |'C0402'| '(C0402-0201)'                                                       | '47PF'     | '50V'         | '5%'     | 'DISCRETE' | 'CAP CHIP 47P 50V(+-5%,NPO,0402)MUR'                           | 'CHIP0402'     | ''          | ''   | '20200312'
 '47PF'     | '50V'   | '5%'      | 'C0402'     | 'EMPTY'   | 'CH0476J0B12'(!)   = ''              | ''                 | ''       | 'CH0476J0B12'     |'C0402'| '(C0402-0201)'                                                       | 'NA'       | '50V'         | '5%'     | 'IO'       | 'CAP CHIP 47P 50V(+-5%,NPO,0402)MUR'                           | 'CHIP0402'     | ''          | ''   | '20200312'
 '220PF'    | '100V'  | '10%'     | 'C0402'     | 'X7R'     | 'CH1228K1B01'(!)   = ''              | ''                 | ''       | 'CH1228K1B01'     |'C0402'| '(C0402-0201)'                                                       | '220PF'    | '100V'        | '10%'    | 'DISCRETE' | 'CAP CHIP 220PF 100V(+-10%,X7R,0402)MUR'                       | 'CHIP0402'     | ''          | ''   | '20200312'
 '220PF'    | '100V'  | '10%'     | 'C0402'     | 'EMPTY'   | 'CH1228K1B01'(!)   = ''              | ''                 | ''       | 'CH1228K1B01'     |'C0402'| '(C0402-0201)'                                                       | 'NA'       | '100V'        | '10%'    | 'IO'       | 'CAP CHIP 220PF 100V(+-10%,X7R,0402)MUR'                       | 'CHIP0402'     | ''          | ''   | '20200312'
 '5600PF'   | '50V'   | '10%'     | 'C0402'     | 'X7R'     | 'CH2566K1B09'(!)   = ''              | ''                 | ''       | 'CH2566K1B09'     |'C0402'| '(C0402-0201)'                                                       | '5600PF'   | '50V'         | '10%'    | 'DISCRETE' | 'CAP CHIP 5600P 50V(+-10%,X7R,0402)API'                        | 'CHIP0402'     | ''          | ''   | '20200312'
 '5600PF'   | '50V'   | '10%'     | 'C0402'     | 'EMPTY'   | 'CH2566K1B09'(!)   = ''              | ''                 | ''       | 'CH2566K1B09'     |'C0402'| '(C0402-0201)'                                                       | 'NA'       | '50V'         | '10%'    | 'IO'       | 'CAP CHIP 5600P 50V(+-10%,X7R,0402)API'                        | 'CHIP0402'     | ''          | ''   | '20200312'
 '0.022UF'  | '50V'   | '10%'     | 'C0603'     | 'X7R'     | 'CH3226K1908'(!)   = ''              | ''                 | ''       | 'CH3226K1908'     |'C0603'| '(SMC0603AW)'                                                        | '0.022UF'  | '50V'         | '10%'    | 'DISCRETE' | 'CAP CHIP 0.022U 50V(+-10%,X7R,0603)API'                       | 'CHIP0603'     | ''          | ''   | '20200313'
 '0.022UF'  | '50V'   | '10%'     | 'C0603'     | 'EMPTY'   | 'CH3226K1908'(!)   = ''              | ''                 | ''       | 'CH3226K1908'     |'C0603'| '(SMC0603AW)'                                                        | 'NA'       | '50V'         | '10%'    | 'IO'       | 'CAP CHIP 0.022U 50V(+-10%,X7R,0603)API'                       | 'CHIP0603'     | ''          | ''   | '20200313'
 '22UF'     | '25V'   | '20%'     | 'C0805'     | 'X5R'     | 'CH6224M9A05'(!)   = ''              | ''                 | ''       | 'CH6224M9A05'     |'C0805_H57'| '(SMC0805AW)'                                                        | '22UF'     | '25V'         | '20%'    | 'DISCRETE' | 'CAP CHIP 22U 25V(+-20%,X5R,0805)MUR'                          | 'CHIP0805'     | ''          | ''   | '20200313'
 '22UF'     | '25V'   | '20%'     | 'C0805'     | 'EMPTY'   | 'CH6224M9A05'(!)   = ''              | ''                 | ''       | 'CH6224M9A05'     |'C0805_H57'| '(SMC0805AW)'                                                        | 'NA'       | '25V'         | '20%'    | 'IO'       | 'CAP CHIP 22U 25V(+-20%,X5R,0805)MUR'                          | 'CHIP0805'     | ''          | ''   | '20200313'
 '10UF'     | '25V'   | '20%'     | 'C0603'     | 'X5R'     | 'CH6104M9905'(!)   = ''              | ''                 | ''       | 'CH6104M9905'     |'C0603_H40'| '(SMC0603AW)'                                                        | '10UF'     | '25V'         | '20%'    | 'DISCRETE' | 'CAP CHIP 10UF 25V(+-20%,X5R,0603)MUR'                         | 'CHIP0603'     | ''          | ''   | '20200313'
 '10UF'     | '25V'   | '20%'     | 'C0603'     | 'EMPTY'   | 'CH6104M9905'(!)   = ''              | ''                 | ''       | 'CH6104M9905'     |'C0603_H40'| '(SMC0603AW)'                                                        | 'NA'       | '25V'         | '20%'    | 'IO'       | 'CAP CHIP 10UF 25V(+-20%,X5R,0603)MUR'                         | 'CHIP0603'     | ''          | ''   | '20200313'
 '4.7UF'    | '25V'   | '10%'     | 'C0805'     | 'X7R'     | 'CH5474K1A04'(!)   = 'End of Design' | 'Comp-Approve'     | ''       | 'CH5474K1A04'     |'C0805_H57'| '(SMC0805AW)'                                                        | '4.7UF'    | '25V'         | '10%'    | 'DISCRETE' | 'CAP CHIP 4.7U 25V(+-10%,X7R,0805)MUR'                         | 'CHIP0805'     | ''          | ''   | '20200317'
 '4.7UF'    | '25V'   | '10%'     | 'C0805'     | 'EMPTY'   | 'CH5474K1A04'(!)   = 'End of Design' | 'Comp-Approve'     | ''       | 'CH5474K1A04'     |'C0805_H57'| '(SMC0805AW)'                                                        | 'NA'       | '25V'         | '10%'    | 'IO'       | 'CAP CHIP 4.7U 25V(+-10%,X7R,0805)MUR'                         | 'CHIP0805'     | ''          | ''   | '20200317'
 '220PF'    | '50V'   | '10%'     | 'C0402'     | 'X7R'     | 'CH1226K1B10'(!)   = ''              | ''                 | ''       | 'CH1226K1B10'     |'C0402'| '(C0402-0201)'                                                       | '220PF'    | '50V'         | '10%'    | 'DISCRETE' | 'CAP CHIP 220PF 50V(+-10%,X7R,0402)MUR'                        | 'CHIP0402'     | ''          | ''   | '20200317'
 '220PF'    | '50V'   | '10%'     | 'C0402'     | 'EMPTY'   | 'CH1226K1B10'(!)   = ''              | ''                 | ''       | 'CH1226K1B10'     |'C0402'| '(C0402-0201)'                                                       | 'NA'       | '50V'         | '10%'    | 'IO'       | 'CAP CHIP 220PF 50V(+-10%,X7R,0402)MUR'                        | 'CHIP0402'     | ''          | ''   | '20200317'
 '0.047UF'  | '16V'   | '10%'     | 'C0402'     | 'X7R'     | 'CH3473K1B10'(!)   = ''              | ''                 | ''       | 'CH3473K1B10'     |'C0402'| '(C0402-0201)'                                                       | '0.047UF'  | '16V'         | '10%'    | 'DISCRETE' | 'CAP CHIP 0.047U 16V(+-10%,X7R,0402)MUR'                       | 'CHIP0402'     | ''          | ''   | '20200318'
 '0.047UF'  | '16V'   | '10%'     | 'C0402'     | 'EMPTY'   | 'CH3473K1B10'(!)   = ''              | ''                 | ''       | 'CH3473K1B10'     |'C0402'| '(C0402-0201)'                                                       | 'NA'       | '16V'         | '10%'    | 'IO'       | 'CAP CHIP 0.047U 16V(+-10%,X7R,0402)MUR'                       | 'CHIP0402'     | ''          | ''   | '20200318'
 '4.7UF'    | '16V'   | '10%'     | 'C0603'     | 'X6S'     | 'CH5473KE903'(!)   = ''              | ''                 | ''       | 'CH5473KE903'     |'C0603_H40'| '(SMC0603AW)'                                                        | '4.7UF'    | '16V'         | '10%'    | 'DISCRETE' | 'CAP CHIP 4.7UF 16V(+-10%,X6S,0603)MUR'                        | 'CHIP0603'     | ''          | ''   | '20200318'
 '4.7UF'    | '16V'   | '10%'     | 'C0603'     | 'EMPTY'   | 'CH5473KE903'(!)   = ''              | ''                 | ''       | 'CH5473KE903'     |'C0603_H40'| '(SMC0603AW)'                                                        | 'NA'       | '16V'         | '10%'    | 'IO'       | 'CAP CHIP 4.7UF 16V(+-10%,X6S,0603)MUR'                        | 'CHIP0603'     | ''          | ''   | '20200318'
 '0.047UF'  | '50V'   | '10%'     | 'C0603'     | 'X7R'     | 'CH3476K1905'(!)   = ''              | ''                 | ''       | 'CH3476K1905'     |'C0603'| '(SMC0603AW)'                                                        | '0.047UF'  | '50V'         | '10%'    | 'DISCRETE' | 'CAP CHIP 0.047UF 50V(+-10%,X7R,0603)SAM'                      | 'CHIP0603'     | ''          | ''   | '20200318'
 '0.047UF'  | '50V'   | '10%'     | 'C0603'     | 'EMPTY'   | 'CH3476K1905'(!)   = ''              | ''                 | ''       | 'CH3476K1905'     |'C0603'| '(SMC0603AW)'                                                        | 'NA'       | '50V'         | '10%'    | 'IO'       | 'CAP CHIP 0.047UF 50V(+-10%,X7R,0603)SAM'                      | 'CHIP0603'     | ''          | ''   | '20200318'
 '5PF'      | '50V'   | '0.25PF'  | 'C0402'     | 'C0G'     | 'CH-506C0B04'(!)   = ''              | ''                 | ''       | 'CH-506C0B04'     |'C0402'| '(C0402-0201)'                                                       | '5PF'      | '50V'         | '0.25PF' | 'DISCRETE' | 'CAP CHIP 5P 50V(0.25P,C0G,0402)MUR'                           | 'CHIP0402'     | ''          | ''   | '20200319'
 '5PF'      | '50V'   | '0.25PF'  | 'C0402'     | 'EMPTY'   | 'CH-506C0B04'(!)   = ''              | ''                 | ''       | 'CH-506C0B04'     |'C0402'| '(C0402-0201)'                                                       | 'NA'       | '50V'         | '0.25PF' | 'IO'       | 'CAP CHIP 5P 50V(0.25P,C0G,0402)MUR'                           | 'CHIP0402'     | ''          | ''   | '20200319'
 '8.2PF'    | '50V'   | '0.25PF'  | 'C0402'     | 'NPO'     | 'CH-826C0B07'(!)   = ''              | ''                 | ''       | 'CH-826C0B07'     |'C0402'| '(C0402-0201)'                                                       | '8.2PF'    | '50V'         | '0.25PF' | 'DISCRETE' | 'CAP CHIP 8.2P 50V(+-0.25P,NPO,0402)YGO'                       | 'CHIP0402'     | ''          | ''   | '20200320'
 '8.2PF'    | '50V'   | '0.25PF'  | 'C0402'     | 'EMPTY'   | 'CH-826C0B07'(!)   = ''              | ''                 | ''       | 'CH-826C0B07'     |'C0402'| '(C0402-0201)'                                                       | 'NA'       | '50V'         | '0.25PF' | 'IO'       | 'CAP CHIP 8.2P 50V(+-0.25P,NPO,0402)YGO'                       | 'CHIP0402'     | ''          | ''   | '20200320'
 '39PF'     | '50V'   | '5%'      | 'C0402'     | 'NPO'     | 'CH0396J0B06'(!)   = ''              | ''                 | ''       | 'CH0396J0B06'     |'C0402'| '(C0402-0201)'                                                       | '39PF'     | '50V'         | '5%'     | 'DISCRETE' | 'CAP CHIP 39P 50V(+-5%,NPO,0402)YGO'                           | 'CHIP0402'     | ''          | ''   | '20200327'
 '39PF'     | '50V'   | '5%'      | 'C0402'     | 'EMPTY'   | 'CH0396J0B06'(!)   = ''              | ''                 | ''       | 'CH0396J0B06'     |'C0402'| '(C0402-0201)'                                                       | 'NA'       | '50V'         | '5%'     | 'IO'       | 'CAP CHIP 39P 50V(+-5%,NPO,0402)YGO'                           | 'CHIP0402'     | ''          | ''   | '20200327'
 '1200PF'   | '50V'   | '5%'      | 'C0402'     | 'C0G'     | 'CH2126J0B01'(!)   = 'End of Design' | 'Comp-Approve'     | ''       | 'CH2126J0B01'     |'C0402'| '(C0402-0201)'                                                       | '1200PF'   | '50V'         | '5%'     | 'DISCRETE' | 'CAP CHIP 1200P 50V(+-5%,C0G,0402)MUR'                         | 'CHIP0402'     | ''          | ''   | '20200331'
 '1200PF'   | '50V'   | '5%'      | 'C0402'     | 'EMPTY'   | 'CH2126J0B01'(!)   = 'End of Design' | 'Comp-Approve'     | ''       | 'CH2126J0B01'     |'C0402'| '(C0402-0201)'                                                       | 'NA'       | '50V'         | '5%'     | 'IO'       | 'CAP CHIP 1200P 50V(+-5%,C0G,0402)MUR'                         | 'CHIP0402'     | ''          | ''   | '20200331'
 '27PF'     | '50V'   | '5%'      | 'C0402'     | 'NPO'     | 'CH0276J0B09'(!)   = ''              | ''                 | ''       | 'CH0276J0B09'     |'C0402'| '(C0402-0201)'                                                       | '27PF'     | '50V'         | '5%'     | 'DISCRETE' | 'CAP CHIP 27P 50V(+-5%,NPO,0402)MUR'                           | 'CHIP0402'     | ''          | ''   | '20200331'
 '27PF'     | '50V'   | '5%'      | 'C0402'     | 'EMPTY'   | 'CH0276J0B09'(!)   = ''              | ''                 | ''       | 'CH0276J0B09'     |'C0402'| '(C0402-0201)'                                                       | 'NA'       | '50V'         | '5%'     | 'IO'       | 'CAP CHIP 27P 50V(+-5%,NPO,0402)MUR'                           | 'CHIP0402'     | ''          | ''   | '20200331'
 '10UF'     | '35V'   | '10%'     | 'C0805'     | 'X6S'     | 'CH6105KEA01'(!)   = 'End of Design' | 'Comp-Approve'     | ''       | 'CH6105KEA01'     |'C0805_H57'| '(SMC0805AW)'                                                        | '10UF'     | '35V'         | '10%'    | 'DISCRETE' | 'CAP CHIP 10UF 35V(+-10%,X6S,0805)'                            | 'CHIP0805'     | ''          | ''   | '20200410'
 '10UF'     | '35V'   | '10%'     | 'C0805'     | 'EMPTY'   | 'CH6105KEA01'(!)   = 'End of Design' | 'Comp-Approve'     | ''       | 'CH6105KEA01'     |'C0805_H57'| '(SMC0805AW)'                                                        | 'NA'       | '35V'         | '10%'    | 'IO'       | 'CAP CHIP 10UF 35V(+-10%,X6S,0805)'                            | 'CHIP0805'     | ''          | ''   | '20200410'
 '5600PF'   | '50V'   | '10%'     | 'C0402'     | 'X7R'     | 'CH2566K1B06'(!)   = ''              | ''                 | ''       | 'CH2566K1B06'     |'C0402'| '(C0402-0201)'                                                       | '5600PF'   | '50V'         | '10%'    | 'DISCRETE' | 'CAP CHIP 5600PF 50V(+-10%,X7R,0402)SAM'                       | 'CHIP0402'     | ''          | ''   | '20200410'
 '5600PF'   | '50V'   | '10%'     | 'C0402'     | 'EMPTY'   | 'CH2566K1B06'(!)   = ''              | ''                 | ''       | 'CH2566K1B06'     |'C0402'| '(C0402-0201)'                                                       | 'NA'       | '50V'         | '10%'    | 'IO'       | 'CAP CHIP 5600PF 50V(+-10%,X7R,0402)SAM'                       | 'CHIP0402'     | ''          | ''   | '20200410'
 '0.047UF'  | '50V'   | '10%'     | 'C0402'     | 'X7R'     | 'CH3476K1B10'(!)   = ''              | ''                 | ''       | 'CH3476K1B10'     |'C0402'| '(C0402-0201)'                                                       | '0.047UF'  | '50V'         | '10%'    | 'DISCRETE' | 'CAP CHIP 0.047UF 50V(+-10%,X7R,0402)MUR'                      | 'CHIP0402'     | ''          | ''   | '20200520'
 '0.047UF'  | '50V'   | '10%'     | 'C0402'     | 'EMPTY'   | 'CH3476K1B10'(!)   = ''              | ''                 | ''       | 'CH3476K1B10'     |'C0402'| '(C0402-0201)'                                                       | 'NA'       | '50V'         | '10%'    | 'IO'       | 'CAP CHIP 0.047UF 50V(+-10%,X7R,0402)MUR'                      | 'CHIP0402'     | ''          | ''   | '20200520'
 '0.022UF'  | '100V'  | '10%'     | 'C0805'     | 'X7R'     | 'CH3228K1A00'(!)   = 'End of Design' | 'Comp-Approve'     | ''       | 'CH3228K1A00'     |'C0805_H57'| '(SMC0805AW)'                                                        | '0.022UF'  | '100V'        | '10%'    | 'DISCRETE' | 'CAP CHIP 0.022UF 100V(+-10%,X7R,0805)SAM'                     | 'CHIP0805'     | ''          | ''   | '20200520'
 '0.022UF'  | '100V'  | '10%'     | 'C0805'     | 'EMPTY'   | 'CH3228K1A00'(!)   = 'End of Design' | 'Comp-Approve'     | ''       | 'CH3228K1A00'     |'C0805_H57'| '(SMC0805AW)'                                                        | 'NA'       | '100V'        | '10%'    | 'IO'       | 'CAP CHIP 0.022UF 100V(+-10%,X7R,0805)SAM'                     | 'CHIP0805'     | ''          | ''   | '20200520'
 '68NF'     | '50V'   | '10%'     | 'C0603'     | 'X7R'     | 'CH3686K1902'(!)   = ''              | ''                 | ''       | 'CH3686K1902'     |'C0603'| '(SMC0603AW)'                                                        | '68NF'     | '50V'         | '10%'    | 'DISCRETE' | 'CAP CHIP 68NF 50V(+-10%,X7R,0603)SAM'                         | 'CHIP0603'     | ''          | ''   | '20200527'
 '68NF'     | '50V'   | '10%'     | 'C0603'     | 'EMPTY'   | 'CH3686K1902'(!)   = ''              | ''                 | ''       | 'CH3686K1902'     |'C0603'| '(SMC0603AW)'                                                        | 'NA'       | '50V'         | '10%'    | 'IO'       | 'CAP CHIP 68NF 50V(+-10%,X7R,0603)SAM'                         | 'CHIP0603'     | ''          | ''   | '20200527'
 '0.01UF'   | '100V'  | '10%'     | 'C1206'     | 'X7R'     | 'CH3108K1200'(!)   = ''              | ''                 | ''       | 'CH3108K1200'     |'C1206XG_H38'| '(SMC1206AW)'                                                        | '0.01UF'   | '100V'        | '10%'    | 'DISCRETE' | 'CAP CHIP 0.01U 100V(+-10%,X7R,1206)MUR'                       | 'CHIP1206'     | ''          | ''   | '20200617'
 '0.01UF'   | '100V'  | '10%'     | 'C1206'     | 'EMPTY'   | 'CH3108K1200'(!)   = ''              | ''                 | ''       | 'CH3108K1200'     |'C1206XG_H38'| '(SMC1206AW)'                                                        | 'NA'       | '100V'        | '10%'    | 'IO'       | 'CAP CHIP 0.01U 100V(+-10%,X7R,1206)MUR'                       | 'CHIP1206'     | ''          | ''   | '20200617'
 '10UF'     | '4V'    | '20%'     | 'C0402'     | 'X6S'     | 'CH610KMEB09'(!)   = ''              | ''                 | ''       | 'CH610KMEB09'     |'C0402_H28'| '(C0402-0201_H28)'                                                   | '10UF'     | '4V'          | '20%'    | 'DISCRETE' | 'CAP CHIP 10U 4V(+-20%,X6S,0402)MUR'                           | 'CHIP0402'     | ''          | ''   | '20200807'
 '10UF'     | '4V'    | '20%'     | 'C0402'     | 'EMPTY'   | 'CH610KMEB09'(!)   = ''              | ''                 | ''       | 'CH610KMEB09'     |'C0402_H28'| '(C0402-0201_H28)'                                                   | 'NA'       | '4V'          | '20%'    | 'IO'       | 'CAP CHIP 10U 4V(+-20%,X6S,0402)MUR'                           | 'CHIP0402'     | ''          | ''   | '20200807'
 '4700PF'   | '50V'   | '5%'      | 'C0603'     | 'C0G'     | 'CH2476J0902'(!)   = ''              | ''                 | ''       | 'CH2476J0902'     |'C0603_H40'| '(SMC0603AW)'                                                        | '4700PF'   | '50V'         | '5%'     | 'DISCRETE' | 'CAP CHIP 4700P 50V(+-5%,C0G,0603)MUR'                         | 'CHIP0603'     | ''          | ''   | '20200813'
 '4700PF'   | '50V'   | '5%'      | 'C0603'     | 'EMPTY'   | 'CH2476J0902'(!)   = ''              | ''                 | ''       | 'CH2476J0902'     |'C0603_H40'| '(SMC0603AW)'                                                        | 'NA'       | '50V'         | '5%'     | 'IO'       | 'CAP CHIP 4700P 50V(+-5%,C0G,0603)MUR'                         | 'CHIP0603'     | ''          | ''   | '20200813'
 '6.8PF'    | '50V'   | '0.25PF'  | 'C0402'     | 'C0G'     | 'CH-686C0B04'(!)   = ''              | ''                 | ''       | 'CH-686C0B04'     |'C0402'| '(C0402-0201)'                                                       | '6.8PF'    | '50V'         | '0.25PF' | 'DISCRETE' | 'CAP CHIP 6.8P 50V(+-0.25P,C0G,0402)YGO'                       | 'CHIP0402'     | ''          | ''   | '20200824'
 '6.8PF'    | '50V'   | '0.25PF'  | 'C0402'     | 'EMPTY'   | 'CH-686C0B04'(!)   = ''              | ''                 | ''       | 'CH-686C0B04'     |'C0402'| '(C0402-0201)'                                                       | 'NA'       | '50V'         | '0.25PF' | 'IO'       | 'CAP CHIP 6.8P 50V(+-0.25P,C0G,0402)YGO'                       | 'CHIP0402'     | ''          | ''   | '20200824'
 '22NF'     | '100V'  | '10%'     | 'C0805'     | 'X7R'     | 'CH3228K1A02'(!)   = ''              | ''                 | ''       | 'CH3228K1A02'     |'C0805_H43'| '(SMC0805AW)'                                                        | '22NF'     | '100V'        | '10%'    | 'DISCRETE' | 'CAP CHIP 22N 100V(+-10%,X7R,0805)YGO'                         | 'CHIP0805'     | ''          | ''   | '20200824'
 '22NF'     | '100V'  | '10%'     | 'C0805'     | 'EMPTY'   | 'CH3228K1A02'(!)   = ''              | ''                 | ''       | 'CH3228K1A02'     |'C0805_H43'| '(SMC0805AW)'                                                        | 'NA'       | '100V'        | '10%'    | 'IO'       | 'CAP CHIP 22N 100V(+-10%,X7R,0805)YGO'                         | 'CHIP0805'     | ''          | ''   | '20200824'
 '2.2UF'    | '16V'   | '10%'     | 'C0402'     | 'X6S'     | 'CH5223KEB01'(!)   = ''              | ''                 | ''       | 'CH5223KEB01'     |'C0402_H28'| '(C0402-0201_H28)'                                                   | '2.2UF'    | '16V'         | '10%'    | 'DISCRETE' | 'CAP CHIP 2.2U 16V(+-10%,X6S,0402)'                            | 'CHIP0402'     | ''          | ''   | '20200903'
 '2.2UF'    | '16V'   | '10%'     | 'C0402'     | 'EMPTY'   | 'CH5223KEB01'(!)   = ''              | ''                 | ''       | 'CH5223KEB01'     |'C0402_H28'| '(C0402-0201_H28)'                                                   | 'NA'       | '16V'         | '10%'    | 'IO'       | 'CAP CHIP 2.2U 16V(+-10%,X6S,0402)'                            | 'CHIP0402'     | ''          | ''   | '20200903'
 '75PF'     | '50V'   | '5%'      | 'C0402'     | 'C0G'     | 'CH0756J0B00'(!)   = 'End of Design' | 'Comp-Approve'     | ''       | 'CH0756J0B00'     |'C0402'| '(C0402-0201)'                                                       | '75PF'     | '50V'         | '5%'     | 'DISCRETE' | 'CAP CHIP 75PF 50V(+-5%,C0G,0402)'                             | 'CHIP0402'     | ''          | ''   | '20200909'
 '75PF'     | '50V'   | '5%'      | 'C0402'     | 'EMPTY'   | 'CH0756J0B00'(!)   = 'End of Design' | 'Comp-Approve'     | ''       | 'CH0756J0B00'     |'C0402'| '(C0402-0201)'                                                       | 'NA'       | '50V'         | '5%'     | 'IO'       | 'CAP CHIP 75PF 50V(+-5%,C0G,0402)'                             | 'CHIP0402'     | ''          | ''   | '20200909'
 '150PF'    | '50V'   | '5%'      | 'C0402'     | 'C0G'     | 'CH1156J0B00'(!)   = ''              | ''                 | ''       | 'CH1156J0B00'     |'C0402'| '(C0402-0201)'                                                       | '150PF'    | '50V'         | '5%'     | 'DISCRETE' | 'CAP CHIP 150P 50V(+-5%,0402,C0G)'                             | 'CHIP0402'     | ''          | ''   | '20200909'
 '150PF'    | '50V'   | '5%'      | 'C0402'     | 'EMPTY'   | 'CH1156J0B00'(!)   = ''              | ''                 | ''       | 'CH1156J0B00'     |'C0402'| '(C0402-0201)'                                                       | 'NA'       | '50V'         | '5%'     | 'IO'       | 'CAP CHIP 150P 50V(+-5%,0402,C0G)'                             | 'CHIP0402'     | ''          | ''   | '20200909'
 '51PF'     | '50V'   | '5%'      | 'C0402'     | 'NPO'     | 'CH0516J0B07'(!)   = ''              | ''                 | ''       | 'CH0516J0B07'     |'C0402'| '(C0402-0201)'                                                       | '51PF'     | '50V'         | '5%'     | 'DISCRETE' | 'CAP CHIP 51P 50V+-5% NPO(0402)'                               | 'CHIP0402'     | ''          | ''   | '20200914'
 '51PF'     | '50V'   | '5%'      | 'C0402'     | 'EMPTY'   | 'CH0516J0B07'(!)   = ''              | ''                 | ''       | 'CH0516J0B07'     |'C0402'| '(C0402-0201)'                                                       | 'NA'       | '50V'         | '5%'     | 'IO'       | 'CAP CHIP 51P 50V+-5% NPO(0402)'                               | 'CHIP0402'     | ''          | ''   | '20200914'
 '18PF'     | '50V'   | '2%'      | 'C0402'     | 'NP0'     | 'CH0186G0B00'(!)   = ''              | ''                 | ''       | 'CH0186G0B00'     |'C0402'| '(C0402-0201)'                                                       | '18PF'     | '50V'         | '2%'     | 'DISCRETE' | 'CAP CHIP 18PF 50V(+-2%,NP0,0402)H0.55'                        | 'CHIP0402'     | ''          | ''   | '20200914'
 '18PF'     | '50V'   | '2%'      | 'C0402'     | 'EMPTY'   | 'CH0186G0B00'(!)   = ''              | ''                 | ''       | 'CH0186G0B00'     |'C0402'| '(C0402-0201)'                                                       | 'NA'       | '50V'         | '2%'     | 'IO'       | 'CAP CHIP 18PF 50V(+-2%,NP0,0402)H0.55'                        | 'CHIP0402'     | ''          | ''   | '20200914'
 '0.3PF'    | '50V'   | '0.05PF'  | 'C0402'     | 'C0G'     | 'CH+306T0B00'(!)   = ''              | ''                 | ''       | 'CH+306T0B00'     |'C0402'| '(C0402-0201)'                                                       | '0.3PF'    | '50V'         | '0.05PF' | 'DISCRETE' | 'CAP CHIP 0.3P 50V(+-0.05P,C0G,0402)'                          | 'CHIP0402'     | ''          | ''   | '20200916'
 '0.3PF'    | '50V'   | '0.05PF'  | 'C0402'     | 'EMPTY'   | 'CH+306T0B00'(!)   = ''              | ''                 | ''       | 'CH+306T0B00'     |'C0402'| '(C0402-0201)'                                                       | 'NA'       | '50V'         | '0.05PF' | 'IO'       | 'CAP CHIP 0.3P 50V(+-0.05P,C0G,0402)'                          | 'CHIP0402'     | ''          | ''   | '20200916'
 '6.8PF'    | '50V'   | '0.5PF'   | 'C0603'     | 'NPO'     | 'CH-6806T901'(!)   = ''              | ''                 | ''       | 'CH-6806T901'     |'C0603'| '(SMC0603AW)'                                                        | '6.8PF'    | '50V'         | '0.5PF'  | 'DISCRETE' | 'CAP CHIP 6.8P 50V(+-0.5P 0603 NPO)'                           | 'CHIP0603'     | ''          | ''   | '20200916'
 '6.8PF'    | '50V'   | '0.5PF'   | 'C0603'     | 'EMPTY'   | 'CH-6806T901'(!)   = ''              | ''                 | ''       | 'CH-6806T901'     |'C0603'| '(SMC0603AW)'                                                        | 'NA'       | '50V'         | '0.5PF'  | 'IO'       | 'CAP CHIP 6.8P 50V(+-0.5P 0603 NPO)'                           | 'CHIP0603'     | ''          | ''   | '20200916'
 '0.2PF'    | '50V'   | '0.05PF'  | 'C0402'     | 'C0G'     | 'CH+206T0B00'(!)   = ''              | ''                 | ''       | 'CH+206T0B00'     |'C0402'| '(C0402-0201)'                                                       | '0.2PF'    | '50V'         | '0.05PF' | 'DISCRETE' | 'CAP CHIP 0.2P 50V(+-0.05P,C0G,0402)'                          | 'CHIP0402'     | ''          | ''   | '20200916'
 '0.2PF'    | '50V'   | '0.05PF'  | 'C0402'     | 'EMPTY'   | 'CH+206T0B00'(!)   = ''              | ''                 | ''       | 'CH+206T0B00'     |'C0402'| '(C0402-0201)'                                                       | 'NA'       | '50V'         | '0.05PF' | 'IO'       | 'CAP CHIP 0.2P 50V(+-0.05P,C0G,0402)'                          | 'CHIP0402'     | ''          | ''   | '20200916'
 '4.7UF'    | '25V'   | '10%'     | 'C0805'     | 'X5R'     | 'CH5474K9A01'(!)   = 'End of Design' | 'Comp-Release Qty' | ''       | 'CH5474K9A01'     |'C0805_H57'| '(SMC0805AW)'                                                        | '4.7UF'    | '25V'         | '10%'    | 'DISCRETE' | 'CAPACITOR CHIP 4.7U 25V(+-10% X5R 0805)'                      | 'CHIP0805'     | ''          | ''   | '20200916'
 '4.7UF'    | '25V'   | '10%'     | 'C0805'     | 'EMPTY'   | 'CH5474K9A01'(!)   = 'End of Design' | 'Comp-Release Qty' | ''       | 'CH5474K9A01'     |'C0805_H57'| '(SMC0805AW)'                                                        | 'NA'       | '100V'        | '10%'    | 'IO'       | 'CAPACITOR CHIP 4.7U 25V(+-10% X5R 0805)'                      | 'CHIP0805'     | ''          | ''   | '20200916'
 '0.5PF'    | '50V'   | '0.1PF'   | 'C0402'     | 'NPO'     | 'CH+5016TB01'(!)   = ''              | ''                 | ''       | 'CH+5016TB01'     |'C0402'| '(C0402-0201)'                                                       | '0.5PF'    | '50V'         | '0.1PF'  | 'DISCRETE' | 'CAP CHIP 0.5P 50V(+-0.1P,NPO,0402)'                           | 'CHIP0402'     | ''          | ''   | '20200918'
 '0.5PF'    | '50V'   | '0.1PF'   | 'C0402'     | 'EMPTY'   | 'CH+5016TB01'(!)   = ''              | ''                 | ''       | 'CH+5016TB01'     |'C0402'| '(C0402-0201)'                                                       | 'NA'       | '50V'         | '0.1PF'  | 'IO'       | 'CAP CHIP 0.5P 50V(+-0.1P,NPO,0402)'                           | 'CHIP0402'     | ''          | ''   | '20200918'
 '47UF'     | '25V'   | '20%'     | 'C1206'     | 'X5R'     | 'CH6474M9200'(!)   = 'End of Design' | 'Comp-Approve'     | ''       | 'CH6474M9200'     |'C1206XH'| '(SMC1206AW)'                                                        | '47UF'     | '25V'         | '20%'    | 'DISCRETE' | 'CAP CHIP 47U 25V(+-20%,X5R,1206)'                             | 'CHIP1206'     | ''          | ''   | '20200921'
 '47UF'     | '25V'   | '20%'     | 'C1206'     | 'EMPTY'   | 'CH6474M9200'(!)   = 'End of Design' | 'Comp-Approve'     | ''       | 'CH6474M9200'     |'C1206XH'| '(SMC1206AW)'                                                        | 'NA'       | '25V'         | '20%'    | 'IO'       | 'CAP CHIP 47U 25V(+-20%,X5R,1206)'                             | 'CHIP1206'     | ''          | ''   | '20200921'
 '10UF'     | '50V'   | '10%'     | 'C1206'     | 'X5R'     | 'CH6106K9201'(!)   = 'End of Design' | 'Comp-Release Qty' | ''       | 'CH6106K9201'     |'C1206XI'| '(SMC1206AW)'                                                        | '10UF'     | '50V'         | '10%'    | 'DISCRETE' | 'CAP CHIP 10UF 50V(+-10%,X5R,1206)'                            | 'CHIP1206'     | ''          | ''   | '20200923'
 '10UF'     | '50V'   | '10%'     | 'C1206'     | 'EMPTY'   | 'CH6106K9201'(!)   = 'End of Design' | 'Comp-Release Qty' | ''       | 'CH6106K9201'     |'C1206XI'| '(SMC1206AW)'                                                        | 'NA'       | '50V'         | '10%'    | 'IO'       | 'CAP CHIP 10UF 50V(+-10%,X5R,1206)'                            | 'CHIP1206'     | ''          | ''   | '20200923'
 '100UF'    | '10V'   | '20%'     | 'C1210'     | 'X5R'     | 'CH7102M9300'(!)   = 'End of Design' | 'Comp-Approve'     | ''       | 'CH7102M9300'     |'C1210_CL32A'| '(SMC1210AW)'                                                        | '100UF'    | '10V'         | '20%'    | 'DISCRETE' | 'CAP CHIP 100U 10V(+-20%,X5R,1210)H2.5'                        | 'CHIP1210'     | ''          | ''   | '20200923'
 '100UF'    | '10V'   | '20%'     | 'C1210'     | 'EMPTY'   | 'CH7102M9300'(!)   = 'End of Design' | 'Comp-Approve'     | ''       | 'CH7102M9300'     |'C1210_CL32A'| '(SMC1210AW)'                                                        | 'NA'       | '10V'         | '20%'    | 'IO'       | 'CAP CHIP 100U 10V(+-20%,X5R,1210)H2.5'                        | 'CHIP1210'     | ''          | ''   | '20200923'
 '4.7UF'    | '100V'  | '10%'     | 'C1206'     | 'X7S'     | 'CH5478K6201'(!)   = 'End of Design' | 'Comp-Approve'     | ''       | 'CH5478K6201'     |'C1206XB'| '(SMC1206AW)'                                                        | '4.7UF'    | '100V'        | '10%'    | 'DISCRETE' | 'CAP CHIP 4.7U 100V(10%,X7S,1206)'                             | 'CHIP1206'     | ''          | ''   | '20200925'
 '4.7UF'    | '100V'  | '10%'     | 'C1206'     | 'EMPTY'   | 'CH5478K6201'(!)   = 'End of Design' | 'Comp-Approve'     | ''       | 'CH5478K6201'     |'C1206XB'| '(SMC1206AW)'                                                        | 'NA'       | '100V'        | '10%'    | 'IO'       | 'CAP CHIP 4.7U 100V(10%,X7S,1206)'                             | 'CHIP1206'     | ''          | ''   | '20200925'
 '47UF'     | '6.3V'  | '20%'     | 'C0805'     | 'X6S'     | 'CH6471MEA02'(!)   = ''              | ''                 | ''       | 'CH6471MEA02'     |'C0805_H57'| '(C0805_BHS)'                                                        | '47UF'     | '6.3V'        | '20%'    | 'DISCRETE' | 'CAP CHIP 47U 6.3V(+-20%,X6S,0805)'                            | 'CHIP0805'     | ''          | ''   | '20200930'
 '47UF'     | '6.3V'  | '20%'     | 'C0805'     | 'EMPTY'   | 'CH6471MEA02'(!)   = ''              | ''                 | ''       | 'CH6471MEA02'     |'C0805_H57'| '(C0805_BHS)'                                                        | 'NA'       | '6.3V'        | '20%'    | 'IO'       | 'CAP CHIP 47U 6.3V(+-20%,X6S,0805)'                            | 'CHIP0805'     | ''          | ''   | '20200930'
 '4.7UF'    | '100V'  | '10%'     | 'C1206'     | 'X7R'     | 'CH5478K1201'(!)   = 'End of Design' | 'Comp-Approve'     | ''       | 'CH5478K1201'     |'C1206XB'| '(SMC1206AW)'                                                        | '4.7UF'    | '100V'        | '10%'    | 'DISCRETE' | 'CAP CHIP 4.7UF 100V(+-10%,X7R,1206)'                          | 'CHIP1206'     | ''          | ''   | '20201026'
 '4.7UF'    | '100V'  | '10%'     | 'C1206'     | 'EMPTY'   | 'CH5478K1201'(!)   = 'End of Design' | 'Comp-Approve'     | ''       | 'CH5478K1201'     |'C1206XB'| '(SMC1206AW)'                                                        | 'NA'       | '100V'        | '10%'    | 'IO'       | 'CAP CHIP 4.7UF 100V(+-10%,X7R,1206)'                          | 'CHIP1206'     | ''          | ''   | '20201026'
 '0.1UF'    | '25V'   | '10%'     | 'C0402'     | 'X7R'     | 'CH4104K1B13'(!)   = ''              | ''                 | ''       | 'CH4104K1B13'     |'C0402'| '(C0402-0201)'                                                       | '0.1UF'    | '25V'         | '10%'    | 'DISCRETE' | 'CAP CHIP 0.1U 25V(+-10%,X7R,0402)YGO'                         | 'CHIP0402'     | ''          | ''   | '20201223'
 '0.1UF'    | '25V'   | '10%'     | 'C0402'     | 'EMPTY'   | 'CH4104K1B13'(!)   = ''              | ''                 | ''       | 'CH4104K1B13'     |'C0402'| '(C0402-0201)'                                                       | 'NA'       | '25V'         | '10%'    | 'IO'       | 'CAP CHIP 0.1U 25V(+-10%,X7R,0402)YGO'                         | 'CHIP0402'     | ''          | ''   | '20201223'
 '33PF'     | '50V'   | '5%'      | 'C0402'     | 'NPO'     | 'CH0336J0B19'(!)   = ''              | ''                 | ''       | 'CH0336J0B19'     |'C0402'| '(C0402-0201)'                                                       | '33PF'     | '50V'         | '5%'     | 'DISCRETE' | 'CAP CHIP 33P 50V(+-5%,NPO,0402)YGO'                           | 'CHIP0402'     | ''          | ''   | '20201223'
 '33PF'     | '50V'   | '5%'      | 'C0402'     | 'EMPTY'   | 'CH0336J0B19'(!)   = ''              | ''                 | ''       | 'CH0336J0B19'     |'C0402'| '(C0402-0201)'                                                       | 'NA'       | '50V'         | '5%'     | 'IO'       | 'CAP CHIP 33P 50V(+-5%,NPO,0402)YGO'                           | 'CHIP0402'     | ''          | ''   | '20201223'
 '220PF'    | '50V'   | '5%'      | 'C0402'     | 'C0G'     | 'CH1226J0B04'(!)   = ''              | ''                 | ''       | 'CH1226J0B04'     |'C0402'| '(C0402-0201)'                                                       | '220PF'    | '50V'         | '5%'     | 'DISCRETE' | 'CAP CHIP 220P 50V(+-5%,C0G,0402)SAM'                          | 'CHIP0402'     | ''          | ''   | '20201223'
 '220PF'    | '50V'   | '5%'      | 'C0402'     | 'EMPTY'   | 'CH1226J0B04'(!)   = ''              | ''                 | ''       | 'CH1226J0B04'     |'C0402'| '(C0402-0201)'                                                       | 'NA'       | '50V'         | '5%'     | 'IO'       | 'CAP CHIP 220P 50V(+-5%,C0G,0402)SAM'                          | 'CHIP0402'     | ''          | ''   | '20201223'
 '0.01UF'   | '50V'   | '10%'     | 'C0603'     | 'X7R'     | 'CH3106K1921'(!)   = ''              | ''                 | ''       | 'CH3106K1921'     |'C0603'| '(SMC0603AW)'                                                        | '0.01UF'   | '50V'         | '10%'    | 'DISCRETE' | 'CAP CHIP 0.01U 50V(+-10%,X7R,0603)YGO'                        | 'CHIP0603'     | ''          | ''   | '20201223'
 '0.01UF'   | '50V'   | '10%'     | 'C0603'     | 'EMPTY'   | 'CH3106K1921'(!)   = ''              | ''                 | ''       | 'CH3106K1921'     |'C0603'| '(SMC0603AW)'                                                        | 'NA'       | '50V'         | '10%'    | 'IO'       | 'CAP CHIP 0.01U 50V(+-10%,X7R,0603)YGO'                        | 'CHIP0603'     | ''          | ''   | '20201223'
 '0.2PF'    | '50V'   | '0.1PF'   | 'C0603'     | 'NPO'     | 'CH+206B0900'(!)   = ''              | ''                 | ''       | 'CH+206B0900'     |'C0603'| '(SMC0603AW)'                                                        | '0.2PF'    | '50V'         | '0.1PF'  | 'DISCRETE' | 'CAP CHIP 0.2PF 50V(+-0.1P,NPO,0603)HQ'                        | 'CHIP0603'     | ''          | ''   | '20201223'
 '0.2PF'    | '50V'   | '0.1PF'   | 'C0603'     | 'EMPTY'   | 'CH+206B0900'(!)   = ''              | ''                 | ''       | 'CH+206B0900'     |'C0603'| '(SMC0603AW)'                                                        | 'NA'       | '50V'         | '0.1PF'  | 'IO'       | 'CAP CHIP 0.2PF 50V(+-0.1P,NPO,0603)HQ'                        | 'CHIP0603'     | ''          | ''   | '20201223'
 '5.6PF'    | '50V'   | '0.5PF'   | 'C0402'     | 'NPO'     | 'CH-566D0B01'(!)   = ''              | ''                 | ''       | 'CH-566D0B01'     |'C0402'| '(C0402-0201)'                                                       | '5.6PF'    | '50V'         | '0.5PF'  | 'DISCRETE' | 'CAP CHIP 5.6P 50V(+-0.5P,NPO,0402)'                           | 'CHIP0402'     | ''          | ''   | '20210126'
 '5.6PF'    | '50V'   | '0.5PF'   | 'C0402'     | 'EMPTY'   | 'CH-566D0B01'(!)   = ''              | ''                 | ''       | 'CH-566D0B01'     |'C0402'| '(C0402-0201)'                                                       | 'NA'       | '50V'         | '0.5PF'  | 'IO'       | 'CAP CHIP 5.6P 50V(+-0.5P,NPO,0402)'                           | 'CHIP0402'     | ''          | ''   | '20210126'
 '100UF'    | '6.3V'  | '20%'     | 'C1210'     | 'X6S'     | 'CH7101ME301'(!)   = ''              | ''                 | ''       | 'CH7101ME301'     |'C1210_CL32X'| '(SMC1210AW)'                                                        | '100UF'    | '6.3V'        | '20%'    | 'DISCRETE' | 'CAP CHIP 100U 6.3V(+-20%,X6S,1210)'                           | 'CHIP1210'     | ''          | ''   | '20210325'
 '100UF'    | '6.3V'  | '20%'     | 'C1210'     | 'EMPTY'   | 'CH7101ME301'(!)   = ''              | ''                 | ''       | 'CH7101ME301'     |'C1210_CL32X'| '(SMC1210AW)'                                                        | 'NA'       | '6.3V'        | '20%'    | 'IO'       | 'CAP CHIP 100U 6.3V(+-20%,X6S,1210)'                           | 'CHIP1210'     | ''          | ''   | '20210325'
 '330UF'    | '2.5V'  | '20%'     | 'C1210'     | 'X6S'     | 'CH733LME301'(!)   = ''              | ''                 | ''       | 'CH733LME301'     |'C1210_GRM32EXA'| '(SMC1210AW)'                                                        | '330UF'    | '2.5V'        | '20%'    | 'DISCRETE' | 'CAP CHIP 330UF 2.5V(+-20%,X6S,1210)'                          | 'CHIP1210'     | ''          | ''   | '20210407'
 '330UF'    | '2.5V'  | '20%'     | 'C1210'     | 'EMPTY'   | 'CH733LME301'(!)   = ''              | ''                 | ''       | 'CH733LME301'     |'C1210_GRM32EXA'| '(SMC1210AW)'                                                        | 'NA'       | '2.5V'        | '20%'    | 'IO'       | 'CAP CHIP 330UF 2.5V(+-20%,X6S,1210)'                          | 'CHIP1210'     | ''          | ''   | '20210407'
 '10UF'     | '4V'    | '20%'     | 'C0402'     | 'X6S'     | 'CH610KMEB10'(!)   = ''              | ''                 | ''       | 'CH610KMEB10'     |'C0402_H28'| '(C0402-0201_H28)'                                                   | '10UF'     | '4V'          | '20%'    | 'DISCRETE' | 'CAP CHIP 10U 4V(+-20%,X6S,0402)'                              | 'CHIP0402'     | ''          | ''   | '20210426'
 '10UF'     | '4V'    | '20%'     | 'C0402'     | 'EMPTY'   | 'CH610KMEB10'(!)   = ''              | ''                 | ''       | 'CH610KMEB10'     |'C0402_H28'| '(C0402-0201_H28)'                                                   | 'NA'       | '4V'          | '20%'    | 'IO'       | 'CAP CHIP 10U 4V(+-20%,X6S,0402)'                              | 'CHIP0402'     | ''          | ''   | '20210426'
 '220UF'    | '4V'    | '20%'     | 'C1206'     | 'X6S'     | 'CH722KME201'(!)   = ''              | ''                 | ''       | 'CH722KME201'     |'C1206XB'| '(SMC1206AW)'                                                        | '220UF'    | '4V'          | '20%'    | 'DISCRETE' | 'CAP CHIP 220U 4V(+-20%,X6S,1206)MUR'                          | 'CHIP1206'     | ''          | ''   | '20210426'
 '220UF'    | '4V'    | '20%'     | 'C1206'     | 'EMPTY'   | 'CH722KME201'(!)   = ''              | ''                 | ''       | 'CH722KME201'     |'C1206XB'| '(SMC1206AW)'                                                        | 'NA'       | '4V'          | '20%'    | 'IO'       | 'CAP CHIP 220U 4V(+-20%,X6S,1206)MUR'                          | 'CHIP1206'     | ''          | ''   | '20210426'
 '2.2UF'    | '6.3V'  | '20%'     | 'C0201'     | 'X5R'     | 'CH5221M9E07'(!)   = ''              | ''                 | ''       | 'CH5221M9E07'     |'C0201_H16'| '(C0201_HOME-PLATE_H22)'                                             | '2.2UF'    | '6.3V'        | '20%'    | 'DISCRETE' | 'CAP CHIP 2.2UF 6.3V(+-20%,X5R,0201)SAM'                       | 'CHIP0201'     | ''          | ''   | '20210429'
 '2.2UF'    | '6.3V'  | '20%'     | 'C0201'     | 'EMPTY'   | 'CH5221M9E07'(!)   = ''              | ''                 | ''       | 'CH5221M9E07'     |'C0201_H16'| '(C0201_HOME-PLATE_H22)'                                             | 'NA'       | '6.3V'        | '20%'    | 'IO'       | 'CAP CHIP 2.2UF 6.3V(+-20%,X5R,0201)SAM'                       | 'CHIP0201'     | ''          | ''   | '20210429'
 '10UF'     | '6.3V'  | '20%'     | 'C0402'     | 'X6S'     | 'CH6101MEB08'(!)   = ''              | ''                 | ''       | 'CH6101MEB08'     |'C0402_H28'| '(C0402-0201_H28)'                                                   | '10UF'     | '6.3V'        | '20%'    | 'DISCRETE' | 'CAP CHIP 10UF 6.3V(+-20%,X6S,0402)SAM'                        | 'CHIP0402'     | ''          | ''   | '20210506'
 '10UF'     | '6.3V'  | '20%'     | 'C0402'     | 'EMPTY'   | 'CH6101MEB08'(!)   = ''              | ''                 | ''       | 'CH6101MEB08'     |'C0402_H28'| '(C0402-0201_H28)'                                                   | 'NA'       | '6.3V'        | '20%'    | 'IO'       | 'CAP CHIP 10UF 6.3V(+-20%,X6S,0402)SAM'                        | 'CHIP0402'     | ''          | ''   | '20210506'
 '2.2UF'    | '6.3V'  | '20%'     | 'C0201'     | 'X5R'     | 'CH5221M9E00'(!)   = ''              | ''                 | ''       | 'CH5221M9E00'     |'C0201_H16'| '(SMC0201AW)'                                                        | '2.2UF'    | '6.3V'        | '20%'    | 'DISCRETE' | 'CAP CHIP 2.2UF 6.3V(+-20%,X5R,0201)'                          | 'CHIP0201'     | ''          | ''   | '20210507'
 '2.2UF'    | '6.3V'  | '20%'     | 'C0201'     | 'EMPTY'   | 'CH5221M9E00'(!)   = ''              | ''                 | ''       | 'CH5221M9E00'     |'C0201_H16'| '(SMC0201AW)'                                                        | 'NA'       | '6.3V'        | '20%'    | 'IO'       | 'CAP CHIP 2.2UF 6.3V(+-20%,X5R,0201)'                          | 'CHIP0201'     | ''          | ''   | '20210507'
 '10UF'     | '25V'   | '20%'     | 'C0805'     | 'X7S'     | 'CH6104M6A00'(!)   = ''              | ''                 | ''       | 'CH6104M6A00'     |'C0805_H57'| '(SMC0805AW)'                                                        | '10UF'     | '25V'         | '20%'    | 'DISCRETE' | 'CAP CHIP 10UF 25V(+-20%,X7S,0805)'                            | 'CHIP0805'     | ''          | ''   | '20210525'
 '10UF'     | '25V'   | '20%'     | 'C0805'     | 'EMPTY'   | 'CH6104M6A00'(!)   = ''              | ''                 | ''       | 'CH6104M6A00'     |'C0805_H57'| '(SMC0805AW)'                                                        | 'NA'       | '25V'         | '20%'    | 'IO'       | 'CAP CHIP 10UF 25V(+-20%,X7S,0805)'                            | 'CHIP0805'     | ''          | ''   | '20210525'
 '4.7UF'    | '25V'   | '10%'     | 'C0805'     | 'X7S'     | 'CH5474K6A01'(!)   = ''              | ''                 | ''       | 'CH5474K6A01'     |'C0805_H43'| '(SMC0805AW)'                                                        | '4.7UF'    | '25V'         | '10%'    | 'DISCRETE' | 'CAP CHIP 4.7U 25V(10%,X7S,0805)MUR'                           | 'CHIP0805'     | ''          | ''   | '20210525'
 '4.7UF'    | '25V'   | '10%'     | 'C0805'     | 'EMPTY'   | 'CH5474K6A01'(!)   = ''              | ''                 | ''       | 'CH5474K6A01'     |'C0805_H43'| '(SMC0805AW)'                                                        | 'NA'       | '25V'         | '10%'    | 'IO'       | 'CAP CHIP 4.7U 25V(10%,X7S,0805)MUR'                           | 'CHIP0805'     | ''          | ''   | '20210525'
 '0.027UF'  | '16V'   | '10%'     | 'C0402'     | 'X7R'     | 'CH3273K1B00'(!)   = ''              | ''                 | ''       | 'CH3273K1B00'     |'C0402'| '(C0402-0201)'                                                       | '0.027UF'  | '16V'         | '10%'    | 'DISCRETE' | 'CAP CHIP 0.027UF 16V(+-10%, X7R,0402)'                        | 'CHIP0402'     | ''          | ''   | '20210526'
 '0.027UF'  | '16V'   | '10%'     | 'C0402'     | 'EMPTY'   | 'CH3273K1B00'(!)   = ''              | ''                 | ''       | 'CH3273K1B00'     |'C0402'| '(C0402-0201)'                                                       | 'NA'       | '16V'         | '10%'    | 'IO'       | 'CAP CHIP 0.027UF 16V(+-10%, X7R,0402)'                        | 'CHIP0402'     | ''          | ''   | '20210526'
 '4700PF'   | '25V'   | '10%'     | 'C0201'     | 'X7R'     | 'CH2474K1E00'(!)   = ''              | ''                 | ''       | 'CH2474K1E00'     |'C0201'| '(SMC0201AW)'                                                        | '4700PF'   | '25V'         | '10%'    | 'DISCRETE' | 'CAP CHIP 4700P 25V(+-10%,X7R,0201)'                           | 'CHIP0201'     | ''          | ''   | '20210526'
 '4700PF'   | '25V'   | '10%'     | 'C0201'     | 'EMPTY'   | 'CH2474K1E00'(!)   = ''              | ''                 | ''       | 'CH2474K1E00'     |'C0201'| '(SMC0201AW)'                                                        | 'NA'       | '25V'         | '10%'    | 'IO'       | 'CAP CHIP 4700P 25V(+-10%,X7R,0201)'                           | 'CHIP0201'     | ''          | ''   | '20210526'
 '1UF'      | '10V'   | '20%'     | 'C0201'     | 'X6S'     | 'CH5102MEE02'(!)   = ''              | ''                 | ''       | 'CH5102MEE02'     |'C0201_H16'| '(SMC0201AW)'                                                        | '1UF'      | '10V'         | '20%'    | 'DISCRETE' | 'CAP CHIP 1UF 10V(20%,X6S,0201)'                               | 'CHIP0201'     | ''          | ''   | '20210531'
 '1UF'      | '10V'   | '20%'     | 'C0201'     | 'EMPTY'   | 'CH5102MEE02'(!)   = ''              | ''                 | ''       | 'CH5102MEE02'     |'C0201_H16'| '(SMC0201AW)'                                                        | 'NA'       | '10V'         | '20%'    | 'IO'       | 'CAP CHIP 1UF 10V(20%,X6S,0201)'                               | 'CHIP0201'     | ''          | ''   | '20210531'
 '4.7UF'    | '50V'   | '10%'     | 'C1206'     | 'X7R'     | 'CH5476K1207'(!)   = 'End of Design' | 'Comp-Approve'     | ''       | 'CH5476K1207'     |'C1206XG_H71'| '(SMC1206AW)'                                                        | '4.7UF'    | '50V'         | '10%'    | 'DISCRETE' | 'CAP CHIP 4.7U 50V(+-10%, X7R,1206,H1.6)'                      | 'CHIP1206'     | ''          | ''   | '20210609'
 '4.7UF'    | '50V'   | '10%'     | 'C1206'     | 'EMPTY'   | 'CH5476K1207'(!)   = 'End of Design' | 'Comp-Approve'     | ''       | 'CH5476K1207'     |'C1206XG_H71'| '(SMC1206AW)'                                                        | 'NA'       | '50V'         | '10%'    | 'IO'       | 'CAP CHIP 4.7U 50V(+-10%, X7R,1206,H1.6)'                      | 'CHIP1206'     | ''          | ''   | '20210609'
 '100UF'    | '6.3V'  | '20%'     | 'C1206'     | 'X6S'     | 'CH7101ME200'(!)   = 'End of Design' | 'Comp-Release Qty' | ''       | 'CH7101ME200'     |'C1206XE'| '(SMC1206AW)'                                                        | '100UF'    | '6.3V'        | '20%'    | 'DISCRETE' | 'CAP CHIP 100UF 6.3V(+-20%,X6S,1206)'                          | 'CHIP1206'     | ''          | ''   | '20210609'
 '100UF'    | '6.3V'  | '20%'     | 'C1206'     | 'EMPTY'   | 'CH7101ME200'(!)   = 'End of Design' | 'Comp-Release Qty' | ''       | 'CH7101ME200'     |'C1206XE'| '(SMC1206AW)'                                                        | 'NA'       | '6.3V'        | '20%'    | 'IO'       | 'CAP CHIP 100UF 6.3V(+-20%,X6S,1206)'                          | 'CHIP1206'     | ''          | ''   | '20210609'
 '200PF'    | '50V'   | '5%'      | 'C0402'     | 'NPO'     | 'CH1206J0B00'(!)   = 'End of Design' | 'Comp-Approve'     | ''       | 'CH1206J0B00'     |'C0402'| '(C0402-0201)'                                                       | '200PF'    | '50V'         | '5%'     | 'DISCRETE' | 'CAP CHIP 200P 50V(+-5%,NPO,0402)'                             | 'CHIP0402'     | ''          | ''   | '20210616'
 '200PF'    | '50V'   | '5%'      | 'C0402'     | 'EMPTY'   | 'CH1206J0B00'(!)   = 'End of Design' | 'Comp-Approve'     | ''       | 'CH1206J0B00'     |'C0402'| '(C0402-0201)'                                                       | 'NA'       | '50V'         | '5%'     | 'IO'       | 'CAP CHIP 200P 50V(+-5%,NPO,0402)'                             | 'CHIP0402'     | ''          | ''   | '20210616'
 '0.01UF'   | '50V'   | '10%'     | 'C0402'     | 'X7R'     | 'CH3106K1B10'(!)   = ''              | ''                 | ''       | 'CH3106K1B10'     |'C0402'| '(C0402-0201)'                                                       | '0.01UF'   | '50V'         | '10%'    | 'DISCRETE' | 'CAP CHIP 0.01U 50V(+-10%,X7R,0402)MUR'                        | 'CHIP0402'     | ''          | ''   | '20210727'
 '0.01UF'   | '50V'   | '10%'     | 'C0402'     | 'EMPTY'   | 'CH3106K1B10'(!)   = ''              | ''                 | ''       | 'CH3106K1B10'     |'C0402'| '(C0402-0201)'                                                       | 'NA'       | '50V'         | '10%'    | 'IO'       | 'CAP CHIP 0.01U 50V(+-10%,X7R,0402)MUR'                        | 'CHIP0402'     | ''          | ''   | '20210727'
 '0.3PF'    | '50V'   | '0.1PF'   | 'C0603'     | 'NPO'     | 'CH+306B0900'(!)   = ''              | ''                 | ''       | 'CH+306B0900'     |'C0603'| '(SMC0603AW)'                                                        | '0.3PF'    | '50V'         | '0.1PF'  | 'DISCRETE' | 'CAP CHIP 0.3PF 50V(+-0.1P,NPO,0603)HQ'                        | 'CHIP0603'     | ''          | ''   | '20210809'
 '0.3PF'    | '50V'   | '0.1PF'   | 'C0603'     | 'EMPTY'   | 'CH+306B0900'(!)   = ''              | ''                 | ''       | 'CH+306B0900'     |'C0603'| '(SMC0603AW)'                                                        | 'NA'       | '50V'         | '0.1PF'  | 'IO'       | 'CAP CHIP 0.3PF 50V(+-0.1P,NPO,0603)HQ'                        | 'CHIP0603'     | ''          | ''   | '20210809'
 '0.1UF'    | '50V'   | '10%'     | 'C0603'     | 'X7R'     | 'CH4106K1912'(!)   = 'End of Design' | 'Comp-Approve'     | ''       | 'CH4106K1912'     |'C0603'| '(SMC0603AW)'                                                        | '0.1UF'    | '50V'         | '10%'    | 'DISCRETE' | 'CAP CHIP 0.1U 50V(+-10%,X7R,0603)SAM'                         | 'CHIP0603'     | ''          | ''   | '20210812'
 '0.1UF'    | '50V'   | '10%'     | 'C0603'     | 'EMPTY'   | 'CH4106K1912'(!)   = 'End of Design' | 'Comp-Approve'     | ''       | 'CH4106K1912'     |'C0603'| '(SMC0603AW)'                                                        | 'NA'       | '50V'         | '10%'    | 'IO'       | 'CAP CHIP 0.1U 50V(+-10%,X7R,0603)SAM'                         | 'CHIP0603'     | ''          | ''   | '20210812'
 '47PF'     | '50V'   | '1%'      | 'C0402'     | 'NPO'     | 'CH0476F0B00'(!)   = ''              | ''                 | ''       | 'CH0476F0B00'     |'C0402'| '(C0402-0201)'                                                       | '47PF'     | '50V'         | '1%'     | 'DISCRETE' | 'CAP CHIP 47P 50V(+-1%,NPO,0402)'                              | 'CHIP0402'     | ''          | ''   | '20210817'
 '47PF'     | '50V'   | '1%'      | 'C0402'     | 'EMPTY'   | 'CH0476F0B00'(!)   = ''              | ''                 | ''       | 'CH0476F0B00'     |'C0402'| '(C0402-0201)'                                                       | 'NA'       | '50V'         | '1%'     | 'IO'       | 'CAP CHIP 47P 50V(+-1%,NPO,0402)'                              | 'CHIP0402'     | ''          | ''   | '20210817'
 '1000PF'   | '100V'  | '10%'     | 'C0402'     | 'X7R'     | 'CH2108K1B00'(!)   = ''              | ''                 | ''       | 'CH2108K1B00'     |'C0402'| '(C0402-0201)'                                                       | '1000PF'   | '100V'        | '10%'    | 'DISCRETE' | 'CAP CHIP 1000P 100V(+-10%,X7R,0402)'                          | 'CHIP0402'     | ''          | ''   | '20210817'
 '1000PF'   | '100V'  | '10%'     | 'C0402'     | 'EMPTY'   | 'CH2108K1B00'(!)   = ''              | ''                 | ''       | 'CH2108K1B00'     |'C0402'| '(C0402-0201)'                                                       | 'NA'       | '100V'        | '10%'    | 'IO'       | 'CAP CHIP 1000P 100V(+-10%,X7R,0402)'                          | 'CHIP0402'     | ''          | ''   | '20210817'
 '0.1UF'    | '1KV'   | '10%'     | 'C2220'     | 'X7R'     | 'CH410FK1F00'(!)   = ''              | ''                 | ''       | 'CH410FK1F00'     |'C2220XB'| '(SMC2220AW)'                                                        | '0.1UF'    | '1KV'         | '10%'    | 'DISCRETE' | 'CAP CHIP 0.1U 1KV(+-10%,X7R,2220)H2.5'                        | 'CHIP2220'     | ''          | ''   | '20210823'
 '0.1UF'    | '1KV'   | '10%'     | 'C2220'     | 'EMPTY'   | 'CH410FK1F00'(!)   = ''              | ''                 | ''       | 'CH410FK1F00'     |'C2220XB'| '(SMC2220AW)'                                                        | 'NA'       | '1KV'         | '10%'    | 'IO'       | 'CAP CHIP 0.1U 1KV(+-10%,X7R,2220)H2.5'                        | 'CHIP2220'     | ''          | ''   | '20210823'
 '0.033UF'  | '100V'  | '10%'     | 'C0805'     | 'X7R'     | 'CH3338K1A00'(!)   = ''              | ''                 | ''       | 'CH3338K1A00'     |'C0805_H57'| '(SMC0805AW)'                                                        | '0.033UF'  | '100V'        | '10%'    | 'DISCRETE' | 'CAP CHIP 0.033U 100V(+-10%,X7R,0805)'                         | 'CHIP0805'     | ''          | ''   | '20210827'
 '0.033UF'  | '100V'  | '10%'     | 'C0805'     | 'EMPTY'   | 'CH3338K1A00'(!)   = ''              | ''                 | ''       | 'CH3338K1A00'     |'C0805_H57'| '(SMC0805AW)'                                                        | 'NA'       | '100V'        | '10%'    | 'IO'       | 'CAP CHIP 0.033U 100V(+-10%,X7R,0805)'                         | 'CHIP0805'     | ''          | ''   | '20210827'
 '0.022UF'  | '50V'   | '10%'     | 'C0402'     | 'X7R'     | 'CH3226K1B00'(!)   = ''              | ''                 | ''       | 'CH3226K1B00'     |'C0402'| '(C0402-0201)'                                                       | '0.022UF'  | '50V'         | '10%'    | 'DISCRETE' | 'CAP CHIP 0.022U 50V(+-10%,X7R,0402)'                          | 'CHIP0402'     | ''          | ''   | '20210909'
 '0.022UF'  | '50V'   | '10%'     | 'C0402'     | 'EMPTY'   | 'CH3226K1B00'(!)   = ''              | ''                 | ''       | 'CH3226K1B00'     |'C0402'| '(C0402-0201)'                                                       | 'NA'       | '50V'         | '10%'    | 'IO'       | 'CAP CHIP 0.022U 50V(+-10%,X7R,0402)'                          | 'CHIP0402'     | ''          | ''   | '20210909'
 '0.33UF'   | '10V'   | '10%'     | 'C0402'     | 'X5R'     | 'CH4332K9B00'(!)   = ''              | ''                 | ''       | 'CH4332K9B00'     |'C0402'| '(C0402-0201)'                                                       | '0.33UF'   | '10V'         | '10%'    | 'DISCRETE' | 'CAP CHIP 0.33UF 10V(+-10%,X5R,0402)'                          | 'CHIP0402'     | ''          | ''   | '20211018'
 '0.33UF'   | '10V'   | '10%'     | 'C0402'     | 'EMPTY'   | 'CH4332K9B00'(!)   = ''              | ''                 | ''       | 'CH4332K9B00'     |'C0402'| '(C0402-0201)'                                                       | 'NA'       | '10V'         | '10%'    | 'IO'       | 'CAP CHIP 0.33UF 10V(+-10%,X5R,0402)'                          | 'CHIP0402'     | ''          | ''   | '20211018'
 '10UF'     | '10V'   | '10%'     | 'C0805'     | 'X7R'     | 'CH6102K1A05'(!)   = ''              | ''                 | ''       | 'CH6102K1A05'     |'C0805_H57'| '(SMC0805AW)'                                                        | '10UF'     | '10V'         | '10%'    | 'DISCRETE' | 'CAP CHIP 10U 10V(+-10%,X7R,0805)YGO'                          | 'CHIP0805'     | ''          | ''   | '20211115'
 '10UF'     | '10V'   | '10%'     | 'C0805'     | 'EMPTY'   | 'CH6102K1A05'(!)   = ''              | ''                 | ''       | 'CH6102K1A05'     |'C0805_H57'| '(SMC0805AW)'                                                        | 'NA'       | '10V'         | '10%'    | 'IO'       | 'CAP CHIP 10U 10V(+-10%,X7R,0805)YGO'                          | 'CHIP0805'     | ''          | ''   | '20211115'
 '100PF'    | '50V'   | '5%'      | 'C0402'     | 'NPO'     | 'CH1106J0B17'(!)   = ''              | ''                 | ''       | 'CH1106J0B17'     |'C0402'| '(C0402-0201)'                                                       | '100PF'    | '50V'         | '5%'     | 'DISCRETE' | 'CAP CHIP 100P 50V(+-5%,NPO,0402)SAM'                          | 'CHIP0402'     | ''          | ''   | '20211126'
 '100PF'    | '50V'   | '5%'      | 'C0402'     | 'EMPTY'   | 'CH1106J0B17'(!)   = ''              | ''                 | ''       | 'CH1106J0B17'     |'C0402'| '(C0402-0201)'                                                       | 'NA'       | '50V'         | '5%'     | 'IO'       | 'CAP CHIP 100P 50V(+-5%,NPO,0402)SAM'                          | 'CHIP0402'     | ''          | ''   | '20211126'
 '12PF'     | '50V'   | '5%'      | 'C0402'     | 'NP0'     | 'CH0126J0B16'(!)   = ''              | ''                 | ''       | 'CH0126J0B16'     |'C0402'| '(C0402-0201)'                                                       | '12PF'     | '50V'         | '5%'     | 'DISCRETE' | 'CAP CHIP 12P 50V(+-5%,NP0,0402)SAM'                           | 'CHIP0402'     | ''          | ''   | '20211129'
 '12PF'     | '50V'   | '5%'      | 'C0402'     | 'EMPTY'   | 'CH0126J0B16'(!)   = ''              | ''                 | ''       | 'CH0126J0B16'     |'C0402'| '(C0402-0201)'                                                       | 'NA'       | '50V'         | '5%'     | 'IO'       | 'CAP CHIP 12P 50V(+-5%,NP0,0402)SAM'                           | 'CHIP0402'     | ''          | ''   | '20211129'
 '1NF'      | '50V'   | '10%'     | 'C0402'     | 'X7R'     | 'CH2106K1B28'(!)   = ''              | ''                 | ''       | 'CH2106K1B28'     |'C0402'| '(C0402-0201)'                                                       | '1NF'      | '50V'         | '10%'    | 'DISCRETE' | 'CAP CHIP 1N 50V(+-10%,X7R,0402)SAM'                           | 'CHIP0402'     | ''          | ''   | '20211227'
 '1NF'      | '50V'   | '10%'     | 'C0402'     | 'EMPTY'   | 'CH2106K1B28'(!)   = ''              | ''                 | ''       | 'CH2106K1B28'     |'C0402'| '(C0402-0201)'                                                       | 'NA'       | '50V'         | '10%'    | 'IO'       | 'CAP CHIP 1N 50V(+-10%,X7R,0402)SAM'                           | 'CHIP0402'     | ''          | ''   | '20211227'
 '1.5UF'    | '25V'   | '10%'     | 'C0805'     | 'X7R'     | 'CH5154K1A05'(!)   = 'End of Design' | 'Comp-Approve'     | ''       | 'CH5154K1A05'     |'C0805_H57'| '(SMC0805AW)'                                                        | '1.5UF'    | '25V'         | '10%'    | 'DISCRETE' | 'CAP CHIP 1.5U 25V(10%,X7R,0805)H1.25'                         | 'CHIP0805'     | ''          | ''   | '20211227'
 '1.5UF'    | '25V'   | '10%'     | 'C0805'     | 'EMPTY'   | 'CH5154K1A05'(!)   = 'End of Design' | 'Comp-Approve'     | ''       | 'CH5154K1A05'     |'C0805_H57'| '(SMC0805AW)'                                                        | 'NA'       | '25V'         | '10%'    | 'IO'       | 'CAP CHIP 1.5U 25V(10%,X7R,0805)H1.25'                         | 'CHIP0805'     | ''          | ''   | '20211227'
 '0.5PF'    | '250V'  | '0.1PF'   | 'C0603'     | 'C0G'     | 'CH+50CB0900'(!)   = ''              | ''                 | ''       | 'CH+50CB0900'     |'C0603'| '(SMC0603AW)'                                                        | '0.5PF'    | '250V'        | '0.1PF'  | 'DISCRETE' | 'CAP CHIP 0.5P 250V(+-0.1P,C0G,0603)HQ'                        | 'CHIP0603'     | ''          | ''   | '20220106'
 '0.5PF'    | '250V'  | '0.1PF'   | 'C0603'     | 'EMPTY'   | 'CH+50CB0900'(!)   = ''              | ''                 | ''       | 'CH+50CB0900'     |'C0603'| '(SMC0603AW)'                                                        | 'NA'       | '250V'        | '0.1PF'  | 'IO'       | 'CAP CHIP 0.5P 250V(+-0.1P,C0G,0603)HQ'                        | 'CHIP0603'     | ''          | ''   | '20220106'
 '1.2PF'    | '250V'  | '0.1PF'   | 'C0603'     | 'C0G'     | 'CH-12CB0900'(!)   = ''              | ''                 | ''       | 'CH-12CB0900'     |'C0603'| '(SMC0603AW)'                                                        | '1.2PF'    | '250V'        | '0.1PF'  | 'DISCRETE' | 'CAP CHIP 1.2P 250V(+-0.1P,C0G,0603)HQ'                        | 'CHIP0603'     | ''          | ''   | '20220106'
 '1.2PF'    | '250V'  | '0.1PF'   | 'C0603'     | 'EMPTY'   | 'CH-12CB0900'(!)   = ''              | ''                 | ''       | 'CH-12CB0900'     |'C0603'| '(SMC0603AW)'                                                        | 'NA'       | '250V'        | '0.1PF'  | 'IO'       | 'CAP CHIP 1.2P 250V(+-0.1P,C0G,0603)HQ'                        | 'CHIP0603'     | ''          | ''   | '20220106'
 '8.2PF'    | '250V'  | '0.25PF'  | 'C0603'     | 'C0G'     | 'CH-82CC0900'(!)   = ''              | ''                 | ''       | 'CH-82CC0900'     |'C0603'| '(SMC0603AW)'                                                        | '8.2PF'    | '250V'        | '0.25PF' | 'DISCRETE' | 'CAP CHIP 8.2P 250V(+-0.25P,C0G,0603)HQ'                       | 'CHIP0603'     | ''          | ''   | '20220106'
 '8.2PF'    | '250V'  | '0.25PF'  | 'C0603'     | 'EMPTY'   | 'CH-82CC0900'(!)   = ''              | ''                 | ''       | 'CH-82CC0900'     |'C0603'| '(SMC0603AW)'                                                        | 'NA'       | '250V'        | '0.25PF' | 'IO'       | 'CAP CHIP 8.2P 250V(+-0.25P,C0G,0603)HQ'                       | 'CHIP0603'     | ''          | ''   | '20220106'
 '8.2PF'    | '50V'   | '0.25PF'  | 'C0402'     | 'C0G'     | 'CH-826C0B01'(!)   = 'End of Design' | 'Comp-Approve'     | ''       | 'CH-826C0B01'     |'C0402'| '(C0402-0201)'                                                       | '8.2PF'    | '50V'         | '0.25PF' | 'DISCRETE' | 'CAP CHIP 8.2PF,50V(+-0.25PF,C0G,0402)HIQ'                     | 'CHIP0402'     | ''          | ''   | '20220106'
 '8.2PF'    | '50V'   | '0.25PF'  | 'C0402'     | 'EMPTY'   | 'CH-826C0B01'(!)   = 'End of Design' | 'Comp-Approve'     | ''       | 'CH-826C0B01'     |'C0402'| '(C0402-0201)'                                                       | 'NA'       | '50V'         | '0.25PF' | 'IO'       | 'CAP CHIP 8.2PF,50V(+-0.25PF,C0G,0402)HIQ'                     | 'CHIP0402'     | ''          | ''   | '20220106'
 '330PF'    | '50V'   | '5%'      | 'C0402'     | 'X7R'     | 'CH13306JB14'(!)   = ''              | ''                 | ''       | 'CH13306JB14'     |'C0402'| '(C0402-0201)'                                                       | '330PF'    | '50V'         | '5%'     | 'DISCRETE' | 'CAP CHIP 330P 50V (+-5% X7R 0402)'                            | 'CHIP0402'     | ''          | ''   | '20220110'
 '330PF'    | '50V'   | '5%'      | 'C0402'     | 'EMPTY'   | 'CH13306JB14'(!)   = ''              | ''                 | ''       | 'CH13306JB14'     |'C0402'| '(C0402-0201)'                                                       | 'NA'       | '50V'         | '5%'     | 'IO'       | 'CAP CHIP 330P 50V (+-5% X7R 0402)'                            | 'CHIP0402'     | ''          | ''   | '20220110'
 '1PF'      | '250V'  | '0.1PF'   | 'C0603'     | 'C0G'     | 'CH-10CB0900'(!)   = ''              | ''                 | ''       | 'CH-10CB0900'     |'C0603'| '(SMC0603AW)'                                                        | '1PF'      | '250V'        | '0.1PF'  | 'DISCRETE' | 'CAP CHIP 1P 250V(+-0.1P,C0G,0603)HQ'                          | 'CHIP0603'     | ''          | ''   | '20220113'
 '1PF'      | '250V'  | '0.1PF'   | 'C0603'     | 'EMPTY'   | 'CH-10CB0900'(!)   = ''              | ''                 | ''       | 'CH-10CB0900'     |'C0603'| '(SMC0603AW)'                                                        | 'NA'       | '250V'        | '0.1PF'  | 'IO'       | 'CAP CHIP 1P 250V(+-0.1P,C0G,0603)HQ'                          | 'CHIP0603'     | ''          | ''   | '20220113'
 '6.8PF'    | '250V'  | '0.1PF'   | 'C0603'     | 'C0G'     | 'CH-68CB0900'(!)   = ''              | ''                 | ''       | 'CH-68CB0900'     |'C0603'| '(SMC0603AW)'                                                        | '6.8PF'    | '250V'        | '0.1PF'  | 'DISCRETE' | 'CAP CHIP 6.8P 250V(+-0.1P,C0G,0603)HQ'                        | 'CHIP0603'     | ''          | ''   | '20220113'
 '6.8PF'    | '250V'  | '0.1PF'   | 'C0603'     | 'EMPTY'   | 'CH-68CB0900'(!)   = ''              | ''                 | ''       | 'CH-68CB0900'     |'C0603'| '(SMC0603AW)'                                                        | 'NA'       | '250V'        | '0.1PF'  | 'IO'       | 'CAP CHIP 6.8P 250V(+-0.1P,C0G,0603)HQ'                        | 'CHIP0603'     | ''          | ''   | '20220113'
 '22UF'     | '4V'    | '20%'     | 'C0402'     | 'X6S'     | 'CH622KMEB04'(!)   = ''              | ''                 | ''       | 'CH622KMEB04'     |'C0402_H28'| '(C0402-0201_H28)'                                                   | '22UF'     | '4V'          | '20%'    | 'DISCRETE' | 'CAP CHIP 22UF 4V(+-20%,X6S,0402)SAM'                          | 'CHIP0402'     | ''          | ''   | '20220120'
 '22UF'     | '4V'    | '20%'     | 'C0402'     | 'EMPTY'   | 'CH622KMEB04'(!)   = ''              | ''                 | ''       | 'CH622KMEB04'     |'C0402_H28'| '(C0402-0201_H28)'                                                   | 'NA'       | '4V'          | '20%'    | 'IO'       | 'CAP CHIP 22UF 4V(+-20%,X6S,0402)SAM'                          | 'CHIP0402'     | ''          | ''   | '20220120'
 '47UF'     | '2.5V'  | '20%'     | 'C0603'     | 'X6S'     | 'CH647LME902'(!)   = ''              | ''                 | ''       | 'CH647LME902'     |'C0603_H40'| '(SMC0603AW)'                                                        | '47UF'     | '2.5V'        | '20%'    | 'DISCRETE' | 'CAP CHIP 47U 2.5V(+-20%,X6S,0603)SAM'                         | 'CHIP0603'     | ''          | ''   | '20220120'
 '47UF'     | '2.5V'  | '20%'     | 'C0603'     | 'EMPTY'   | 'CH647LME902'(!)   = ''              | ''                 | ''       | 'CH647LME902'     |'C0603_H40'| '(SMC0603AW)'                                                        | 'NA'       | '2.5V'        | '20%'    | 'IO'       | 'CAP CHIP 47U 2.5V(+-20%,X6S,0603)SAM'                         | 'CHIP0603'     | ''          | ''   | '20220120'
 '10UF'     | '16V'   | '10%'     | 'C0805'     | 'X6S'     | 'CH6103KEA03'(!)   = ''              | ''                 | ''       | 'CH6103KEA03'     |'C0805_H57'| '(SMC0805AW)'                                                        | '10UF'     | '16V'         | '10%'    | 'DISCRETE' | 'CAP CHIP 10UF 16V(+-10%,X6S,0805)SAM'                         | 'CHIP0805'     | ''          | ''   | '20220120'
 '10UF'     | '16V'   | '10%'     | 'C0805'     | 'EMPTY'   | 'CH6103KEA03'(!)   = ''              | ''                 | ''       | 'CH6103KEA03'     |'C0805_H57'| '(SMC0805AW)'                                                        | 'NA'       | '16V'         | '10%'    | 'IO'       | 'CAP CHIP 10UF 16V(+-10%,X6S,0805)SAM'                         | 'CHIP0805'     | ''          | ''   | '20220120'
 '0.3PF'    | '250V'  | '0.1PF'   | 'C0603'     | 'C0G'     | 'CH+30CB0900'(!)   = ''              | ''                 | ''       | 'CH+30CB0900'     |'C0603'| '(SMC0603AW)'                                                        | '0.3PF'    | '250V'        | '0.1PF'  | 'DISCRETE' | 'CAP CHIP 0.3P 250V(+-0.1P,C0G,0603)HQ'                        | 'CHIP0603'     | ''          | ''   | '20220120'
 '0.3PF'    | '250V'  | '0.1PF'   | 'C0603'     | 'EMPTY'   | 'CH+30CB0900'(!)   = ''              | ''                 | ''       | 'CH+30CB0900'     |'C0603'| '(SMC0603AW)'                                                        | 'NA'       | '250V'        | '0.1PF'  | 'IO'       | 'CAP CHIP 0.3P 250V(+-0.1P,C0G,0603)HQ'                        | 'CHIP0603'     | ''          | ''   | '20220120'
 '22UF'     | '10V'   | '20%'     | 'C0805'     | 'X6S'     | 'CH6222MEA06'(!)   = 'End of Design' | 'Comp-Approve'     | ''       | 'CH6222MEA06'     |'C0805_H57'| '(SMC0805AW)'                                                        | '22UF'     | '10V'         | '20%'    | 'DISCRETE' | 'CAP CHIP 22U 10V(20%,X6S,0805)SAM'                            | 'CHIP0805'     | ''          | ''   | '20220120'
 '22UF'     | '10V'   | '20%'     | 'C0805'     | 'EMPTY'   | 'CH6222MEA06'(!)   = 'End of Design' | 'Comp-Approve'     | ''       | 'CH6222MEA06'     |'C0805_H57'| '(SMC0805AW)'                                                        | 'NA'       | '10V'         | '20%'    | 'IO'       | 'CAP CHIP 22U 10V(20%,X6S,0805)SAM'                            | 'CHIP0805'     | ''          | ''   | '20220120'
 '2.2UF'    | '25V'   | '20%'     | 'C0402'     | 'X6S'     | 'CH5224MEB04'(!)   = ''              | ''                 | ''       | 'CH5224MEB04'     |'C0402_H28'| '(C0402-0201_H28)'                                                   | '2.2UF'    | '25V'         | '20%'    | 'DISCRETE' | 'CAP CHIP 2.2UF 25V(+-20%,X6S,0402)'                           | 'CHIP0402'     | ''          | ''   | '20220125'
 '2.2UF'    | '25V'   | '20%'     | 'C0402'     | 'EMPTY'   | 'CH5224MEB04'(!)   = ''              | ''                 | ''       | 'CH5224MEB04'     |'C0402_H28'| '(C0402-0201_H28)'                                                   | 'NA'       | '25V'         | '20%'    | 'IO'       | 'CAP CHIP 2.2UF 25V(+-20%,X6S,0402)'                           | 'CHIP0402'     | ''          | ''   | '20220125'
 '1000PF'   | '50V'   | '5%'      | 'C0402'     | 'NPO'     | 'CH2106J0B06'(!)   = ''              | ''                 | ''       | 'CH2106J0B06'     |'C0402'| '(C0402-0201)'                                                       | '1000PF'   | '50V'         | '5%'     | 'DISCRETE' | 'CAP CHIP 1000P,50V(+-5%,NPO,0402)'                            | 'CHIP0402'     | ''          | ''   | '20220221'
 '1000PF'   | '50V'   | '5%'      | 'C0402'     | 'EMPTY'   | 'CH2106J0B06'(!)   = ''              | ''                 | ''       | 'CH2106J0B06'     |'C0402'| '(C0402-0201)'                                                       | 'NA'       | '50V'         | '5%'     | 'IO'       | 'CAP CHIP 1000P,50V(+-5%,NPO,0402)'                            | 'CHIP0402'     | ''          | ''   | '20220221'
 '0.15UF'   | '100V'  | '10%'     | 'C0805'     | 'X7R'     | 'CH4158K1A00'(!)   = ''              | ''                 | ''       | 'CH4158K1A00'     |'C0805_H57'| '(SMC0805AW)'                                                        | '0.15UF'   | '100V'        | '10%'    | 'DISCRETE' | 'CAP CHIP 0.15U 100V(+-10%,X7R,0805)'                          | 'CHIP0805'     | ''          | ''   | '20220301'
 '0.15UF'   | '100V'  | '10%'     | 'C0805'     | 'EMPTY'   | 'CH4158K1A00'(!)   = ''              | ''                 | ''       | 'CH4158K1A00'     |'C0805_H57'| '(SMC0805AW)'                                                        | 'NA'       | '100V'        | '10%'    | 'IO'       | 'CAP CHIP 0.15U 100V(+-10%,X7R,0805)'                          | 'CHIP0805'     | ''          | ''   | '20220301'
 '18PF'     | '50V'   | '2%'      | 'C0201'     | 'C0G'     | 'CH0186G0E00'(!)   = ''              | ''                 | ''       | 'CH0186G0E00'     |'C0201'| '(SMC0201AW)'                                                        | '18PF'     | '50V'         | '2%'     | 'DISCRETE' | 'CAP CHIP 18PF 50V(+-2%,C0G,0201)'                             | 'CHIP0201'     | ''          | ''   | '20220303'
 '18PF'     | '50V'   | '2%'      | 'C0201'     | 'EMPTY'   | 'CH0186G0E00'(!)   = ''              | ''                 | ''       | 'CH0186G0E00'     |'C0201'| '(SMC0201AW)'                                                        | 'NA'       | '50V'         | '2%'     | 'IO'       | 'CAP CHIP 18PF 50V(+-2%,C0G,0201)'                             | 'CHIP0201'     | ''          | ''   | '20220303'
 '22UF'     | '10V'   | '20%'     | 'C0402'     | 'X5R'     | 'CH6222M9B01'(!)   = ''              | ''                 | ''       | 'CH6222M9B01'     |'C0402_H32'| '(C0402-0201_H32)'                                                   | '22UF'     | '10V'         | '20%'    | 'DISCRETE' | 'CAP CHIP 22U 10V(+-20%,X5R,0402)'                             | 'CHIP0402'     | ''          | ''   | '20220307'
 '22UF'     | '10V'   | '20%'     | 'C0402'     | 'EMPTY'   | 'CH6222M9B01'(!)   = ''              | ''                 | ''       | 'CH6222M9B01'     |'C0402_H32'| '(C0402-0201_H32)'                                                   | 'NA'       | '10V'         | '20%'    | 'IO'       | 'CAP CHIP 22U 10V(+-20%,X5R,0402)'                             | 'CHIP0402'     | ''          | ''   | '20220307'
 '1.8PF'    | '50V'   | '0.1PF'   | 'C0402'     | 'NPO'     | 'CH-1826TB06'(!)   = ''              | ''                 | ''       | 'CH-1826TB06'     |'C0402'| '(C0402-0201)'                                                       | '1.8PF'    | '50V'         | '0.1PF'  | 'DISCRETE' | 'CAP CHIP 1.8P 50V(+-0.1P,NPO,0402)'                           | 'CHIP0402'     | ''          | ''   | '20220307'
 '1.8PF'    | '50V'   | '0.1PF'   | 'C0402'     | 'EMPTY'   | 'CH-1826TB06'(!)   = ''              | ''                 | ''       | 'CH-1826TB06'     |'C0402'| '(C0402-0201)'                                                       | 'NA'       | '50V'         | '0.1PF'  | 'IO'       | 'CAP CHIP 1.8P 50V(+-0.1P,NPO,0402)'                           | 'CHIP0402'     | ''          | ''   | '20220307'
 '100PF'    | '50V'   | '5%'      | 'C0201'     | 'NPO'     | 'CH1106J0E00'(!)   = ''              | ''                 | ''       | 'CH1106J0E00'     |'C0201'| '(SMC0201AW)'                                                        | '100PF'    | '50V'         | '5%'     | 'DISCRETE' | 'CAP CHIP 100P 50V(+-5%,NPO,0201)'                             | 'CHIP0201'     | ''          | ''   | '20220307'
 '100PF'    | '50V'   | '5%'      | 'C0201'     | 'EMPTY'   | 'CH1106J0E00'(!)   = ''              | ''                 | ''       | 'CH1106J0E00'     |'C0201'| '(SMC0201AW)'                                                        | 'NA'       | '50V'         | '5%'     | 'IO'       | 'CAP CHIP 100P 50V(+-5%,NPO,0201)'                             | 'CHIP0201'     | ''          | ''   | '20220307'
 '0.22UF'   | '50V'   | '10%'     | 'C0603'     | 'X7R'     | 'CH4226K1902'(!)   = ''              | ''                 | ''       | 'CH4226K1902'     |'C0603'| '(SMC0603AW)'                                                        | '0.22UF'   | '50V'         | '10%'    | 'DISCRETE' | 'CAP CHIP 0.22U 50V(+-10%,X7R,0603)'                           | 'CHIP0603'     | ''          | ''   | '20220321'
 '0.22UF'   | '50V'   | '10%'     | 'C0603'     | 'EMPTY'   | 'CH4226K1902'(!)   = ''              | ''                 | ''       | 'CH4226K1902'     |'C0603'| '(SMC0603AW)'                                                        | 'NA'       | '50V'         | '10%'    | 'IO'       | 'CAP CHIP 0.22U 50V(+-10%,X7R,0603)'                           | 'CHIP0603'     | ''          | ''   | '20220321'
 '330PF'    | '16V'   | '10%'     | 'C0201'     | 'X7R'     | 'CH1333K1E01'(!)   = ''              | ''                 | ''       | 'CH1333K1E01'     |'C0201'| '(SMC0201AW)'                                                        | '330PF'    | '16V'         | '10%'    | 'DISCRETE' | 'CAP CHIP 330PF 16V(+-10%,X7R,0201)'                           | 'CHIP0201'     | ''          | ''   | '20220321'
 '330PF'    | '16V'   | '10%'     | 'C0201'     | 'EMPTY'   | 'CH1333K1E01'(!)   = ''              | ''                 | ''       | 'CH1333K1E01'     |'C0201'| '(SMC0201AW)'                                                        | 'NA'       | '16V'         | '10%'    | 'IO'       | 'CAP CHIP 330PF 16V(+-10%,X7R,0201)'                           | 'CHIP0201'     | ''          | ''   | '20220321'
 '0.022UF'  | '100V'  | '10%'     | 'C0603'     | 'X7R'     | 'CH3228K1900'(!)   = ''              | ''                 | ''       | 'CH3228K1900'     |'C0603'| '(SMC0603AW)'                                                        | '0.022UF'  | '100V'        | '10%'    | 'DISCRETE' | 'CAP CHIP 0.022UF 100V(+-10%,X7R,0603)'                        | 'CHIP0603'     | ''          | ''   | '20220321'
 '0.022UF'  | '100V'  | '10%'     | 'C0603'     | 'EMPTY'   | 'CH3228K1900'(!)   = ''              | ''                 | ''       | 'CH3228K1900'     |'C0603'| '(SMC0603AW)'                                                        | 'NA'       | '100V'        | '10%'    | 'IO'       | 'CAP CHIP 0.022UF 100V(+-10%,X7R,0603)'                        | 'CHIP0603'     | ''          | ''   | '20220321'
 '680PF'    | '50V'   | '10%'     | 'C0402'     | 'X7R'     | 'CH1686K1B09'(!)   = ''              | ''                 | ''       | 'CH1686K1B09'     |'C0402'| '(C0402-0201)'                                                       | '680PF'    | '50V'         | '10%'    | 'DISCRETE' | 'CAP CHIP 680P 50V(+-10%,X7R,0402)MUR'                         | 'CHIP0402'     | ''          | ''   | '20220414'
 '680PF'    | '50V'   | '10%'     | 'C0402'     | 'EMPTY'   | 'CH1686K1B09'(!)   = ''              | ''                 | ''       | 'CH1686K1B09'     |'C0402'| '(C0402-0201)'                                                       | 'NA'       | '50V'         | '10%'    | 'IO'       | 'CAP CHIP 680P 50V(+-10%,X7R,0402)MUR'                         | 'CHIP0402'     | ''          | ''   | '20220414'
 '0.01UF'   | '100V'  | '10%'     | 'C0805'     | 'X7R'     | 'CH3108K1A03'(!)   = ''              | ''                 | ''       | 'CH3108K1A03'     |'C0805_H57'| '(SMC0805AW)'                                                        | '0.01UF'   | '100V'        | '10%'    | 'DISCRETE' | 'CAP CHIP 0.01U 100V(10%,X7R,0805)'                            | 'CHIP0805'     | ''          | ''   | '20220421'
 '0.01UF'   | '100V'  | '10%'     | 'C0805'     | 'EMPTY'   | 'CH3108K1A03'(!)   = ''              | ''                 | ''       | 'CH3108K1A03'     |'C0805_H57'| '(SMC0805AW)'                                                        | 'NA'       | '100V'        | '10%'    | 'IO'       | 'CAP CHIP 0.01U 100V(10%,X7R,0805)'                            | 'CHIP0805'     | ''          | ''   | '20220421'
 '4.7UF'    | '10V'   | '20%'     | 'C0402'     | 'X5R'     | 'CH5472M9B01'(!)   = 'End of Design' | 'Comp-Approve'     | ''       | 'CH5472M9B01'     |'C0402_H28'| '(C0402-0201_H28)'                                                   | '4.7UF'    | '10V'         | '20%'    | 'DISCRETE' | 'CAP CHIP 4.7U 10V(+-20%,X5R,0402)'                            | 'CHIP0402'     | ''          | ''   | '20220422'
 '4.7UF'    | '10V'   | '20%'     | 'C0402'     | 'EMPTY'   | 'CH5472M9B01'(!)   = 'End of Design' | 'Comp-Approve'     | ''       | 'CH5472M9B01'     |'C0402_H28'| '(C0402-0201_H28)'                                                   | 'NA'       | '10V'         | '20%'    | 'IO'       | 'CAP CHIP 4.7U 10V(+-20%,X5R,0402)'                            | 'CHIP0402'     | ''          | ''   | '20220422'
 '330PF'    | '50V'   | '5%'      | 'C0402'     | 'NPO'     | 'CH1336J0B10'(!)   = ''              | ''                 | ''       | 'CH1336J0B10'     |'C0402'| '(C0402-0201)'                                                       | '330PF'    | '50V'         | '5%'     | 'DISCRETE' | 'CAP CHIP 330P 50V(+-5%,NPO,0402)MUR'                          | 'CHIP0402'     | ''          | ''   | '20220422'
 '330PF'    | '50V'   | '5%'      | 'C0402'     | 'EMPTY'   | 'CH1336J0B10'(!)   = ''              | ''                 | ''       | 'CH1336J0B10'     |'C0402'| '(C0402-0201)'                                                       | 'NA'       | '50V'         | '5%'     | 'IO'       | 'CAP CHIP 330P 50V(+-5%,NPO,0402)MUR'                          | 'CHIP0402'     | ''          | ''   | '20220422'
 '680PF'    | '50V'   | '5%'      | 'C0402'     | 'C0G'     | 'CH1686J0B03'(!)   = ''              | ''                 | ''       | 'CH1686J0B03'     |'C0402'| '(C0402-0201)'                                                       | '680PF'    | '50V'         | '5%'     | 'DISCRETE' | 'CAP CHIP 680P 50V(+-5%,C0G,0402)MUR'                          | 'CHIP0402'     | ''          | ''   | '20220422'
 '680PF'    | '50V'   | '5%'      | 'C0402'     | 'EMPTY'   | 'CH1686J0B03'(!)   = ''              | ''                 | ''       | 'CH1686J0B03'     |'C0402'| '(C0402-0201)'                                                       | 'NA'       | '50V'         | '5%'     | 'IO'       | 'CAP CHIP 680P 50V(+-5%,C0G,0402)MUR'                          | 'CHIP0402'     | ''          | ''   | '20220422'
 '0.5PF'    | '250V'  | '0.05PF'  | 'C0603'     | 'C0G'     | 'CH+50CT0900'(!)   = ''              | ''                 | ''       | 'CH+50CT0900'     |'C0603'| '(SMC0603AW)'                                                        | '0.5PF'    | '250V'        | '0.05PF' | 'DISCRETE' | 'CAP CHIP 0.5P 250V(0.05P,C0G,0603)HQ'                         | 'CHIP0603'     | ''          | ''   | '20220504'
 '0.5PF'    | '250V'  | '0.05PF'  | 'C0603'     | 'EMPTY'   | 'CH+50CT0900'(!)   = ''              | ''                 | ''       | 'CH+50CT0900'     |'C0603'| '(SMC0603AW)'                                                        | 'NA'       | '250V'        | '0.05PF' | 'IO'       | 'CAP CHIP 0.5P 250V(0.05P,C0G,0603)HQ'                         | 'CHIP0603'     | ''          | ''   | '20220504'
 '0.2PF'    | '250V'  | '0.05PF'  | 'C0603'     | 'C0G'     | 'CH+20CT0900'(!)   = ''              | ''                 | ''       | 'CH+20CT0900'     |'C0603'| '(SMC0603AW)'                                                        | '0.2PF'    | '250V'        | '0.05PF' | 'DISCRETE' | 'CAP CHIP 0.2P 250V(0.05P,C0G,0603)HQ'                         | 'CHIP0603'     | ''          | ''   | '20220504'
 '0.2PF'    | '250V'  | '0.05PF'  | 'C0603'     | 'EMPTY'   | 'CH+20CT0900'(!)   = ''              | ''                 | ''       | 'CH+20CT0900'     |'C0603'| '(SMC0603AW)'                                                        | 'NA'       | '250V'        | '0.05PF' | 'IO'       | 'CAP CHIP 0.2P 250V(0.05P,C0G,0603)HQ'                         | 'CHIP0603'     | ''          | ''   | '20220504'
 '1000PF'   | '50V'   | '5%'      | 'C0402'     | 'C0G'     | 'CH2106J0B01'(!)   = ''              | ''                 | ''       | 'CH2106J0B01'     |'C0402'| '(C0402-0201)'                                                       | '1000PF'   | '50V'         | '5%'     | 'DISCRETE' | 'CAP CHIP 1000PF 50V( 5%,C0G, 0402)MUR'                        | 'CHIP0402'     | ''          | ''   | '20220506'
 '1000PF'   | '50V'   | '5%'      | 'C0402'     | 'EMPTY'   | 'CH2106J0B01'(!)   = ''              | ''                 | ''       | 'CH2106J0B01'     |'C0402'| '(C0402-0201)'                                                       | 'NA'       | '50V'         | '5%'     | 'IO'       | 'CAP CHIP 1000PF 50V( 5%,C0G, 0402)MUR'                        | 'CHIP0402'     | ''          | ''   | '20220506'
 '0.15UF'   | '50V'   | '10%'     | 'C0603'     | 'X7R'     | 'CH4156K1901'(!)   = ''              | ''                 | ''       | 'CH4156K1901'     |'C0603'| '(SMC0603AW)'                                                        | '0.15UF'   | '50V'         | '10%'    | 'DISCRETE' | 'CAP CHIP 0.15U 50V(10%,X7R,0603)'                             | 'CHIP0603'     | ''          | ''   | '20220512'
 '0.15UF'   | '50V'   | '10%'     | 'C0603'     | 'EMPTY'   | 'CH4156K1901'(!)   = ''              | ''                 | ''       | 'CH4156K1901'     |'C0603'| '(SMC0603AW)'                                                        | 'NA'       | '50V'         | '10%'    | 'IO'       | 'CAP CHIP 0.15U 50V(10%,X7R,0603)'                             | 'CHIP0603'     | ''          | ''   | '20220512'
 '2.2UF'    | '16V'   | '20%'     | 'C0402'     | 'X6S'     | 'CH5223MEB01'(!)   = ''              | ''                 | ''       | 'CH5223MEB01'     |'C0402'| '(C0402-0201)'                                                       | '2.2UF'    | '16V'         | '20%'    | 'DISCRETE' | 'CAP CHIP 2.2U 16V(+-20%,X6S,0402)MUR'                         | 'CHIP0402'     | ''          | ''   | '20220518'
 '2.2UF'    | '16V'   | '20%'     | 'C0402'     | 'EMPTY'   | 'CH5223MEB01'(!)   = ''              | ''                 | ''       | 'CH5223MEB01'     |'C0402'| '(C0402-0201)'                                                       | 'NA'       | '16V'         | '20%'    | 'IO'       | 'CAP CHIP 2.2U 16V(+-20%,X6S,0402)MUR'                         | 'CHIP0402'     | ''          | ''   | '20220518'
 '0.01UF'   | '2KV'   | '10%'     | 'C1812'     | 'X7R'     | 'CH310IK1402'(!)   = ''              | ''                 | ''       | 'CH310IK1402'     |'C1812XC_H111'| '(SMC1812AW)'                                                        | '0.01UF'   | '2KV'         | '10%'    | 'DISCRETE' | 'CAP CHIP 0.01U 2KV(+-10%,X7R,1812)H2.5'                       | 'CHIP1812'     | ''          | ''   | '20220520'
 '0.01UF'   | '2KV'   | '10%'     | 'C1812'     | 'EMPTY'   | 'CH310IK1402'(!)   = ''              | ''                 | ''       | 'CH310IK1402'     |'C1812XC_H111'| '(SMC1812AW)'                                                        | 'NA'       | '2KV'         | '10%'    | 'IO'       | 'CAP CHIP 0.01U 2KV(+-10%,X7R,1812)H2.5'                       | 'CHIP1812'     | ''          | ''   | '20220520'
 '1500PF'   | '50V'   | '2%'      | 'C0402'     | 'C0G'     | 'CH2156G0B01'(!)   = ''              | ''                 | ''       | 'CH2156G0B01'     |'C0402'| '(C0402-0201)'                                                       | '1500PF'   | '50V'         | '2%'     | 'DISCRETE' | 'CAP CHIP 1500PF 50V(+-2%,C0G,0402)MUR'                        | 'CHIP0402'     | ''          | ''   | '20220520'
 '1500PF'   | '50V'   | '2%'      | 'C0402'     | 'EMPTY'   | 'CH2156G0B01'(!)   = ''              | ''                 | ''       | 'CH2156G0B01'     |'C0402'| '(C0402-0201)'                                                       | 'NA'       | '50V'         | '2%'     | 'IO'       | 'CAP CHIP 1500PF 50V(+-2%,C0G,0402)MUR'                        | 'CHIP0402'     | ''          | ''   | '20220520'
 '47UF'     | '4V'    | '20%'     | 'C0603'     | 'X6S'     | 'CH647KME900'(!)   = 'End of Design' | 'Comp-Approve'     | ''       | 'CH647KME900'     |'C0603_H40'| '(C0603_BHS-SP)'                                                     | '47UF'     | '4V'          | '20%'    | 'DISCRETE' | 'CAP CHIP 47U 4V(+-20%,X6S,0603)'                              | 'CHIP0603'     | ''          | ''   | '20220523'
 '47UF'     | '4V'    | '20%'     | 'C0603'     | 'EMPTY'   | 'CH647KME900'(!)   = 'End of Design' | 'Comp-Approve'     | ''       | 'CH647KME900'     |'C0603_H40'| '(C0603_BHS-SP)'                                                     | 'NA'       | '4V'          | '20%'    | 'IO'       | 'CAP CHIP 47U 4V(+-20%,X6S,0603)'                              | 'CHIP0603'     | ''          | ''   | '20220523'
 '15PF'     | '25V'   | '5%'      | 'C0201'     | 'C0G'     | 'CH0154J0E13'(!)   = ''              | ''                 | ''       | 'CH0154J0E13'     |'C0201'| '(SMC0201AW)'                                                        | '15PF'     | '25V'         | '5%'     | 'DISCRETE' | 'CAP CHIP 15P 25V(+-5%,C0G,0201)MUR SELA'                      | 'CHIP0201'     | ''          | ''   | '20220608'
 '15PF'     | '25V'   | '5%'      | 'C0201'     | 'EMPTY'   | 'CH0154J0E13'(!)   = ''              | ''                 | ''       | 'CH0154J0E13'     |'C0201'| '(SMC0201AW)'                                                        | 'NA'       | '25V'         | '5%'     | 'IO'       | 'CAP CHIP 15P 25V(+-5%,C0G,0201)MUR SELA'                      | 'CHIP0201'     | ''          | ''   | '20220608'
 '18PF'     | '50V'   | '2%'      | 'C0201'     | 'C0G'     | 'CH0186G0E01'(!)   = ''              | ''                 | ''       | 'CH0186G0E01'     |'C0201'| '(SMC0201AW)'                                                        | '18PF'     | '50V'         | '2%'     | 'DISCRETE' | 'CAP CHIP 18PF 50V(+-2%,C0G,0201)MUR'                          | 'CHIP0201'     | ''          | ''   | '20220608'
 '18PF'     | '50V'   | '2%'      | 'C0201'     | 'EMPTY'   | 'CH0186G0E01'(!)   = ''              | ''                 | ''       | 'CH0186G0E01'     |'C0201'| '(SMC0201AW)'                                                        | 'NA'       | '50V'         | '2%'     | 'IO'       | 'CAP CHIP 18PF 50V(+-2%,C0G,0201)MUR'                          | 'CHIP0201'     | ''          | ''   | '20220608'
 '100PF'    | '25V'   | '5%'      | 'C0402'     | 'C0G'     | 'CH1104J0B00'(!)   = ''              | ''                 | ''       | 'CH1104J0B00'     |'C0402'| '(C0402-0201)'                                                       | '100PF'    | '25V'         | '5%'     | 'DISCRETE' | 'CAP CHIP 100P 25V(+-5%,C0G,0402)'                             | 'CHIP0402'     | ''          | ''   | '20220608'
 '100PF'    | '25V'   | '5%'      | 'C0402'     | 'EMPTY'   | 'CH1104J0B00'(!)   = ''              | ''                 | ''       | 'CH1104J0B00'     |'C0402'| '(C0402-0201)'                                                       | 'NA'       | '25V'         | '5%'     | 'IO'       | 'CAP CHIP 100P 25V(+-5%,C0G,0402)'                             | 'CHIP0402'     | ''          | ''   | '20220608'
 '0.1UF'    | '16V'   | '10%'     | 'C0402'     | 'X5R'     | 'CH4103K9B06'(!)   = ''              | ''                 | ''       | 'CH4103K9B06'     |'C0402'| '(C0402-0201)'                                                       | '0.1UF'    | '16V'         | '10%'    | 'DISCRETE' | 'CAP CHIP 0.1U 16V(+-10%,X5R,0402)MUR'                         | 'CHIP0402'     | ''          | ''   | '20220608'
 '0.1UF'    | '16V'   | '10%'     | 'C0402'     | 'EMPTY'   | 'CH4103K9B06'(!)   = ''              | ''                 | ''       | 'CH4103K9B06'     |'C0402'| '(C0402-0201)'                                                       | 'NA'       | '16V'         | '10%'    | 'IO'       | 'CAP CHIP 0.1U 16V(+-10%,X5R,0402)MUR'                         | 'CHIP0402'     | ''          | ''   | '20220608'
 '1UF'      | '25V'   | '20%'     | 'C0402'     | 'X5R'     | 'CH5104M9B01'(!)   = ''              | ''                 | ''       | 'CH5104M9B01'     |'C0402'| '(C0402-0201)'                                                       | '1UF'      | '25V'         | '20%'    | 'DISCRETE' | 'CAP CHIP 1UF 25V(+-20%,X5R,0402)MUR'                          | 'CHIP0402'     | ''          | ''   | '20220608'
 '1UF'      | '25V'   | '20%'     | 'C0402'     | 'EMPTY'   | 'CH5104M9B01'(!)   = ''              | ''                 | ''       | 'CH5104M9B01'     |'C0402'| '(C0402-0201)'                                                       | 'NA'       | '25V'         | '20%'    | 'IO'       | 'CAP CHIP 1UF 25V(+-20%,X5R,0402)MUR'                          | 'CHIP0402'     | ''          | ''   | '20220608'
 '0.01UF'   | '10V'   | '10%'     | 'C0402'     | 'X7R'     | 'CH3102K1B00'(!)   = 'End of Design' | 'Comp-Approve'     | ''       | 'CH3102K1B00'     |'C0402'| '(C0402-0201)'                                                       | '0.01UF'   | '10V'         | '10%'    | 'DISCRETE' | 'CAP CHIP 0.01UF 10V(+-10%,X7R,0402)'                          | 'CHIP0402'     | ''          | ''   | '20220609'
 '0.01UF'   | '10V'   | '10%'     | 'C0402'     | 'EMPTY'   | 'CH3102K1B00'(!)   = 'End of Design' | 'Comp-Approve'     | ''       | 'CH3102K1B00'     |'C0402'| '(C0402-0201)'                                                       | 'NA'       | '10V'         | '10%'    | 'IO'       | 'CAP CHIP 0.01UF 10V(+-10%,X7R,0402)'                          | 'CHIP0402'     | ''          | ''   | '20220609'
 '47UF'     | '6.3V'  | '20%'     | 'C0805'     | 'X6S'     | 'CH6471MEA03'(!)   = ''              | ''                 | ''       | 'CH6471MEA03'     |'C0805_H57'| '(SMC0805AW)'                                                        | '47UF'     | '6.3V'        | '20%'    | 'DISCRETE' | 'CAP CHIP 47U 6.3V(+-20%,X6S,0805)MUR'                         | 'CHIP0805'     | ''          | ''   | '20220609'
 '47UF'     | '6.3V'  | '20%'     | 'C0805'     | 'EMPTY'   | 'CH6471MEA03'(!)   = ''              | ''                 | ''       | 'CH6471MEA03'     |'C0805_H57'| '(SMC0805AW)'                                                        | 'NA'       | '6.3V'        | '20%'    | 'IO'       | 'CAP CHIP 47U 6.3V(+-20%,X6S,0805)MUR'                         | 'CHIP0805'     | ''          | ''   | '20220609'
 '100UF'    | '4V'    | '20%'     | 'C0805'     | 'X5R'     | 'CH710KM9A01'(!)   = ''              | ''                 | ''       | 'CH710KM9A01'     |'C0805_H61'| '(SMC0805AW)'                                                        | '100UF'    | '4V'          | '20%'    | 'DISCRETE' | 'CAP CHIP 100U 4V(+-20%,X5R,0805)MUR'                          | 'CHIP0805'     | ''          | ''   | '20220609'
 '100UF'    | '4V'    | '20%'     | 'C0805'     | 'EMPTY'   | 'CH710KM9A01'(!)   = ''              | ''                 | ''       | 'CH710KM9A01'     |'C0805_H61'| '(SMC0805AW)'                                                        | 'NA'       | '4V'          | '20%'    | 'IO'       | 'CAP CHIP 100U 4V(+-20%,X5R,0805)MUR'                          | 'CHIP0805'     | ''          | ''   | '20220609'
 '47UF'     | '10V'   | '20%'     | 'C0805'     | 'X5R'     | 'CH6472M9A02'(!)   = ''              | ''                 | ''       | 'CH6472M9A02'     |'C0805_H61'| '(SMC0805AW)'                                                        | '47UF'     | '10V'         | '20%'    | 'DISCRETE' | 'CAP CHIP 47U 10V(+-20%,X5R,0805)MUR'                          | 'CHIP0805'     | ''          | ''   | '20220609'
 '47UF'     | '10V'   | '20%'     | 'C0805'     | 'EMPTY'   | 'CH6472M9A02'(!)   = ''              | ''                 | ''       | 'CH6472M9A02'     |'C0805_H61'| '(SMC0805AW)'                                                        | 'NA'       | '10V'         | '20%'    | 'IO'       | 'CAP CHIP 47U 10V(+-20%,X5R,0805)MUR'                          | 'CHIP0805'     | ''          | ''   | '20220609'
 '0.1UF'    | '100V'  | '10%'     | 'C0603'     | 'X7R'     | 'CH4108K1909'(!)   = ''              | ''                 | ''       | 'CH4108K1909'     |'C0603'| '(SMC0603AW)'                                                        | '0.1UF'    | '100V'        | '10%'    | 'DISCRETE' | 'CAP CHIP 0.1U 100V(+-10%,X7R,0603)MUR'                        | 'CHIP0603'     | ''          | ''   | '20220609'
 '0.1UF'    | '100V'  | '10%'     | 'C0603'     | 'EMPTY'   | 'CH4108K1909'(!)   = ''              | ''                 | ''       | 'CH4108K1909'     |'C0603'| '(SMC0603AW)'                                                        | 'NA'       | '100V'        | '10%'    | 'IO'       | 'CAP CHIP 0.1U 100V(+-10%,X7R,0603)MUR'                        | 'CHIP0603'     | ''          | ''   | '20220609'
 '15PF'     | '25V'   | '5%'      | 'C0201'     | 'C0G'     | 'CH0154J0E22'(!)   = ''              | ''                 | ''       | 'CH0154J0E22'     |'C0201'| '(SMC0201AW)'                                                        | '15PF'     | '25V'         | '5%'     | 'DISCRETE' | 'CAP CHIP 15P 25V(+-5%,C0G,0201)MUR'                           | 'CHIP0201'     | ''          | ''   | '20220620'
 '15PF'     | '25V'   | '5%'      | 'C0201'     | 'EMPTY'   | 'CH0154J0E22'(!)   = ''              | ''                 | ''       | 'CH0154J0E22'     |'C0201'| '(SMC0201AW)'                                                        | 'NA'       | '25V'         | '5%'     | 'IO'       | 'CAP CHIP 15P 25V(+-5%,C0G,0201)MUR'                           | 'CHIP0201'     | ''          | ''   | '20220620'
 '1UF'      | '25V'   | '10%'     | 'C0402'     | 'X5R'     | 'CH5104K9B15'(!)   = ''              | ''                 | ''       | 'CH5104K9B15'     |'C0402'| '(C0402-0201)'                                                       | '1UF'      | '25V'         | '10%'    | 'DISCRETE' | 'CAP CHIP 1UF 25V(+-10%,X5R,0402)MUR'                          | 'CHIP0402'     | ''          | ''   | '20220620'
 '1UF'      | '25V'   | '10%'     | 'C0402'     | 'EMPTY'   | 'CH5104K9B15'(!)   = ''              | ''                 | ''       | 'CH5104K9B15'     |'C0402'| '(C0402-0201)'                                                       | 'NA'       | '25V'         | '10%'    | 'IO'       | 'CAP CHIP 1UF 25V(+-10%,X5R,0402)MUR'                          | 'CHIP0402'     | ''          | ''   | '20220620'
 '0.1NF'    | '25V'   | '5%'      | 'C0201'     | 'C0G'     | 'CH1104J0E09'(!)   = ''              | ''                 | ''       | 'CH1104J0E09'     |'C0201'| '(SMC0201AW)'                                                        | '0.1NF'    | '25V'         | '5%'     | 'DISCRETE' | 'CAP CHIP 0.1NF 25V(+-5%,C0G,0201)MUR'                         | 'CHIP0201'     | ''          | ''   | '20220621'
 '0.1NF'    | '25V'   | '5%'      | 'C0201'     | 'EMPTY'   | 'CH1104J0E09'(!)   = ''              | ''                 | ''       | 'CH1104J0E09'     |'C0201'| '(SMC0201AW)'                                                        | 'NA'       | '25V'         | '5%'     | 'IO'       | 'CAP CHIP 0.1NF 25V(+-5%,C0G,0201)MUR'                         | 'CHIP0201'     | ''          | ''   | '20220621'
 '1500PF'   | '50V'   | '10%'     | 'C0402'     | 'X7R'     | 'CH2156K1B14'(!)   = ''              | ''                 | ''       | 'CH2156K1B14'     |'C0402'| '(C0402-0201)'                                                       | '1500PF'   | '50V'         | '10%'    | 'DISCRETE' | 'CAP CHIP 1500PF 50V(+-10%,X7R,0402)YGO'                       | 'CHIP0402'     | ''          | ''   | '20220621'
 '1500PF'   | '50V'   | '10%'     | 'C0402'     | 'EMPTY'   | 'CH2156K1B14'(!)   = ''              | ''                 | ''       | 'CH2156K1B14'     |'C0402'| '(C0402-0201)'                                                       | 'NA'       | '50V'         | '10%'    | 'IO'       | 'CAP CHIP 1500PF 50V(+-10%,X7R,0402)YGO'                       | 'CHIP0402'     | ''          | ''   | '20220621'
 '0.01UF'   | '10V'   | '10%'     | 'C0402'     | 'X7R'     | 'CH3102K1B06'(!)   = ''              | ''                 | ''       | 'CH3102K1B06'     |'C0402'| '(C0402_OCTAGONXA,C0402-0201)'                                       | '0.01UF'   | '10V'         | '10%'    | 'DISCRETE' | 'CAP CHIP 0.01UF 10V(+-10%,X7R,0402)YGO'                       | 'CHIP0402'     | ''          | ''   | '20220621'
 '0.01UF'   | '10V'   | '10%'     | 'C0402'     | 'EMPTY'   | 'CH3102K1B06'(!)   = ''              | ''                 | ''       | 'CH3102K1B06'     |'C0402'| '(C0402_OCTAGONXA,C0402-0201)'                                       | 'NA'       | '10V'         | '10%'    | 'IO'       | 'CAP CHIP 0.01UF 10V(+-10%,X7R,0402)YGO'                       | 'CHIP0402'     | ''          | ''   | '20220621'
 '2.2PF'    | '50V'   | '0.1PF'   | 'C0402'     | 'NPO'     | 'CH-226B0B02'(!)   = ''              | ''                 | ''       | 'CH-226B0B02'     |'C0402'| '(C0402-0201)'                                                       | '2.2PF'    | '50V'         | '0.1PF'  | 'DISCRETE' | 'CAP CHIP 2.2P 50V (+-0.1P,NPO,0402)MUR'                       | 'CHIP0402'     | ''          | ''   | '20220621'
 '2.2PF'    | '50V'   | '0.1PF'   | 'C0402'     | 'EMPTY'   | 'CH-226B0B02'(!)   = ''              | ''                 | ''       | 'CH-226B0B02'     |'C0402'| '(C0402-0201)'                                                       | 'NA'       | '50V'         | '0.1PF'  | 'IO'       | 'CAP CHIP 2.2P 50V (+-0.1P,NPO,0402)MUR'                       | 'CHIP0402'     | ''          | ''   | '20220621'
 '3900PF'   | '50V'   | '10%'     | 'C0402'     | 'X7R'     | 'CH2396K1B07'(!)   = ''              | ''                 | ''       | 'CH2396K1B07'     |'C0402'| '(C0402-0201)'                                                       | '3900PF'   | '50V'         | '10%'    | 'DISCRETE' | 'CAP CHIP 3900P 50V(+-10%,X7R,0402)MUR'                        | 'CHIP0402'     | ''          | ''   | '20220622'
 '3900PF'   | '50V'   | '10%'     | 'C0402'     | 'EMPTY'   | 'CH2396K1B07'(!)   = ''              | ''                 | ''       | 'CH2396K1B07'     |'C0402'| '(C0402-0201)'                                                       | 'NA'       | '50V'         | '10%'    | 'IO'       | 'CAP CHIP 3900P 50V(+-10%,X7R,0402)MUR'                        | 'CHIP0402'     | ''          | ''   | '20220622'
 '0.22UF'   | '6.3V'  | '20%'     | 'C0201'     | 'X6S'     | 'CH4221MEE03'(!)   = ''              | ''                 | ''       | 'CH4221MEE03'     |'C0201'| '(SMC0201AW)'                                                        | '0.22UF'   | '6.3V'        | '20%'    | 'DISCRETE' | 'CAP CHIP 0.22UF 6.3V(20%,X6S,0201)MUR'                        | 'CHIP0201'     | ''          | ''   | '20220623'
 '0.22UF'   | '6.3V'  | '20%'     | 'C0201'     | 'EMPTY'   | 'CH4221MEE03'(!)   = ''              | ''                 | ''       | 'CH4221MEE03'     |'C0201'| '(SMC0201AW)'                                                        | 'NA'       | '6.3V'        | '20%'    | 'IO'       | 'CAP CHIP 0.22UF 6.3V(20%,X6S,0201)MUR'                        | 'CHIP0201'     | ''          | ''   | '20220623'
 '0.22UF'   | '6.3V'  | '20%'     | 'C0201'     | 'X6S'     | 'CH4221MEE04'(!)   = ''              | ''                 | ''       | 'CH4221MEE04'     |'C0201'| '(SMC0201AW)'                                                        | '0.22UF'   | '6.3V'        | '20%'    | 'DISCRETE' | 'CAP CHIP 0.22UF 6.3V(20%,X6S,0201)TAY'                        | 'CHIP0201'     | ''          | ''   | '20220623'
 '0.22UF'   | '6.3V'  | '20%'     | 'C0201'     | 'EMPTY'   | 'CH4221MEE04'(!)   = ''              | ''                 | ''       | 'CH4221MEE04'     |'C0201'| '(SMC0201AW)'                                                        | 'NA'       | '6.3V'        | '20%'    | 'IO'       | 'CAP CHIP 0.22UF 6.3V(20%,X6S,0201)TAY'                        | 'CHIP0201'     | ''          | ''   | '20220623'
 '0.015UF'  | '16V'   | '20%'     | 'C0402'     | 'X7R'     | 'CH3153M1B01'(!)   = ''              | ''                 | ''       | 'CH3153M1B01'     |'C0402'| '(C0402-0201)'                                                       | '0.015UF'  | '16V'         | '20%'    | 'DISCRETE' | 'CAP CHIP 0.015U 16V(+-20%,X7R,0402)YGO'                       | 'CHIP0402'     | ''          | ''   | '20220624'
 '0.015UF'  | '16V'   | '20%'     | 'C0402'     | 'EMPTY'   | 'CH3153M1B01'(!)   = ''              | ''                 | ''       | 'CH3153M1B01'     |'C0402'| '(C0402-0201)'                                                       | 'NA'       | '16V'         | '20%'    | 'IO'       | 'CAP CHIP 0.015U 16V(+-20%,X7R,0402)YGO'                       | 'CHIP0402'     | ''          | ''   | '20220624'
 '3300PF'   | '50V'   | '5%'      | 'C0402'     | 'X7R'     | 'CH2336J1B05'(!)   = ''              | ''                 | ''       | 'CH2336J1B05'     |'C0402'| '(C0402-0201)'                                                       | '3300PF'   | '50V'         | '5%'     | 'DISCRETE' | 'CAP CHIP 3300P 50V(+-5%,X7R,0402)MUR'                         | 'CHIP0402'     | ''          | ''   | '20220624'
 '3300PF'   | '50V'   | '5%'      | 'C0402'     | 'EMPTY'   | 'CH2336J1B05'(!)   = ''              | ''                 | ''       | 'CH2336J1B05'     |'C0402'| '(C0402-0201)'                                                       | 'NA'       | '50V'         | '5%'     | 'IO'       | 'CAP CHIP 3300P 50V(+-5%,X7R,0402)MUR'                         | 'CHIP0402'     | ''          | ''   | '20220624'
 '3300PF'   | '50V'   | '5%'      | 'C0402'     | 'X7R'     | 'CH2336J1B07'(!)   = ''              | ''                 | ''       | 'CH2336J1B07'     |'C0402'| '(C0402-0201)'                                                       | '3300PF'   | '50V'         | '5%'     | 'DISCRETE' | 'CAP CHIP 3300P 50V(+-5%,X7R,0402)YGO'                         | 'CHIP0402'     | ''          | ''   | '20220630'
 '3300PF'   | '50V'   | '5%'      | 'C0402'     | 'EMPTY'   | 'CH2336J1B07'(!)   = ''              | ''                 | ''       | 'CH2336J1B07'     |'C0402'| '(C0402-0201)'                                                       | 'NA'       | '50V'         | '5%'     | 'IO'       | 'CAP CHIP 3300P 50V(+-5%,X7R,0402)YGO'                         | 'CHIP0402'     | ''          | ''   | '20220630'
 '2.2UF'    | '25V'   | '10%'     | 'C0402'     | 'X5R'     | 'CH5224K9B06'(!)   = ''              | ''                 | ''       | 'CH5224K9B06'     |'C0402_H28'| '(C0402-0201_H28)'                                                   | '2.2UF'    | '25V'         | '10%'    | 'DISCRETE' | 'CAP CHIP 2.2U 25V(+-10%,X5R,0402)MUR'                         | 'CHIP0402'     | ''          | ''   | '20220704'
 '2.2UF'    | '25V'   | '10%'     | 'C0402'     | 'EMPTY'   | 'CH5224K9B06'(!)   = ''              | ''                 | ''       | 'CH5224K9B06'     |'C0402_H28'| '(C0402-0201_H28)'                                                   | 'NA'       | '25V'         | '10%'    | 'IO'       | 'CAP CHIP 2.2U 25V(+-10%,X5R,0402)MUR'                         | 'CHIP0402'     | ''          | ''   | '20220704'
 '2.2UF'    | '25V'   | '10%'     | 'C0402'     | 'X5R'     | 'CH5224K9B07'(!)   = ''              | ''                 | ''       | 'CH5224K9B07'     |'C0402_H28'| '(C0402-0201_H28)'                                                   | '2.2UF'    | '25V'         | '10%'    | 'DISCRETE' | 'CAP CHIP 2.2U 25V(+-10%,X5R,0402)SAM'                         | 'CHIP0402'     | ''          | ''   | '20220705'
 '2.2UF'    | '25V'   | '10%'     | 'C0402'     | 'EMPTY'   | 'CH5224K9B07'(!)   = ''              | ''                 | ''       | 'CH5224K9B07'     |'C0402_H28'| '(C0402-0201_H28)'                                                   | 'NA'       | '25V'         | '10%'    | 'IO'       | 'CAP CHIP 2.2U 25V(+-10%,X5R,0402)SAM'                         | 'CHIP0402'     | ''          | ''   | '20220705'
 '2.2UF'    | '25V'   | '10%'     | 'C0402'     | 'X5R'     | 'CH5224K9B08'(!)   = ''              | ''                 | ''       | 'CH5224K9B08'     |'C0402_H28'| '(C0402-0201_H28)'                                                   | '2.2UF'    | '25V'         | '10%'    | 'DISCRETE' | 'CAP CHIP 2.2U 25V(+-10%,X5R,0402)WTC'                         | 'CHIP0402'     | ''          | ''   | '20220705'
 '2.2UF'    | '25V'   | '10%'     | 'C0402'     | 'EMPTY'   | 'CH5224K9B08'(!)   = ''              | ''                 | ''       | 'CH5224K9B08'     |'C0402_H28'| '(C0402-0201_H28)'                                                   | 'NA'       | '25V'         | '10%'    | 'IO'       | 'CAP CHIP 2.2U 25V(+-10%,X5R,0402)WTC'                         | 'CHIP0402'     | ''          | ''   | '20220705'
 '2.2UF'    | '6.3V'  | '20%'     | 'C0201'     | 'X6S'     | 'CH5221MEE00'(!)   = ''              | ''                 | ''       | 'CH5221MEE00'     |'C0201_H22'| '(C0201-0402_H22)'                                                   | '2.2UF'    | '6.3V'        | '20%'    | 'DISCRETE' | 'CAP CHIP 2.2UF 6.3V(+-20%,X6S,0201)'                          | 'CHIP0201'     | ''          | ''   | '20220715'
 '2.2UF'    | '6.3V'  | '20%'     | 'C0201'     | 'EMPTY'   | 'CH5221MEE00'(!)   = ''              | ''                 | ''       | 'CH5221MEE00'     |'C0201_H22'| '(C0201-0402_H22)'                                                   | 'NA'       | '6.3V'        | '20%'    | 'IO'       | 'CAP CHIP 2.2UF 6.3V(+-20%,X6S,0201)'                          | 'CHIP0201'     | ''          | ''   | '20220715'
 '820PF'    | '50V'   | '5%'      | 'C0402'     | 'NPO'     | 'CH1826J0B10'(!)   = ''              | ''                 | ''       | 'CH1826J0B10'     |'C0402'| '(C0402-0201)'                                                       | '820PF'    | '50V'         | '5%'     | 'DISCRETE' | 'CAP CHIP 820P 50V(+-5%,NPO,0402)MUR'                          | 'CHIP0402'     | ''          | ''   | '20220722'
 '820PF'    | '50V'   | '5%'      | 'C0402'     | 'EMPTY'   | 'CH1826J0B10'(!)   = ''              | ''                 | ''       | 'CH1826J0B10'     |'C0402'| '(C0402-0201)'                                                       | 'NA'       | '50V'         | '5%'     | 'IO'       | 'CAP CHIP 820P 50V(+-5%,NPO,0402)MUR'                          | 'CHIP0402'     | ''          | ''   | '20220722'
 '0.22UF'   | '10V'   | '10%'     | 'C0201'     | 'X5R'     | 'CH4222K9E00'(!)   = ''              | ''                 | ''       | 'CH4222K9E00'     |'C0201'| '(C0201_HOME-PLATE_H22)'                                             | '0.22UF'   | '10V'         | '10%'    | 'DISCRETE' | 'CAP CHIP 0.22UF 10V(+-10%,X5R,0201)MUR'                       | 'CHIP0201'     | ''          | ''   | '20220725'
 '0.22UF'   | '10V'   | '10%'     | 'C0201'     | 'EMPTY'   | 'CH4222K9E00'(!)   = ''              | ''                 | ''       | 'CH4222K9E00'     |'C0201'| '(C0201_HOME-PLATE_H22)'                                             | 'NA'       | '10V'         | '10%'    | 'IO'       | 'CAP CHIP 0.22UF 10V(+-10%,X5R,0201)MUR'                       | 'CHIP0201'     | ''          | ''   | '20220725'
 '22UF'     | '10V'   | '20%'     | 'C0603'     | 'X5R'     | 'CH6222M9905'(!)   = ''              | ''                 | ''       | 'CH6222M9905'     |'C0603_H40'| '(SMC0603AW)'                                                        | '22UF'     | '10V'         | '20%'    | 'DISCRETE' | 'CAP CHIP 22UF 10V(+-20%,X5R,0603)MUR'                         | 'CHIP0603'     | ''          | ''   | '20220725'
 '22UF'     | '10V'   | '20%'     | 'C0603'     | 'EMPTY'   | 'CH6222M9905'(!)   = ''              | ''                 | ''       | 'CH6222M9905'     |'C0603_H40'| '(SMC0603AW)'                                                        | 'NA'       | '10V'         | '20%'    | 'IO'       | 'CAP CHIP 22UF 10V(+-20%,X5R,0603)MUR'                         | 'CHIP0603'     | ''          | ''   | '20220725'
 '33NF'     | '50V'   | '10%'     | 'C0402'     | 'X7R'     | 'CH3336K1B00'(!)   = ''              | ''                 | ''       | 'CH3336K1B00'     |'C0402'| '(C0402-0201)'                                                       | '33NF'     | '50V'         | '10%'    | 'DISCRETE' | 'CAP CHIP 33NF 50V(+-10%,X7R,0402)'                            | 'CHIP0402'     | ''          | ''   | '20220816'
 '33NF'     | '50V'   | '10%'     | 'C0402'     | 'EMPTY'   | 'CH3336K1B00'(!)   = ''              | ''                 | ''       | 'CH3336K1B00'     |'C0402'| '(C0402-0201)'                                                       | 'NA'       | '50V'         | '10%'    | 'IO'       | 'CAP CHIP 33NF 50V(+-10%,X7R,0402)'                            | 'CHIP0402'     | ''          | ''   | '20220816'
 '0.022UF'  | '50V'   | '10%'     | 'C0402'     | 'X7R'     | 'CH3226K1B08'(!)   = ''              | ''                 | ''       | 'CH3226K1B08'     |'C0402'| '(C0402-0201)'                                                       | '0.022UF'  | '50V'         | '10%'    | 'DISCRETE' | 'CAP CHIP 0.022U 50V(+-10%,X7R,0402)MUR'                       | 'CHIP0402'     | ''          | ''   | '20220816'
 '0.022UF'  | '50V'   | '10%'     | 'C0402'     | 'EMPTY'   | 'CH3226K1B08'(!)   = ''              | ''                 | ''       | 'CH3226K1B08'     |'C0402'| '(C0402-0201)'                                                       | 'NA'       | '50V'         | '10%'    | 'IO'       | 'CAP CHIP 0.022U 50V(+-10%,X7R,0402)MUR'                       | 'CHIP0402'     | ''          | ''   | '20220816'
 '10UF'     | '100V'  | '10%'     | 'C1210'     | 'X7S'     | 'CH6108K6301'(!)   = ''              | ''                 | ''       | 'CH6108K6301'     |'C1210_GRM32E'| '(SMC1210AW)'                                                        | '10UF'     | '100V'        | '10%'    | 'DISCRETE' | 'CAP CHIP 10UF 100V(+-10%,X7S,1210)'                           | 'CHIP1210'     | ''          | ''   | '20220826'
 '10UF'     | '100V'  | '10%'     | 'C1210'     | 'EMPTY'   | 'CH6108K6301'(!)   = ''              | ''                 | ''       | 'CH6108K6301'     |'C1210_GRM32E'| '(SMC1210AW)'                                                        | 'NA'       | '100V'        | '10%'    | 'IO'       | 'CAP CHIP 10UF 100V(+-10%,X7S,1210)'                           | 'CHIP1210'     | ''          | ''   | '20220826'
 '2200PF'   | '50V'   | '5%'      | 'C0603'     | 'C0G'     | 'CH2226J0903'(!)   = ''              | ''                 | ''       | 'CH2226J0903'     |'C0603'| '(SMC0603AW)'                                                        | '2200PF'   | '50V'         | '5%'     | 'DISCRETE' | 'CAP CHIP 2200PF 50V(+-5%,C0G,0603)MUR'                        | 'CHIP0603'     | ''          | ''   | '20220826'
 '2200PF'   | '50V'   | '5%'      | 'C0603'     | 'EMPTY'   | 'CH2226J0903'(!)   = ''              | ''                 | ''       | 'CH2226J0903'     |'C0603'| '(SMC0603AW)'                                                        | 'NA'       | '50V'         | '5%'     | 'IO'       | 'CAP CHIP 2200PF 50V(+-5%,C0G,0603)MUR'                        | 'CHIP0603'     | ''          | ''   | '20220826'
 '1500PF'   | '50V'   | '5%'      | 'C0603'     | 'C0G'     | 'CH2156J0900'(!)   = ''              | ''                 | ''       | 'CH2156J0900'     |'C0603'| '(SMC0603AW)'                                                        | '1500PF'   | '50V'         | '5%'     | 'DISCRETE' | 'CAP CHIP 1500P 50V(+-5%,C0G,0603)MUR'                         | 'CHIP0603'     | ''          | ''   | '20220826'
 '1500PF'   | '50V'   | '5%'      | 'C0603'     | 'EMPTY'   | 'CH2156J0900'(!)   = ''              | ''                 | ''       | 'CH2156J0900'     |'C0603'| '(SMC0603AW)'                                                        | 'NA'       | '50V'         | '5%'     | 'IO'       | 'CAP CHIP 1500P 50V(+-5%,C0G,0603)MUR'                         | 'CHIP0603'     | ''          | ''   | '20220826'
 '4.7UF'    | '10V'   | '20%'     | 'C0402'     | 'X6S'     | 'CH5472MEB00'(!)   = ''              | ''                 | ''       | 'CH5472MEB00'     |'C0402_H28'| '(C0402-0201_H28)'                                                   | '4.7UF'    | '10V'         | '20%'    | 'DISCRETE' | 'CAP CHIP 4.7U 10V(+-20%,X6S,0402)'                            | 'CHIP0402'     | ''          | ''   | '20220826'
 '4.7UF'    | '10V'   | '20%'     | 'C0402'     | 'EMPTY'   | 'CH5472MEB00'(!)   = ''              | ''                 | ''       | 'CH5472MEB00'     |'C0402_H28'| '(C0402-0201_H28)'                                                   | 'NA'       | '10V'         | '20%'    | 'IO'       | 'CAP CHIP 4.7U 10V(+-20%,X6S,0402)'                            | 'CHIP0402'     | ''          | ''   | '20220826'
 '10NF'     | '10V'   | '10%'     | 'C0201'     | 'X7R'     | 'CH3102K1E06'(!)   = ''              | ''                 | ''       | 'CH3102K1E06'     |'C0201'| '(SMC0201AW)'                                                        | '10NF'     | '10V'         | '10%'    | 'DISCRETE' | 'CAP CHIP 10NF 10V(+-10%,X7R,0201)MUR'                         | 'CHIP0201'     | ''          | ''   | '20220901'
 '10NF'     | '10V'   | '10%'     | 'C0201'     | 'EMPTY'   | 'CH3102K1E06'(!)   = ''              | ''                 | ''       | 'CH3102K1E06'     |'C0201'| '(SMC0201AW)'                                                        | 'NA'       | '10V'         | '10%'    | 'IO'       | 'CAP CHIP 10NF 10V(+-10%,X7R,0201)MUR'                         | 'CHIP0201'     | ''          | ''   | '20220901'
 '4700PF'   | '2KV'   | '10%'     | 'C1812'     | 'X7R'     | 'CH247IK1400'(!)   = ''              | ''                 | ''       | 'CH247IK1400'     |'C1812XD'| '(SMC1812AW)'                                                        | '4700PF'   | '2KV'         | '10%'    | 'DISCRETE' | 'CAP CHIP 4700P 2KV(+-10%,X7R,1812)'                           | 'CHIP1812'     | ''          | ''   | '20220905'
 '4700PF'   | '2KV'   | '10%'     | 'C1812'     | 'EMPTY'   | 'CH247IK1400'(!)   = ''              | ''                 | ''       | 'CH247IK1400'     |'C1812XD'| '(SMC1812AW)'                                                        | 'NA'       | '2KV'         | '10%'    | 'IO'       | 'CAP CHIP 4700P 2KV(+-10%,X7R,1812)'                           | 'CHIP1812'     | ''          | ''   | '20220905'
 '0.01UF'   | '25V'   | '10%'     | 'C0402'     | 'X7R'     | 'CH3104K1B12'(!)   = ''              | ''                 | ''       | 'CH3104K1B12'     |'C0402'| '(C0402-0201)'                                                       | '0.01UF'   | '25V'         | '10%'    | 'DISCRETE' | 'CAP CHIP 0.01U 25V(+-10%,X7R,0402)SAM'                        | 'CHIP0402'     | ''          | ''   | '20220926'
 '0.01UF'   | '25V'   | '10%'     | 'C0402'     | 'EMPTY'   | 'CH3104K1B12'(!)   = ''              | ''                 | ''       | 'CH3104K1B12'     |'C0402'| '(C0402-0201)'                                                       | 'NA'       | '25V'         | '10%'    | 'IO'       | 'CAP CHIP 0.01U 25V(+-10%,X7R,0402)SAM'                        | 'CHIP0402'     | ''          | ''   | '20220926'
 '470PF'    | '50V'   | '10%'     | 'C0402'     | 'X7R'     | 'CH1476K1B14'(!)   = ''              | ''                 | ''       | 'CH1476K1B14'     |'C0402'| '(C0402-0201)'                                                       | '470PF'    | '50V'         | '10%'    | 'DISCRETE' | 'CAP CHIP 470P 50V(+-10%,X7R,0402)SAM'                         | 'CHIP0402'     | ''          | ''   | '20220926'
 '470PF'    | '50V'   | '10%'     | 'C0402'     | 'EMPTY'   | 'CH1476K1B14'(!)   = ''              | ''                 | ''       | 'CH1476K1B14'     |'C0402'| '(C0402-0201)'                                                       | 'NA'       | '50V'         | '10%'    | 'IO'       | 'CAP CHIP 470P 50V(+-10%,X7R,0402)SAM'                         | 'CHIP0402'     | ''          | ''   | '20220926'
 '22UF'     | '6.3V'  | '20%'     | 'C0805'     | 'X7T'     | 'CH6221MJA01'(!)   = 'End of Design' | 'Comp-Release Qty' | ''       | 'CH6221MJA01'     |'C0805_H57'| '(SMC0805AW)'                                                        | '22UF'     | '6.3V'        | '20%'    | 'DISCRETE' | 'CAP CHIP 22U 6.3V(+-20%,X7T,0805)'                            | 'CHIP0805'     | ''          | ''   | '20220929'
 '22UF'     | '6.3V'  | '20%'     | 'C0805'     | 'EMPTY'   | 'CH6221MJA01'(!)   = 'End of Design' | 'Comp-Release Qty' | ''       | 'CH6221MJA01'     |'C0805_H57'| '(SMC0805AW)'                                                        | 'NA'       | '6.3V'        | '20%'    | 'IO'       | 'CAP CHIP 22U 6.3V(+-20%,X7T,0805)'                            | 'CHIP0805'     | ''          | ''   | '20220929'
 '0.22UF'   | '6.3V'  | '10%'     | 'C0201'     | 'X6S'     | 'CH4221KEE04'(!)   = ''              | ''                 | ''       | 'CH4221KEE04'     |'C0201'| '(SMC0201AW)'                                                        | '0.22UF'   | '6.3V'        | '10%'    | 'DISCRETE' | 'CAP CHIP 0.22UF 6.3V(+-10%,X6S,0201)SAM'                      | 'CHIP0201'     | ''          | ''   | '20221017'
 '0.22UF'   | '6.3V'  | '10%'     | 'C0201'     | 'EMPTY'   | 'CH4221KEE04'(!)   = ''              | ''                 | ''       | 'CH4221KEE04'     |'C0201'| '(SMC0201AW)'                                                        | 'NA'       | '6.3V'        | '10%'    | 'IO'       | 'CAP CHIP 0.22UF 6.3V(+-10%,X6S,0201)SAM'                      | 'CHIP0201'     | ''          | ''   | '20221017'
 '1UF'      | '25V'   | '10%'     | 'C0603'     | 'X7R'     | 'CH5104K1909'(!)   = ''              | ''                 | ''       | 'CH5104K1909'     |'C0603'| '(SMC0603AW)'                                                        | '1UF'      | '25V'         | '10%'    | 'DISCRETE' | 'CAP CHIP 1U 25V(+-10%,X7R,0603)YGO'                           | 'CHIP0603'     | ''          | ''   | '20221017'
 '1UF'      | '25V'   | '10%'     | 'C0603'     | 'EMPTY'   | 'CH5104K1909'(!)   = ''              | ''                 | ''       | 'CH5104K1909'     |'C0603'| '(SMC0603AW)'                                                        | 'NA'       | '25V'         | '10%'    | 'IO'       | 'CAP CHIP 1U 25V(+-10%,X7R,0603)YGO'                           | 'CHIP0603'     | ''          | ''   | '20221017'
 '10PF'     | '50V'   | '2%'      | 'C0402'     | 'NPO'     | 'CH0106G0B07'(!)   = ''              | ''                 | ''       | 'CH0106G0B07'     |'C0402'| '(C0402-0201)'                                                       | '10PF'     | '50V'         | '2%'     | 'DISCRETE' | 'CAP CHIP 10P 50V(+-2%,NPO,0402)YGO'                           | 'CHIP0402'     | ''          | ''   | '20221017'
 '10PF'     | '50V'   | '2%'      | 'C0402'     | 'EMPTY'   | 'CH0106G0B07'(!)   = ''              | ''                 | ''       | 'CH0106G0B07'     |'C0402'| '(C0402-0201)'                                                       | 'NA'       | '50V'         | '2%'     | 'IO'       | 'CAP CHIP 10P 50V(+-2%,NPO,0402)YGO'                           | 'CHIP0402'     | ''          | ''   | '20221017'
 '10UF'     | '25V'   | '10%'     | 'C0805'     | 'X6S'     | 'CH6104KEA08'(!)   = ''              | ''                 | ''       | 'CH6104KEA08'     |'C0805_H57'| '(SMC0805AW)'                                                        | '10UF'     | '25V'         | '10%'    | 'DISCRETE' | 'CAP CHIP 10U 25V(+-10%,X6S,0805)TAY'                          | 'CHIP0805'     | ''          | ''   | '20221017'
 '10UF'     | '25V'   | '10%'     | 'C0805'     | 'EMPTY'   | 'CH6104KEA08'(!)   = ''              | ''                 | ''       | 'CH6104KEA08'     |'C0805_H57'| '(SMC0805AW)'                                                        | 'NA'       | '25V'         | '10%'    | 'IO'       | 'CAP CHIP 10U 25V(+-10%,X6S,0805)TAY'                          | 'CHIP0805'     | ''          | ''   | '20221017'
 '0.1UF'    | '10V'   | '10%'     | 'C0201'     | 'X7S'     | 'CH4102K6E00'(!)   = 'End of Design' | 'Comp-Approve'     | ''       | 'CH4102K6E00'     |'C0201'| '(SMC0201AW)'                                                        | '0.1UF'    | '10V'         | '10%'    | 'DISCRETE' | 'CAP CHIP 0.1U 10V(+-10%,X7S,0201)'                            | 'CHIP0201'     | ''          | ''   | '20221017'
 '0.1UF'    | '10V'   | '10%'     | 'C0201'     | 'EMPTY'   | 'CH4102K6E00'(!)   = 'End of Design' | 'Comp-Approve'     | ''       | 'CH4102K6E00'     |'C0201'| '(SMC0201AW)'                                                        | 'NA'       | '10V'         | '10%'    | 'IO'       | 'CAP CHIP 0.1U 10V(+-10%,X7S,0201)'                            | 'CHIP0201'     | ''          | ''   | '20221017'
 '12PF'     | '50V'   | '5%'      | 'C0402'     | 'C0G'     | 'CH0126J0B13'(!)   = ''              | ''                 | ''       | 'CH0126J0B13'     |'C0402'| '(C0402-0201)'                                                       | '12PF'     | '50V'         | '5%'     | 'DISCRETE' | 'CAP CHIP 12P 50V(+-5%,C0G,0402)MUR'                           | 'CHIP0402'     | ''          | ''   | '20221019'
 '12PF'     | '50V'   | '5%'      | 'C0402'     | 'EMPTY'   | 'CH0126J0B13'(!)   = ''              | ''                 | ''       | 'CH0126J0B13'     |'C0402'| '(C0402-0201)'                                                       | 'NA'       | '50V'         | '5%'     | 'IO'       | 'CAP CHIP 12P 50V(+-5%,C0G,0402)MUR'                           | 'CHIP0402'     | ''          | ''   | '20221019'
 '1NF'      | '25V'   | '10%'     | 'C0201'     | 'X7R'     | 'CH2104K1E04'(!)   = ''              | ''                 | ''       | 'CH2104K1E04'     |'C0201'| '(SMC0201AW)'                                                        | '1NF'      | '25V'         | '10%'    | 'DISCRETE' | 'CAP CHIP 1NF 25V(+-10%,X7R,0201)MUR'                          | 'CHIP0201'     | ''          | ''   | '20221019'
 '1NF'      | '25V'   | '10%'     | 'C0201'     | 'EMPTY'   | 'CH2104K1E04'(!)   = ''              | ''                 | ''       | 'CH2104K1E04'     |'C0201'| '(SMC0201AW)'                                                        | 'NA'       | '25V'         | '10%'    | 'IO'       | 'CAP CHIP 1NF 25V(+-10%,X7R,0201)MUR'                          | 'CHIP0201'     | ''          | ''   | '20221019'
 '1.8PF'    | '50V'   | '0.1PF'   | 'C0402'     | 'NPO'     | 'CH-186B0B03'(!)   = ''              | ''                 | ''       | 'CH-186B0B03'     |'C0402'| '(C0402-0201)'                                                       | '1.8PF'    | '50V'         | '0.1PF'  | 'DISCRETE' | 'CAP CHIP 1.8P 50V(+-0.1P,NPO,0402)MUR'                        | 'CHIP0402'     | ''          | ''   | '20221101'
 '1.8PF'    | '50V'   | '0.1PF'   | 'C0402'     | 'EMPTY'   | 'CH-186B0B03'(!)   = ''              | ''                 | ''       | 'CH-186B0B03'     |'C0402'| '(C0402-0201)'                                                       | 'NA'       | '50V'         | '0.1PF'  | 'IO'       | 'CAP CHIP 1.8P 50V(+-0.1P,NPO,0402)MUR'                        | 'CHIP0402'     | ''          | ''   | '20221101'
 '0.33UF'   | '6.3V'  | '10%'     | 'C0402'     | 'X6S'     | 'CH4331KEB02'(!)   = ''              | ''                 | ''       | 'CH4331KEB02'     |'C0402'| '(C0402-0201)'                                                       | '0.33UF'   | '6.3V'        | '10%'    | 'DISCRETE' | 'CAP CHIP 0.33UF 6.3V(10%,X6S,0402)MUR'                        | 'CHIP0402'     | ''          | ''   | '20221101'
 '0.33UF'   | '6.3V'  | '10%'     | 'C0402'     | 'EMPTY'   | 'CH4331KEB02'(!)   = ''              | ''                 | ''       | 'CH4331KEB02'     |'C0402'| '(C0402-0201)'                                                       | 'NA'       | '6.3V'        | '10%'    | 'IO'       | 'CAP CHIP 0.33UF 6.3V(10%,X6S,0402)MUR'                        | 'CHIP0402'     | ''          | ''   | '20221101'
 '10PF'     | '50V'   | '1%'      | 'C0402'     | 'NPO'     | 'CH0106F0B07'(!)   = ''              | ''                 | ''       | 'CH0106F0B07'     |'C0402'| '(C0402-0201)'                                                       | '10PF'     | '50V'         | '1%'     | 'DISCRETE' | 'CAP CHIP 10PF 50V(+-1%,NPO,0402)MUR'                          | 'CHIP0402'     | ''          | ''   | '20221101'
 '10PF'     | '50V'   | '1%'      | 'C0402'     | 'EMPTY'   | 'CH0106F0B07'(!)   = ''              | ''                 | ''       | 'CH0106F0B07'     |'C0402'| '(C0402-0201)'                                                       | 'NA'       | '50V'         | '1%'     | 'IO'       | 'CAP CHIP 10PF 50V(+-1%,NPO,0402)MUR'                          | 'CHIP0402'     | ''          | ''   | '20221101'
 '120PF'    | '50V'   | '5%'      | 'C0402'     | 'NPO'     | 'CH1126J0B14'(!)   = ''              | ''                 | ''       | 'CH1126J0B14'     |'C0402'| '(C0402-0201)'                                                       | '120PF'    | '50V'         | '5%'     | 'DISCRETE' | 'CAP CHIP 120P 50V(+-5%,NPO,0402)MUR'                          | 'CHIP0402'     | ''          | ''   | '20221101'
 '120PF'    | '50V'   | '5%'      | 'C0402'     | 'EMPTY'   | 'CH1126J0B14'(!)   = ''              | ''                 | ''       | 'CH1126J0B14'     |'C0402'| '(C0402-0201)'                                                       | 'NA'       | '50V'         | '5%'     | 'IO'       | 'CAP CHIP 120P 50V(+-5%,NPO,0402)MUR'                          | 'CHIP0402'     | ''          | ''   | '20221101'
 '2.2UF'    | '16V'   | '10%'     | 'C0402'     | 'X6S'     | 'CH5223KEB03'(!)   = ''              | ''                 | ''       | 'CH5223KEB03'     |'C0402_H28'| '(C0402-0201_H28)'                                                   | '2.2UF'    | '16V'         | '10%'    | 'DISCRETE' | 'CAP CHIP 2.2U 16V(+-10%,X6S,0402)MUR'                         | 'CHIP0402'     | ''          | ''   | '20221101'
 '2.2UF'    | '16V'   | '10%'     | 'C0402'     | 'EMPTY'   | 'CH5223KEB03'(!)   = ''              | ''                 | ''       | 'CH5223KEB03'     |'C0402_H28'| '(C0402-0201_H28)'                                                   | 'NA'       | '16V'         | '10%'    | 'IO'       | 'CAP CHIP 2.2U 16V(+-10%,X6S,0402)MUR'                         | 'CHIP0402'     | ''          | ''   | '20221101'
 '22UF'     | '16V'   | '20%'     | 'C0805'     | 'X6S'     | 'CH6223MEA05'(!)   = ''              | ''                 | ''       | 'CH6223MEA05'     |'C0805_H57'| '(SMC0805AW)'                                                        | '22UF'     | '16V'         | '20%'    | 'DISCRETE' | 'CAP CHIP 22U 16V(+-20%,X6S,0805)TAY'                          | 'CHIP0805'     | ''          | ''   | '20221130'
 '22UF'     | '16V'   | '20%'     | 'C0805'     | 'EMPTY'   | 'CH6223MEA05'(!)   = ''              | ''                 | ''       | 'CH6223MEA05'     |'C0805_H57'| '(SMC0805AW)'                                                        | 'NA'       | '16V'         | '20%'    | 'IO'       | 'CAP CHIP 22U 16V(+-20%,X6S,0805)TAY'                          | 'CHIP0805'     | ''          | ''   | '20221130'
 '22UF'     | '4V'    | '20%'     | 'C0805'     | 'X6S'     | 'CH622KMEA05'(!)   = ''              | ''                 | ''       | 'CH622KMEA05'     |'C0805_H57'| '(SMC0805AW)'                                                        | '22UF'     | '4V'          | '20%'    | 'DISCRETE' | 'CAP CHIP 22U 4V(+-20%,X6S,0805)TAY'                           | 'CHIP0805'     | ''          | ''   | '20221130'
 '22UF'     | '4V'    | '20%'     | 'C0805'     | 'EMPTY'   | 'CH622KMEA05'(!)   = ''              | ''                 | ''       | 'CH622KMEA05'     |'C0805_H57'| '(SMC0805AW)'                                                        | 'NA'       | '4V'          | '20%'    | 'IO'       | 'CAP CHIP 22U 4V(+-20%,X6S,0805)TAY'                           | 'CHIP0805'     | ''          | ''   | '20221130'
 '10UF'     | '25V'   | '10%'     | 'C0805'     | 'X6S'     | 'CH6104KEA04'(!)   = ''              | ''                 | ''       | 'CH6104KEA04'     |'C0805_H57'| '(SMC0805AW)'                                                        | '10UF'     | '25V'         | '10%'    | 'DISCRETE' | 'CAP CHIP 10U 25V(10%,X6S,0805,H1.25)SAM'                      | 'CHIP0805'     | ''          | ''   | '20221208'
 '10UF'     | '25V'   | '10%'     | 'C0805'     | 'EMPTY'   | 'CH6104KEA04'(!)   = ''              | ''                 | ''       | 'CH6104KEA04'     |'C0805_H57'| '(SMC0805AW)'                                                        | 'NA'       | '25V'         | '10%'    | 'IO'       | 'CAP CHIP 10U 25V(10%,X6S,0805,H1.25)SAM'                      | 'CHIP0805'     | ''          | ''   | '20221208'
 '1PF'      | '50V'   | '0.05PF'  | 'C0402'     | 'C0G'     | 'CH-106T0B04'(!)   = ''              | ''                 | ''       | 'CH-106T0B04'     |'C0402'| '(C0402-0201)'                                                       | '1PF'      | '50V'         | '0.05PF' | 'DISCRETE' | 'CAP CHIP 1P 50V(+-0.05P,C0G,0402)WTC'                         | 'CHIP0402'     | ''          | ''   | '20221223'
 '1PF'      | '50V'   | '0.05PF'  | 'C0402'     | 'EMPTY'   | 'CH-106T0B04'(!)   = ''              | ''                 | ''       | 'CH-106T0B04'     |'C0402'| '(C0402-0201)'                                                       | 'NA'       | '50V'         | '0.05PF' | 'IO'       | 'CAP CHIP 1P 50V(+-0.05P,C0G,0402)WTC'                         | 'CHIP0402'     | ''          | ''   | '20221223'
 '150PF'    | '50V'   | '5%'      | 'C0402'     | 'NPO'     | 'CH1156J0B07'(!)   = ''              | ''                 | ''       | 'CH1156J0B07'     |'C0402'| '(C0402-0201)'                                                       | '150PF'    | '50V'         | '5%'     | 'DISCRETE' | 'CAP CHIP 150P 50V(+-5%,NPO,0402)WTC'                          | 'CHIP0402'     | ''          | ''   | '20221223'
 '150PF'    | '50V'   | '5%'      | 'C0402'     | 'EMPTY'   | 'CH1156J0B07'(!)   = ''              | ''                 | ''       | 'CH1156J0B07'     |'C0402'| '(C0402-0201)'                                                       | 'NA'       | '50V'         | '5%'     | 'IO'       | 'CAP CHIP 150P 50V(+-5%,NPO,0402)WTC'                          | 'CHIP0402'     | ''          | ''   | '20221223'
 '10UF'     | '10V'   | '20%'     | 'C0402'     | 'X5R'     | 'CH6102M9B09'(!)   = ''              | ''                 | ''       | 'CH6102M9B09'     |'C0402_H28'| '(C0402-0201_H28)'                                                   | '10UF'     | '10V'         | '20%'    | 'DISCRETE' | 'CAP CHIP 10U 10V(+-20%, X5R,0402)MUR'                         | 'CHIP0402'     | ''          | ''   | '20221223'
 '10UF'     | '10V'   | '20%'     | 'C0402'     | 'EMPTY'   | 'CH6102M9B09'(!)   = ''              | ''                 | ''       | 'CH6102M9B09'     |'C0402_H28'| '(C0402-0201_H28)'                                                   | 'NA'       | '10V'         | '20%'    | 'IO'       | 'CAP CHIP 10U 10V(+-20%, X5R,0402)MUR'                         | 'CHIP0402'     | ''          | ''   | '20221223'
 '2.2UF'    | '25V'   | '10%'     | 'C0402'     | 'X6S'     | 'CH5224KEB00'(!)   = ''              | ''                 | ''       | 'CH5224KEB00'     |'C0402_H28'| '(C0402-0201_H28)'                                                   | '2.2UF'    | '25V'         | '10%'    | 'DISCRETE' | 'CAP CHIP 2.2U 25V(+-10%,X6S,0402)MUR'                         | 'CHIP0402'     | ''          | ''   | '20221226'
 '2.2UF'    | '25V'   | '10%'     | 'C0402'     | 'EMPTY'   | 'CH5224KEB00'(!)   = ''              | ''                 | ''       | 'CH5224KEB00'     |'C0402_H28'| '(C0402-0201_H28)'                                                   | 'NA'       | '25V'         | '10%'    | 'IO'       | 'CAP CHIP 2.2U 25V(+-10%,X6S,0402)MUR'                         | 'CHIP0402'     | ''          | ''   | '20221226'
 '3.9PF'    | '50V'   | '0.1PF'   | 'C0402'     | 'NP0'     | 'CH-396B0B01'(!)   = ''              | ''                 | ''       | 'CH-396B0B01'     |'C0402'| '(C0402-0201)'                                                       | '3.9PF'    | '50V'         | '0.1PF'  | 'DISCRETE' | 'CAP CHIP 3.9P 50V(+-0.1P,NP0,0402)WTC'                        | 'CHIP0402'     | ''          | ''   | '20221227'
 '3.9PF'    | '50V'   | '0.1PF'   | 'C0402'     | 'EMPTY'   | 'CH-396B0B01'(!)   = ''              | ''                 | ''       | 'CH-396B0B01'     |'C0402'| '(C0402-0201)'                                                       | 'NA'       | '50V'         | '0.1PF'  | 'IO'       | 'CAP CHIP 3.9P 50V(+-0.1P,NP0,0402)WTC'                        | 'CHIP0402'     | ''          | ''   | '20221227'
 '10PF'     | '50V'   | '1%'      | 'C0402'     | 'NPO'     | 'CH0106F0B08'(!)   = ''              | ''                 | ''       | 'CH0106F0B08'     |'C0402'| '(C0402-0201)'                                                       | '10PF'     | '50V'         | '1%'     | 'DISCRETE' | 'CAP CHIP 10PF 50V(+-1%,NPO,0402)WTC'                          | 'CHIP0402'     | ''          | ''   | '20230104'
 '10PF'     | '50V'   | '1%'      | 'C0402'     | 'EMPTY'   | 'CH0106F0B08'(!)   = ''              | ''                 | ''       | 'CH0106F0B08'     |'C0402'| '(C0402-0201)'                                                       | 'NA'       | '50V'         | '1%'     | 'IO'       | 'CAP CHIP 10PF 50V(+-1%,NPO,0402)WTC'                          | 'CHIP0402'     | ''          | ''   | '20230104'
 '1.8PF'    | '50V'   | '0.1PF'   | 'C0402'     | 'NPO'     | 'CH-186B0B05'(!)   = ''              | ''                 | ''       | 'CH-186B0B05'     |'C0402'| '(C0402-0201)'                                                       | '1.8PF'    | '50V'         | '0.1PF'  | 'DISCRETE' | 'CAP CHIP 1.8P 50V(+-0.1P,NPO,0402)WTC'                        | 'CHIP0402'     | ''          | ''   | '20230104'
 '1.8PF'    | '50V'   | '0.1PF'   | 'C0402'     | 'EMPTY'   | 'CH-186B0B05'(!)   = ''              | ''                 | ''       | 'CH-186B0B05'     |'C0402'| '(C0402-0201)'                                                       | 'NA'       | '50V'         | '0.1PF'  | 'IO'       | 'CAP CHIP 1.8P 50V(+-0.1P,NPO,0402)WTC'                        | 'CHIP0402'     | ''          | ''   | '20230104'
 '120PF'    | '50V'   | '5%'      | 'C0402'     | 'NPO'     | 'CH1126J0B09'(!)   = ''              | ''                 | ''       | 'CH1126J0B09'     |'C0402'| '(C0402-0201)'                                                       | '120PF'    | '50V'         | '5%'     | 'DISCRETE' | 'CAP CHIP 120P 50V(+-5%,NPO,0402)WTC'                          | 'CHIP0402'     | ''          | ''   | '20230104'
 '120PF'    | '50V'   | '5%'      | 'C0402'     | 'EMPTY'   | 'CH1126J0B09'(!)   = ''              | ''                 | ''       | 'CH1126J0B09'     |'C0402'| '(C0402-0201)'                                                       | 'NA'       | '50V'         | '5%'     | 'IO'       | 'CAP CHIP 120P 50V(+-5%,NPO,0402)WTC'                          | 'CHIP0402'     | ''          | ''   | '20230104'
 '0.33UF'   | '6.3V'  | '10%'     | 'C0402'     | 'X6S'     | 'CH4331KEB03'(!)   = ''              | ''                 | ''       | 'CH4331KEB03'     |'C0402'| '(C0402-0201)'                                                       | '0.33UF'   | '6.3V'        | '10%'    | 'DISCRETE' | 'CAP CHIP 0.33U 6.3V(+-10%,X6S,0402)API'                       | 'CHIP0402'     | ''          | ''   | '20230106'
 '0.33UF'   | '6.3V'  | '10%'     | 'C0402'     | 'EMPTY'   | 'CH4331KEB03'(!)   = ''              | ''                 | ''       | 'CH4331KEB03'     |'C0402'| '(C0402-0201)'                                                       | 'NA'       | '6.3V'        | '10%'    | 'IO'       | 'CAP CHIP 0.33U 6.3V(+-10%,X6S,0402)API'                       | 'CHIP0402'     | ''          | ''   | '20230106'
 '1000PF'   | '100V'  | '10%'     | 'C0402'     | 'X7R'     | 'CH2108K1B03'(!)   = ''              | ''                 | ''       | 'CH2108K1B03'     |'C0402_OCTAGONXA_BOUND22'| '(SMC0402AW)'                                                        | '1000PF'   | '100V'        | '10%'    | 'DISCRETE' | 'CAP CHIP 1000P 100V(+-10%,X7R,0402)MUR_OCTAGON'               | 'CHIP0402'     | ''          | ''   | '20230221'
 '1000PF'   | '100V'  | '10%'     | 'C0402'     | 'EMPTY'   | 'CH2108K1B03'(!)   = ''              | ''                 | ''       | 'CH2108K1B03'     |'C0402_OCTAGONXA_BOUND22'| '(SMC0402AW)'                                                        | 'NA'       | '100V'        | '10%'    | 'IO'       | 'CAP CHIP 1000P 100V(+-10%,X7R,0402)MUR_OCTAGON'               | 'CHIP0402'     | ''          | ''   | '20230221'
 '2.7PF'    | '50V'   | '0.1PF'   | 'C0402'     | 'NPO'     | 'CH-276B0B00'(!)   = ''              | ''                 | ''       | 'CH-276B0B00'     |'C0402'| '(C0402-0201)'                                                       | '2.7PF'    | '50V'         | '0.1PF'  | 'DISCRETE' | 'CAP CHIP 2.7P 50V(+-0.1P,NPO,0402)'                           | 'CHIP0402'     | ''          | ''   | '20230316'
 '2.7PF'    | '50V'   | '0.1PF'   | 'C0402'     | 'EMPTY'   | 'CH-276B0B00'(!)   = ''              | ''                 | ''       | 'CH-276B0B00'     |'C0402'| '(C0402-0201)'                                                       | 'NA'       | '50V'         | '0.1PF'  | 'IO'       | 'CAP CHIP 2.7P 50V(+-0.1P,NPO,0402)'                           | 'CHIP0402'     | ''          | ''   | '20230316'
 '620PF'    | '25V'   | '5%'      | 'C0603'     | 'C0G'     | 'CH1624J0900'(!)   = ''              | ''                 | ''       | 'CH1624J0900'     |'C0603'| '(SMC0603AW)'                                                        | '620PF'    | '25V'         | '5%'     | 'DISCRETE' | 'CAP CHIP 620PF 25V(+-5%,C0G,0603)'                            | 'CHIP0603'     | ''          | ''   | '20230407'
 '620PF'    | '25V'   | '5%'      | 'C0603'     | 'EMPTY'   | 'CH1624J0900'(!)   = ''              | ''                 | ''       | 'CH1624J0900'     |'C0603'| '(SMC0603AW)'                                                        | 'NA'       | '25V'         | '5%'     | 'IO'       | 'CAP CHIP 620PF 25V(+-5%,C0G,0603)'                            | 'CHIP0603'     | ''          | ''   | '20230407'
 '100PF'    | '100V'  | '5%'      | 'C0805'     | 'NPO'     | 'CH1108J0A00'(!)   = ''              | ''                 | ''       | 'CH1108J0A00'     |'C0805'| '(SMC0805AW)'                                                        | '100PF'    | '100V'        | '5%'     | 'DISCRETE' | 'CAP CHIP 100P,100V(+-5%,NPO,0805)'                            | 'CHIP0805'     | ''          | ''   | '20230504'
 '100PF'    | '100V'  | '5%'      | 'C0805'     | 'EMPTY'   | 'CH1108J0A00'(!)   = ''              | ''                 | ''       | 'CH1108J0A00'     |'C0805'| '(SMC0805AW)'                                                        | 'NA'       | '100V'        | '5%'     | 'IO'       | 'CAP CHIP 100P,100V(+-5%,NPO,0805)'                            | 'CHIP0805'     | ''          | ''   | '20230504'
 '180PF'    | '50V'   | '5%'      | 'C0402'     | 'NPO'     | 'CH1186J0B16'(!)   = ''              | ''                 | ''       | 'CH1186J0B16'     |'C0402'| '(C0402-0201)'                                                       | '180PF'    | '50V'         | '5%'     | 'DISCRETE' | 'CAP CHIP 180P 50V(+-5%,NPO,0402)WTC'                          | 'CHIP0402'     | ''          | ''   | '20230515'
 '180PF'    | '50V'   | '5%'      | 'C0402'     | 'EMPTY'   | 'CH1186J0B16'(!)   = ''              | ''                 | ''       | 'CH1186J0B16'     |'C0402'| '(C0402-0201)'                                                       | 'NA'       | '50V'         | '5%'     | 'IO'       | 'CAP CHIP 180P 50V(+-5%,NPO,0402)WTC'                          | 'CHIP0402'     | ''          | ''   | '20230515'
 '1000PF'   | '100V'  | '10%'     | 'C0603'     | 'X7R'     | 'CH21008K918'(!)   = ''              | ''                 | ''       | 'CH21008K918'     |'C0603'| '(SMC0603AW)'                                                        | '1000PF'   | '100V'        | '10%'    | 'DISCRETE' | 'CAP CHIP 1000P,100V(+-10%,X7R,0603)'                          | 'CHIP0603'     | ''          | ''   | '20230526'
 '1000PF'   | '100V'  | '10%'     | 'C0603'     | 'EMPTY'   | 'CH21008K918'(!)   = ''              | ''                 | ''       | 'CH21008K918'     |'C0603'| '(SMC0603AW)'                                                        | 'NA'       | '100V'        | '10%'    | 'IO'       | 'CAP CHIP 1000P,100V(+-10%,X7R,0603)'                          | 'CHIP0603'     | ''          | ''   | '20230526'
 '47UF'     | '4V'    | '20%'     | 'C0603'     | 'X6S'     | 'CH647KME901'(!)   = ''              | ''                 | ''       | 'CH647KME901'     |'C0603_H40'| '(C0603_BHS-SP)'                                                     | '47UF'     | '4V'          | '20%'    | 'DISCRETE' | 'CAP CHIP 47U 4V(+-20%,X6S,0603)TAY'                           | 'CHIP0603'     | ''          | ''   | '20230606'
 '47UF'     | '4V'    | '20%'     | 'C0603'     | 'EMPTY'   | 'CH647KME901'(!)   = ''              | ''                 | ''       | 'CH647KME901'     |'C0603_H40'| '(C0603_BHS-SP)'                                                     | 'NA'       | '4V'          | '20%'    | 'IO'       | 'CAP CHIP 47U 4V(+-20%,X6S,0603)TAY'                           | 'CHIP0603'     | ''          | ''   | '20230606'
 '330PF'    | '50V'   | '5%'      | 'C0402'     | 'X7R'     | 'CH1336J1B06'(!)   = ''              | ''                 | ''       | 'CH1336J1B06'     |'C0402'| '(C0402-0201)'                                                       | '330PF'    | '50V'         | '5%'     | 'DISCRETE' | 'CAP CHIP 330P 50V(+-5%,X7R,0402)YGO'                          | 'CHIP0402'     | ''          | ''   | '20230608'
 '330PF'    | '50V'   | '5%'      | 'C0402'     | 'EMPTY'   | 'CH1336J1B06'(!)   = ''              | ''                 | ''       | 'CH1336J1B06'     |'C0402'| '(C0402-0201)'                                                       | 'NA'       | '50V'         | '5%'     | 'IO'       | 'CAP CHIP 330P 50V(+-5%,X7R,0402)YGO'                          | 'CHIP0402'     | ''          | ''   | '20230608'
 '220PF'    | '50V'   | '10%'     | 'C0402'     | 'X7R'     | 'CH1226K1B19'(!)   = ''              | ''                 | ''       | 'CH1226K1B19'     |'C0402'| '(C0402-0201)'                                                       | '220PF'    | '50V'         | '10%'    | 'DISCRETE' | 'CAP CHIP 220P 50V(+-10%,X7R,0402)WTC'                         | 'CHIP0402'     | ''          | ''   | '20230608'
 '220PF'    | '50V'   | '10%'     | 'C0402'     | 'EMPTY'   | 'CH1226K1B19'(!)   = ''              | ''                 | ''       | 'CH1226K1B19'     |'C0402'| '(C0402-0201)'                                                       | 'NA'       | '50V'         | '10%'    | 'IO'       | 'CAP CHIP 220P 50V(+-10%,X7R,0402)WTC'                         | 'CHIP0402'     | ''          | ''   | '20230608'
 '0.33UF'   | '6.3V'  | '10%'     | 'C0402'     | 'X5R'     | 'CH4331K9B08'(!)   = ''              | ''                 | ''       | 'CH4331K9B08'     |'C0402'| '(C0402-0201)'                                                       | '0.33UF'   | '6.3V'        | '10%'    | 'DISCRETE' | 'CAP CHIP 0.33U 6.3V(10%,X5R,0402)MUR'                         | 'CHIP0402'     | ''          | ''   | '20230621'
 '0.33UF'   | '6.3V'  | '10%'     | 'C0402'     | 'EMPTY'   | 'CH4331K9B08'(!)   = ''              | ''                 | ''       | 'CH4331K9B08'     |'C0402'| '(C0402-0201)'                                                       | 'NA'       | '6.3V'        | '10%'    | 'IO'       | 'CAP CHIP 0.33U 6.3V(10%,X5R,0402)MUR'                         | 'CHIP0402'     | ''          | ''   | '20230621'
 '0.33UF'   | '6.3V'  | '10%'     | 'C0402'     | 'X5R'     | 'CH4331K9B10'(!)   = ''              | ''                 | ''       | 'CH4331K9B10'     |'C0402'| '(C0402-0201)'                                                       | '0.33UF'   | '6.3V'        | '10%'    | 'DISCRETE' | 'CAP CHIP 0.33U 6.3V(10%,X5R,0402)YGO'                         | 'CHIP0402'     | ''          | ''   | '20230626'
 '0.33UF'   | '6.3V'  | '10%'     | 'C0402'     | 'EMPTY'   | 'CH4331K9B10'(!)   = ''              | ''                 | ''       | 'CH4331K9B10'     |'C0402'| '(C0402-0201)'                                                       | 'NA'       | '6.3V'        | '10%'    | 'IO'       | 'CAP CHIP 0.33U 6.3V(10%,X5R,0402)YGO'                         | 'CHIP0402'     | ''          | ''   | '20230626'
 '2.2UF'    | '25V'   | '20%'     | 'C0402'     | 'X6S'     | 'CH5224MEB06'(!)   = ''              | ''                 | ''       | 'CH5224MEB06'     |'C0402_H28'| '(C0402-0201_H28)'                                                   | '2.2UF'    | '25V'         | '20%'    | 'DISCRETE' | 'CAP CHIP 2.2U 25V(+-20%,X6S,0402)SAM'                         | 'CHIP0402'     | ''          | ''   | '20230626'
 '2.2UF'    | '25V'   | '20%'     | 'C0402'     | 'EMPTY'   | 'CH5224MEB06'(!)   = ''              | ''                 | ''       | 'CH5224MEB06'     |'C0402_H28'| '(C0402-0201_H28)'                                                   | 'NA'       | '25V'         | '20%'    | 'IO'       | 'CAP CHIP 2.2U 25V(+-20%,X6S,0402)SAM'                         | 'CHIP0402'     | ''          | ''   | '20230626'
 '2.2UF'    | '25V'   | '20%'     | 'C0402'     | 'X6S'     | 'CH5224MEB05'(!)   = ''              | ''                 | ''       | 'CH5224MEB05'     |'C0402_H28'| '(C0402-0201_H28)'                                                   | '2.2UF'    | '25V'         | '20%'    | 'DISCRETE' | 'CAP CHIP 2.2UF 25V(+-20%,X6S,0402)MUR'                        | 'CHIP0402'     | ''          | ''   | '20230705'
 '2.2UF'    | '25V'   | '20%'     | 'C0402'     | 'EMPTY'   | 'CH5224MEB05'(!)   = ''              | ''                 | ''       | 'CH5224MEB05'     |'C0402_H28'| '(C0402-0201_H28)'                                                   | 'NA'       | '25V'         | '20%'    | 'IO'       | 'CAP CHIP 2.2UF 25V(+-20%,X6S,0402)MUR'                        | 'CHIP0402'     | ''          | ''   | '20230705'
 '10PF'     | '50V'   | '2%'      | 'C0402'     | 'NPO'     | 'CH0106G0B03SEL1'(!) = ''              | ''                 | ''       | 'CH0106G0B03SEL1' |'C0402'| '(C0402-0201)'                                                       | '10PF'     | '50V'         | '2%'     | 'DISCRETE' | 'CAP CHIP 10P 50V(+-2%,NPO,0402)MURSELA'                       | 'CHIP0402'     | ''          | ''   | '20230713'
 '10PF'     | '50V'   | '2%'      | 'C0402'     | 'EMPTY'   | 'CH0106G0B03SEL1'(!) = ''              | ''                 | ''       | 'CH0106G0B03SEL1' |'C0402'| '(C0402-0201)'                                                       | 'NA'       | '50V'         | '2%'     | 'IO'       | 'CAP CHIP 10P 50V(+-2%,NPO,0402)MURSELA'                       | 'CHIP0402'     | ''          | ''   | '20230713'
 '10PF'     | '50V'   | '5%'      | 'C0402'     | 'C0G'     | 'CH0106J0B18SEL1'(!) = ''              | ''                 | ''       | 'CH0106J0B18SEL1' |'C0402'| '(C0402-0201)'                                                       | '10PF'     | '50V'         | '5%'     | 'DISCRETE' | 'CAP CHIP 10P 50V(+-5%,C0G,0402)YGOSELASN'                     | 'CHIP0402'     | ''          | ''   | '20230713'
 '10PF'     | '50V'   | '5%'      | 'C0402'     | 'EMPTY'   | 'CH0106J0B18SEL1'(!) = ''              | ''                 | ''       | 'CH0106J0B18SEL1' |'C0402'| '(C0402-0201)'                                                       | 'NA'       | '50V'         | '5%'     | 'IO'       | 'CAP CHIP 10P 50V(+-5%,C0G,0402)YGOSELASN'                     | 'CHIP0402'     | ''          | ''   | '20230713'
 '12PF'     | '50V'   | '5%'      | 'C0402'     | 'C0G'     | 'CH0126J0B13SEL1'(!) = ''              | ''                 | ''       | 'CH0126J0B13SEL1' |'C0402'| '(C0402-0201)'                                                       | '12PF'     | '50V'         | '5%'     | 'DISCRETE' | 'CAP CHIP 12P 50V(+-5%,C0G,0402)MURSELA'                       | 'CHIP0402'     | ''          | ''   | '20230713'
 '12PF'     | '50V'   | '5%'      | 'C0402'     | 'EMPTY'   | 'CH0126J0B13SEL1'(!) = ''              | ''                 | ''       | 'CH0126J0B13SEL1' |'C0402'| '(C0402-0201)'                                                       | 'NA'       | '50V'         | '5%'     | 'IO'       | 'CAP CHIP 12P 50V(+-5%,C0G,0402)MURSELA'                       | 'CHIP0402'     | ''          | ''   | '20230713'
 '15PF'     | '50V'   | '5%'      | 'C0402'     | 'C0G'     | 'CH0156J0B07SEL1'(!) = ''              | ''                 | ''       | 'CH0156J0B07SEL1' |'C0402'| '(C0402-0201)'                                                       | '15PF'     | '50V'         | '5%'     | 'DISCRETE' | 'CAP CHIP 15P 50V(+-5% C0G 0402)MURSELA'                       | 'CHIP0402'     | ''          | ''   | '20230713'
 '15PF'     | '50V'   | '5%'      | 'C0402'     | 'EMPTY'   | 'CH0156J0B07SEL1'(!) = ''              | ''                 | ''       | 'CH0156J0B07SEL1' |'C0402'| '(C0402-0201)'                                                       | 'NA'       | '50V'         | '5%'     | 'IO'       | 'CAP CHIP 15P 50V(+-5% C0G 0402)MURSELA'                       | 'CHIP0402'     | ''          | ''   | '20230713'
 '18PF'     | '50V'   | '5%'      | 'C0402'     | 'C0G'     | 'CH0186J0B05SEL1'(!) = ''              | ''                 | ''       | 'CH0186J0B05SEL1' |'C0402'| '(C0402-0201)'                                                       | '18PF'     | '50V'         | '5%'     | 'DISCRETE' | 'CAP CHIP 18P 50V(+-5% C0G 0402)MURSELA'                       | 'CHIP0402'     | ''          | ''   | '20230713'
 '18PF'     | '50V'   | '5%'      | 'C0402'     | 'EMPTY'   | 'CH0186J0B05SEL1'(!) = ''              | ''                 | ''       | 'CH0186J0B05SEL1' |'C0402'| '(C0402-0201)'                                                       | 'NA'       | '50V'         | '5%'     | 'IO'       | 'CAP CHIP 18P 50V(+-5% C0G 0402)MURSELA'                       | 'CHIP0402'     | ''          | ''   | '20230713'
 '22PF'     | '50V'   | '5%'      | 'C0402'     | 'NPO'     | 'CH0226J0B16SEL1'(!) = ''              | ''                 | ''       | 'CH0226J0B16SEL1' |'C0402'| '(C0402-0201)'                                                       | '22PF'     | '50V'         | '5%'     | 'DISCRETE' | 'CAP CHIP 22P 50V(+-5%,NPO,0402)MURSELASN'                     | 'CHIP0402'     | ''          | ''   | '20230713'
 '22PF'     | '50V'   | '5%'      | 'C0402'     | 'EMPTY'   | 'CH0226J0B16SEL1'(!) = ''              | ''                 | ''       | 'CH0226J0B16SEL1' |'C0402'| '(C0402-0201)'                                                       | 'NA'       | '50V'         | '5%'     | 'IO'       | 'CAP CHIP 22P 50V(+-5%,NPO,0402)MURSELASN'                     | 'CHIP0402'     | ''          | ''   | '20230713'
 '27PF'     | '50V'   | '5%'      | 'C0402'     | 'NPO'     | 'CH0276J0B09SEL1'(!) = ''              | ''                 | ''       | 'CH0276J0B09SEL1' |'C0402'| '(C0402-0201)'                                                       | '27PF'     | '50V'         | '5%'     | 'DISCRETE' | 'CAP CHIP 27P 50V(+-5%,NPO,0402)MURSELA'                       | 'CHIP0402'     | ''          | ''   | '20230713'
 '27PF'     | '50V'   | '5%'      | 'C0402'     | 'EMPTY'   | 'CH0276J0B09SEL1'(!) = ''              | ''                 | ''       | 'CH0276J0B09SEL1' |'C0402'| '(C0402-0201)'                                                       | 'NA'       | '50V'         | '5%'     | 'IO'       | 'CAP CHIP 27P 50V(+-5%,NPO,0402)MURSELA'                       | 'CHIP0402'     | ''          | ''   | '20230713'
 '47PF'     | '50V'   | '5%'      | 'C0402'     | 'NPO'     | 'CH0476J0B11SEL1'(!) = ''              | ''                 | ''       | 'CH0476J0B11SEL1' |'C0402'| '(C0402-0201)'                                                       | '47PF'     | '50V'         | '5%'     | 'DISCRETE' | 'CAP CHIP 47P 50V(+-5%,NPO,0402)SAMSELASN'                     | 'CHIP0402'     | ''          | ''   | '20230713'
 '47PF'     | '50V'   | '5%'      | 'C0402'     | 'EMPTY'   | 'CH0476J0B11SEL1'(!) = ''              | ''                 | ''       | 'CH0476J0B11SEL1' |'C0402'| '(C0402-0201)'                                                       | 'NA'       | '50V'         | '5%'     | 'IO'       | 'CAP CHIP 47P 50V(+-5%,NPO,0402)SAMSELASN'                     | 'CHIP0402'     | ''          | ''   | '20230713'
 '47PF'     | '50V'   | '5%'      | 'C0402'     | 'NPO'     | 'CH0476J0B12SEL1'(!) = ''              | ''                 | ''       | 'CH0476J0B12SEL1' |'C0402'| '(C0402-0201)'                                                       | '47PF'     | '50V'         | '5%'     | 'DISCRETE' | 'CAP CHIP 47P 50V(+-5%,NPO,0402)MURSELASN'                     | 'CHIP0402'     | ''          | ''   | '20230713'
 '47PF'     | '50V'   | '5%'      | 'C0402'     | 'EMPTY'   | 'CH0476J0B12SEL1'(!) = ''              | ''                 | ''       | 'CH0476J0B12SEL1' |'C0402'| '(C0402-0201)'                                                       | 'NA'       | '50V'         | '5%'     | 'IO'       | 'CAP CHIP 47P 50V(+-5%,NPO,0402)MURSELASN'                     | 'CHIP0402'     | ''          | ''   | '20230713'
 '100PF'    | '50V'   | '5%'      | 'C0402'     | 'NPO'     | 'CH1106J0B16SEL1'(!) = ''              | ''                 | ''       | 'CH1106J0B16SEL1' |'C0402'| '(C0402-0201)'                                                       | '100PF'    | '50V'         | '5%'     | 'DISCRETE' | 'CAP CHIP 100P 50V(5%,NPO,0402)MURSELASN'                      | 'CHIP0402'     | ''          | ''   | '20230713'
 '100PF'    | '50V'   | '5%'      | 'C0402'     | 'EMPTY'   | 'CH1106J0B16SEL1'(!) = ''              | ''                 | ''       | 'CH1106J0B16SEL1' |'C0402'| '(C0402-0201)'                                                       | 'NA'       | '50V'         | '5%'     | 'IO'       | 'CAP CHIP 100P 50V(5%,NPO,0402)MURSELASN'                      | 'CHIP0402'     | ''          | ''   | '20230713'
 '100PF'    | '50V'   | '5%'      | 'C0402'     | 'NPO'     | 'CH1106J0B23SEL1'(!) = ''              | ''                 | ''       | 'CH1106J0B23SEL1' |'C0402'| '(C0402-0201)'                                                       | '100PF'    | '50V'         | '5%'     | 'DISCRETE' | 'CAP CHIP 100P 50V(+-5%,NPO,0402)YGOSELA'                      | 'CHIP0402'     | ''          | ''   | '20230713'
 '100PF'    | '50V'   | '5%'      | 'C0402'     | 'EMPTY'   | 'CH1106J0B23SEL1'(!) = ''              | ''                 | ''       | 'CH1106J0B23SEL1' |'C0402'| '(C0402-0201)'                                                       | 'NA'       | '50V'         | '5%'     | 'IO'       | 'CAP CHIP 100P 50V(+-5%,NPO,0402)YGOSELA'                      | 'CHIP0402'     | ''          | ''   | '20230713'
 '220PF'    | '50V'   | '5%'      | 'C0402'     | 'COG'     | 'CH1226J0B03SEL1'(!) = ''              | ''                 | ''       | 'CH1226J0B03SEL1' |'C0402'| '(C0402-0201)'                                                       | '220PF'    | '50V'         | '5%'     | 'DISCRETE' | 'CAP CHIP 220P 50V(+-5%,COG,0402)MURSELA'                      | 'CHIP0402'     | ''          | ''   | '20230713'
 '220PF'    | '50V'   | '5%'      | 'C0402'     | 'EMPTY'   | 'CH1226J0B03SEL1'(!) = ''              | ''                 | ''       | 'CH1226J0B03SEL1' |'C0402'| '(C0402-0201)'                                                       | 'NA'       | '50V'         | '5%'     | 'IO'       | 'CAP CHIP 220P 50V(+-5%,COG,0402)MURSELA'                      | 'CHIP0402'     | ''          | ''   | '20230713'
 '220PF'    | '50V'   | '5%'      | 'C0402'     | 'C0G'     | 'CH1226J0B04SEL1'(!) = ''              | ''                 | ''       | 'CH1226J0B04SEL1' |'C0402'| '(C0402-0201)'                                                       | '220PF'    | '50V'         | '5%'     | 'DISCRETE' | 'CAP CHIP 220P 50V(+-5%,C0G,0402)SAMSELA'                      | 'CHIP0402'     | ''          | ''   | '20230713'
 '220PF'    | '50V'   | '5%'      | 'C0402'     | 'EMPTY'   | 'CH1226J0B04SEL1'(!) = ''              | ''                 | ''       | 'CH1226J0B04SEL1' |'C0402'| '(C0402-0201)'                                                       | 'NA'       | '50V'         | '5%'     | 'IO'       | 'CAP CHIP 220P 50V(+-5%,C0G,0402)SAMSELA'                      | 'CHIP0402'     | ''          | ''   | '20230713'
 '220PF'    | '50V'   | '10%'     | 'C0402'     | 'X7R'     | 'CH1226K1B10SEL1'(!) = ''              | ''                 | ''       | 'CH1226K1B10SEL1' |'C0402'| '(C0402-0201)'                                                       | '220PF'    | '50V'         | '10%'    | 'DISCRETE' | 'CAP CHIP 220PF 50V(10%,X7R,0402)MURSELA'                      | 'CHIP0402'     | ''          | ''   | '20230713'
 '220PF'    | '50V'   | '10%'     | 'C0402'     | 'EMPTY'   | 'CH1226K1B10SEL1'(!) = ''              | ''                 | ''       | 'CH1226K1B10SEL1' |'C0402'| '(C0402-0201)'                                                       | 'NA'       | '50V'         | '10%'    | 'IO'       | 'CAP CHIP 220PF 50V(10%,X7R,0402)MURSELA'                      | 'CHIP0402'     | ''          | ''   | '20230713'
 '330PF'    | '50V'   | '5%'      | 'C0402'     | 'NPO'     | 'CH1336J0B10SEL1'(!) = ''              | ''                 | ''       | 'CH1336J0B10SEL1' |'C0402'| '(C0402-0201)'                                                       | '330PF'    | '50V'         | '5%'     | 'DISCRETE' | 'CAP CHIP 330P 50V(5%,NPO,0402)MURSELASN'                      | 'CHIP0402'     | ''          | ''   | '20230713'
 '330PF'    | '50V'   | '5%'      | 'C0402'     | 'EMPTY'   | 'CH1336J0B10SEL1'(!) = ''              | ''                 | ''       | 'CH1336J0B10SEL1' |'C0402'| '(C0402-0201)'                                                       | 'NA'       | '50V'         | '5%'     | 'IO'       | 'CAP CHIP 330P 50V(5%,NPO,0402)MURSELASN'                      | 'CHIP0402'     | ''          | ''   | '20230713'
 '330PF'    | '50V'   | '10%'     | 'C0402'     | 'X7R'     | 'CH1336K1B06SEL1'(!) = ''              | ''                 | ''       | 'CH1336K1B06SEL1' |'C0402'| '(C0402-0201)'                                                       | '330PF'    | '50V'         | '10%'    | 'DISCRETE' | 'CAP CHIP 330P 50V(+-10%,X7R,0402)MURSELA'                     | 'CHIP0402'     | ''          | ''   | '20230713'
 '330PF'    | '50V'   | '10%'     | 'C0402'     | 'EMPTY'   | 'CH1336K1B06SEL1'(!) = ''              | ''                 | ''       | 'CH1336K1B06SEL1' |'C0402'| '(C0402-0201)'                                                       | 'NA'       | '50V'         | '10%'    | 'IO'       | 'CAP CHIP 330P 50V(+-10%,X7R,0402)MURSELA'                     | 'CHIP0402'     | ''          | ''   | '20230713'
 '470PF'    | '50V'   | '5%'      | 'C0402'     | 'NPO'     | 'CH1476J0B04SEL1'(!) = ''              | ''                 | ''       | 'CH1476J0B04SEL1' |'C0402'| '(C0402-0201)'                                                       | '470PF'    | '50V'         | '5%'     | 'DISCRETE' | 'CAP CHIP 470P,50V(+-5%,NPO,0402)MURSELA'                      | 'CHIP0402'     | ''          | ''   | '20230713'
 '470PF'    | '50V'   | '5%'      | 'C0402'     | 'EMPTY'   | 'CH1476J0B04SEL1'(!) = ''              | ''                 | ''       | 'CH1476J0B04SEL1' |'C0402'| '(C0402-0201)'                                                       | 'NA'       | '50V'         | '5%'     | 'IO'       | 'CAP CHIP 470P,50V(+-5%,NPO,0402)MURSELA'                      | 'CHIP0402'     | ''          | ''   | '20230713'
 '470PF'    | '50V'   | '10%'     | 'C0402'     | 'X7R'     | 'CH1476K1B11SEL1'(!) = ''              | ''                 | ''       | 'CH1476K1B11SEL1' |'C0402'| '(C0402-0201)'                                                       | '470PF'    | '50V'         | '10%'    | 'DISCRETE' | 'CAP CHIP 470P 50V(10%,X7R,0402)MURSELASN'                     | 'CHIP0402'     | ''          | ''   | '20230713'
 '470PF'    | '50V'   | '10%'     | 'C0402'     | 'EMPTY'   | 'CH1476K1B11SEL1'(!) = ''              | ''                 | ''       | 'CH1476K1B11SEL1' |'C0402'| '(C0402-0201)'                                                       | 'NA'       | '50V'         | '10%'    | 'IO'       | 'CAP CHIP 470P 50V(10%,X7R,0402)MURSELASN'                     | 'CHIP0402'     | ''          | ''   | '20230713'
 '470PF'    | '50V'   | '10%'     | 'C0402'     | 'X7R'     | 'CH1476K1B14SEL1'(!) = ''              | ''                 | ''       | 'CH1476K1B14SEL1' |'C0402'| '(C0402-0201)'                                                       | '470PF'    | '50V'         | '10%'    | 'DISCRETE' | 'CAP CHIP 470P 50V(10%,X7R,0402)SAMSELASN'                     | 'CHIP0402'     | ''          | ''   | '20230713'
 '470PF'    | '50V'   | '10%'     | 'C0402'     | 'EMPTY'   | 'CH1476K1B14SEL1'(!) = ''              | ''                 | ''       | 'CH1476K1B14SEL1' |'C0402'| '(C0402-0201)'                                                       | 'NA'       | '50V'         | '10%'    | 'IO'       | 'CAP CHIP 470P 50V(10%,X7R,0402)SAMSELASN'                     | 'CHIP0402'     | ''          | ''   | '20230713'
 '680PF'    | '50V'   | '5%'      | 'C0402'     | 'C0G'     | 'CH1686J0B03SEL1'(!) = ''              | ''                 | ''       | 'CH1686J0B03SEL1' |'C0402'| '(C0402-0201)'                                                       | '680PF'    | '50V'         | '5%'     | 'DISCRETE' | 'CAP CHIP 680P 50V(+-5%,C0G,0402)MURSELA'                      | 'CHIP0402'     | ''          | ''   | '20230713'
 '680PF'    | '50V'   | '5%'      | 'C0402'     | 'EMPTY'   | 'CH1686J0B03SEL1'(!) = ''              | ''                 | ''       | 'CH1686J0B03SEL1' |'C0402'| '(C0402-0201)'                                                       | 'NA'       | '50V'         | '5%'     | 'IO'       | 'CAP CHIP 680P 50V(+-5%,C0G,0402)MURSELA'                      | 'CHIP0402'     | ''          | ''   | '20230713'
 '1000PF'   | '16V'   | '10%'     | 'C0402'     | 'X7R'     | 'CH2103K1B03SEL1'(!) = ''              | ''                 | ''       | 'CH2103K1B03SEL1' |'C0402'| '(C0402-0201)'                                                       | '1000PF'   | '16V'         | '10%'    | 'DISCRETE' | 'CAP CHIP 1000P 16V (10%,X7R,0402)MURSELA'                     | 'CHIP0402'     | ''          | ''   | '20230713'
 '1000PF'   | '16V'   | '10%'     | 'C0402'     | 'EMPTY'   | 'CH2103K1B03SEL1'(!) = ''              | ''                 | ''       | 'CH2103K1B03SEL1' |'C0402'| '(C0402-0201)'                                                       | 'NA'       | '16V'         | '10%'    | 'IO'       | 'CAP CHIP 1000P 16V (10%,X7R,0402)MURSELA'                     | 'CHIP0402'     | ''          | ''   | '20230713'
 '1NF'      | '25V'   | '10%'     | 'C0201'     | 'X7R'     | 'CH2104K1E04SEL1'(!) = ''              | ''                 | ''       | 'CH2104K1E04SEL1' |'C0201'| '(SMC0201AW)'                                                        | '1NF'      | '25V'         | '10%'    | 'DISCRETE' | 'CAP CHIP 1NF 25V(+-10%,X7R,0201)MURSELA'                      | 'CHIP0201'     | ''          | ''   | '20230713'
 '1NF'      | '25V'   | '10%'     | 'C0201'     | 'EMPTY'   | 'CH2104K1E04SEL1'(!) = ''              | ''                 | ''       | 'CH2104K1E04SEL1' |'C0201'| '(SMC0201AW)'                                                        | 'NA'       | '25V'         | '10%'    | 'IO'       | 'CAP CHIP 1NF 25V(+-10%,X7R,0201)MURSELA'                      | 'CHIP0201'     | ''          | ''   | '20230713'
 '1000PF'   | '50V'   | '5%'      | 'C0402'     | 'X7R'     | 'CH2106J1B04SEL1'(!) = ''              | ''                 | ''       | 'CH2106J1B04SEL1' |'C0402'| '(C0402-0201)'                                                       | '1000PF'   | '50V'         | '5%'     | 'DISCRETE' | 'CAP CHIP 1000P 50V(+-5%,X7R,0402)MURSELA'                     | 'CHIP0402'     | ''          | ''   | '20230713'
 '1000PF'   | '50V'   | '5%'      | 'C0402'     | 'EMPTY'   | 'CH2106J1B04SEL1'(!) = ''              | ''                 | ''       | 'CH2106J1B04SEL1' |'C0402'| '(C0402-0201)'                                                       | 'NA'       | '50V'         | '5%'     | 'IO'       | 'CAP CHIP 1000P 50V(+-5%,X7R,0402)MURSELA'                     | 'CHIP0402'     | ''          | ''   | '20230713'
 '2200PF'   | '50V'   | '5%'      | 'C0402'     | 'C0G'     | 'CH2226J0B01SEL1'(!) = ''              | ''                 | ''       | 'CH2226J0B01SEL1' |'C0402'| '(C0402-0201)'                                                       | '2200PF'   | '50V'         | '5%'     | 'DISCRETE' | 'CAP CHIP 2200P 50V(+-5%,C0G,0402)MURSELA'                     | 'CHIP0402'     | ''          | ''   | '20230713'
 '2200PF'   | '50V'   | '5%'      | 'C0402'     | 'EMPTY'   | 'CH2226J0B01SEL1'(!) = ''              | ''                 | ''       | 'CH2226J0B01SEL1' |'C0402'| '(C0402-0201)'                                                       | 'NA'       | '50V'         | '5%'     | 'IO'       | 'CAP CHIP 2200P 50V(+-5%,C0G,0402)MURSELA'                     | 'CHIP0402'     | ''          | ''   | '20230713'
 '2200PF'   | '50V'   | '10%'     | 'C0402'     | 'X7R'     | 'CH2226K1B06SEL1'(!) = ''              | ''                 | ''       | 'CH2226K1B06SEL1' |'C0402'| '(C0402-0201)'                                                       | '2200PF'   | '50V'         | '10%'    | 'DISCRETE' | 'CAP CHIP 2200P 50V(10%,X7R,0402)MURSELA'                      | 'CHIP0402'     | ''          | ''   | '20230713'
 '2200PF'   | '50V'   | '10%'     | 'C0402'     | 'EMPTY'   | 'CH2226K1B06SEL1'(!) = ''              | ''                 | ''       | 'CH2226K1B06SEL1' |'C0402'| '(C0402-0201)'                                                       | 'NA'       | '50V'         | '10%'    | 'IO'       | 'CAP CHIP 2200P 50V(10%,X7R,0402)MURSELA'                      | 'CHIP0402'     | ''          | ''   | '20230713'
 '3300PF'   | '50V'   | '10%'     | 'C0402'     | 'X7R'     | 'CH2336K1B06SEL1'(!) = ''              | ''                 | ''       | 'CH2336K1B06SEL1' |'C0402'| '(C0402-0201)'                                                       | '3300PF'   | '50V'         | '10%'    | 'DISCRETE' | 'CAP CHIP 3300P 50V(10%,X7R,0402)MURSELA'                      | 'CHIP0402'     | ''          | ''   | '20230713'
 '3300PF'   | '50V'   | '10%'     | 'C0402'     | 'EMPTY'   | 'CH2336K1B06SEL1'(!) = ''              | ''                 | ''       | 'CH2336K1B06SEL1' |'C0402'| '(C0402-0201)'                                                       | 'NA'       | '50V'         | '10%'    | 'IO'       | 'CAP CHIP 3300P 50V(10%,X7R,0402)MURSELA'                      | 'CHIP0402'     | ''          | ''   | '20230713'
 '3900PF'   | '50V'   | '10%'     | 'C0402'     | 'X7R'     | 'CH2396K1B07SEL1'(!) = ''              | ''                 | ''       | 'CH2396K1B07SEL1' |'C0402'| '(C0402-0201)'                                                       | '3900PF'   | '50V'         | '10%'    | 'DISCRETE' | 'CAP CHIP 3900P 50V(10%,X7R,0402)MURSELA'                      | 'CHIP0402'     | ''          | ''   | '20230713'
 '3900PF'   | '50V'   | '10%'     | 'C0402'     | 'EMPTY'   | 'CH2396K1B07SEL1'(!) = ''              | ''                 | ''       | 'CH2396K1B07SEL1' |'C0402'| '(C0402-0201)'                                                       | 'NA'       | '50V'         | '10%'    | 'IO'       | 'CAP CHIP 3900P 50V(10%,X7R,0402)MURSELA'                      | 'CHIP0402'     | ''          | ''   | '20230713'
 '4700PF'   | '50V'   | '5%'      | 'C0603'     | 'C0G'     | 'CH2476J0902SEL1'(!) = ''              | ''                 | ''       | 'CH2476J0902SEL1' |'C0603_H40'| '(SMC0603AW)'                                                        | '4700PF'   | '50V'         | '5%'     | 'DISCRETE' | 'CAP CHIP 4700P 50V(+-5%,C0G,0603)MURSELA'                     | 'CHIP0603'     | ''          | ''   | '20230713'
 '4700PF'   | '50V'   | '5%'      | 'C0603'     | 'EMPTY'   | 'CH2476J0902SEL1'(!) = ''              | ''                 | ''       | 'CH2476J0902SEL1' |'C0603_H40'| '(SMC0603AW)'                                                        | 'NA'       | '50V'         | '5%'     | 'IO'       | 'CAP CHIP 4700P 50V(+-5%,C0G,0603)MURSELA'                     | 'CHIP0603'     | ''          | ''   | '20230713'
 '4700PF'   | '50V'   | '5%'      | 'C0402'     | 'C0G'     | 'CH2476J0B01SEL1'(!) = ''              | ''                 | ''       | 'CH2476J0B01SEL1' |'C0402_H28'| '(C0402-0201_H28)'                                                   | '4700PF'   | '50V'         | '5%'     | 'DISCRETE' | 'CAP CHIP 4700P 50V(+-5%,C0G,0402)MURSELA'                     | 'CHIP0402'     | ''          | ''   | '20230713'
 '4700PF'   | '50V'   | '5%'      | 'C0402'     | 'EMPTY'   | 'CH2476J0B01SEL1'(!) = ''              | ''                 | ''       | 'CH2476J0B01SEL1' |'C0402_H28'| '(C0402-0201_H28)'                                                   | 'NA'       | '50V'         | '5%'     | 'IO'       | 'CAP CHIP 4700P 50V(+-5%,C0G,0402)MURSELA'                     | 'CHIP0402'     | ''          | ''   | '20230713'
 '5600PF'   | '50V'   | '10%'     | 'C0402'     | 'X7R'     | 'CH2566K1B06SEL1'(!) = ''              | ''                 | ''       | 'CH2566K1B06SEL1' |'C0402'| '(C0402-0201)'                                                       | '5600PF'   | '50V'         | '10%'    | 'DISCRETE' | 'CAP CHIP 5600PF 50V(10%,X7R,0402)SAMSELA'                     | 'CHIP0402'     | ''          | ''   | '20230713'
 '5600PF'   | '50V'   | '10%'     | 'C0402'     | 'EMPTY'   | 'CH2566K1B06SEL1'(!) = ''              | ''                 | ''       | 'CH2566K1B06SEL1' |'C0402'| '(C0402-0201)'                                                       | 'NA'       | '50V'         | '10%'    | 'IO'       | 'CAP CHIP 5600PF 50V(10%,X7R,0402)SAMSELA'                     | 'CHIP0402'     | ''          | ''   | '20230713'
 '0.01UF'   | '50V'   | '10%'     | 'C0402'     | 'X7R'     | 'CH31006KB00SEL1'(!) = ''              | ''                 | ''       | 'CH31006KB00SEL1' |'C0402'| '(C0402-0201)'                                                       | '0.01UF'   | '50V'         | '10%'    | 'DISCRETE' | 'CAP CHIP 0.01U 50V(10%,X7R,0402)MURSELA'                      | 'CHIP0402'     | ''          | ''   | '20230713'
 '0.01UF'   | '50V'   | '10%'     | 'C0402'     | 'EMPTY'   | 'CH31006KB00SEL1'(!) = ''              | ''                 | ''       | 'CH31006KB00SEL1' |'C0402'| '(C0402-0201)'                                                       | 'NA'       | '50V'         | '10%'    | 'IO'       | 'CAP CHIP 0.01U 50V(10%,X7R,0402)MURSELA'                      | 'CHIP0402'     | ''          | ''   | '20230713'
 '0.01UF'   | '16V'   | '10%'     | 'C0402'     | 'X7R'     | 'CH3103K1B16SEL1'(!) = ''              | ''                 | ''       | 'CH3103K1B16SEL1' |'C0402'| '(C0402-0201)'                                                       | '0.01UF'   | '16V'         | '10%'    | 'DISCRETE' | 'CAP CHIP 0.01U 16V(10%,X7R,0402)MURSELA'                      | 'CHIP0402'     | ''          | ''   | '20230713'
 '0.01UF'   | '16V'   | '10%'     | 'C0402'     | 'EMPTY'   | 'CH3103K1B16SEL1'(!) = ''              | ''                 | ''       | 'CH3103K1B16SEL1' |'C0402'| '(C0402-0201)'                                                       | 'NA'       | '16V'         | '10%'    | 'IO'       | 'CAP CHIP 0.01U 16V(10%,X7R,0402)MURSELA'                      | 'CHIP0402'     | ''          | ''   | '20230713'
 '0.01UF'   | '16V'   | '10%'     | 'C0402'     | 'X7R'     | 'CH3103K1B26SEL1'(!) = ''              | ''                 | ''       | 'CH3103K1B26SEL1' |'C0402'| '(C0402-0201)'                                                       | '0.01UF'   | '16V'         | '10%'    | 'DISCRETE' | 'CAP CHIP 0.01U 16V(10%,X7R,0402)YGOSELA'                      | 'CHIP0402'     | ''          | ''   | '20230713'
 '0.01UF'   | '16V'   | '10%'     | 'C0402'     | 'EMPTY'   | 'CH3103K1B26SEL1'(!) = ''              | ''                 | ''       | 'CH3103K1B26SEL1' |'C0402'| '(C0402-0201)'                                                       | 'NA'       | '16V'         | '10%'    | 'IO'       | 'CAP CHIP 0.01U 16V(10%,X7R,0402)YGOSELA'                      | 'CHIP0402'     | ''          | ''   | '20230713'
 '0.01UF'   | '25V'   | '10%'     | 'C0402'     | 'X7R'     | 'CH3104K1B11SEL1'(!) = ''              | ''                 | ''       | 'CH3104K1B11SEL1' |'C0402'| '(C0402-0201)'                                                       | '0.01UF'   | '25V'         | '10%'    | 'DISCRETE' | 'CAP CHIP 0.01U 25V(10%,X7R,0402)MURSELA'                      | 'CHIP0402'     | ''          | ''   | '20230713'
 '0.01UF'   | '25V'   | '10%'     | 'C0402'     | 'EMPTY'   | 'CH3104K1B11SEL1'(!) = ''              | ''                 | ''       | 'CH3104K1B11SEL1' |'C0402'| '(C0402-0201)'                                                       | 'NA'       | '25V'         | '10%'    | 'IO'       | 'CAP CHIP 0.01U 25V(10%,X7R,0402)MURSELA'                      | 'CHIP0402'     | ''          | ''   | '20230713'
 '0.01UF'   | '50V'   | '10%'     | 'C0402'     | 'X7R'     | 'CH3106K1B06SEL1'(!) = ''              | ''                 | ''       | 'CH3106K1B06SEL1' |'C0402'| '(C0402-0201)'                                                       | '0.01UF'   | '50V'         | '10%'    | 'DISCRETE' | 'CAP CHIP 0.01U 50V(10%,X7R,0402)SAMSELA'                      | 'CHIP0402'     | ''          | ''   | '20230713'
 '0.01UF'   | '50V'   | '10%'     | 'C0402'     | 'EMPTY'   | 'CH3106K1B06SEL1'(!) = ''              | ''                 | ''       | 'CH3106K1B06SEL1' |'C0402'| '(C0402-0201)'                                                       | 'NA'       | '50V'         | '10%'    | 'IO'       | 'CAP CHIP 0.01U 50V(10%,X7R,0402)SAMSELA'                      | 'CHIP0402'     | ''          | ''   | '20230713'
 '0.01UF'   | '50V'   | '10%'     | 'C0402'     | 'X7R'     | 'CH3106K1B10SEL1'(!) = ''              | ''                 | ''       | 'CH3106K1B10SEL1' |'C0402'| '(C0402-0201)'                                                       | '0.01UF'   | '50V'         | '10%'    | 'DISCRETE' | 'CAP CHIP 0.01U 50V(10%,X7R,0402)MURSELA'                      | 'CHIP0402'     | ''          | ''   | '20230713'
 '0.01UF'   | '50V'   | '10%'     | 'C0402'     | 'EMPTY'   | 'CH3106K1B10SEL1'(!) = ''              | ''                 | ''       | 'CH3106K1B10SEL1' |'C0402'| '(C0402-0201)'                                                       | 'NA'       | '50V'         | '10%'    | 'IO'       | 'CAP CHIP 0.01U 50V(10%,X7R,0402)MURSELA'                      | 'CHIP0402'     | ''          | ''   | '20230713'
 '0.01UF'   | '1KV'   | '10%'     | 'C1206'     | 'X7R'     | 'CH310FK1202SEL1'(!) = ''              | ''                 | ''       | 'CH310FK1202SEL1' |'C1206_H76'| '(SMC1206AW)'                                                        | '0.01UF'   | '1KV'         | '10%'    | 'DISCRETE' | 'CAP CHIP 0.01U 1KV(10%,X7R,1206)MURSELA'                      | 'CHIP1206'     | ''          | ''   | '20230713'
 '0.01UF'   | '1KV'   | '10%'     | 'C1206'     | 'EMPTY'   | 'CH310FK1202SEL1'(!) = ''              | ''                 | ''       | 'CH310FK1202SEL1' |'C1206_H76'| '(SMC1206AW)'                                                        | 'NA'       | '1KV'         | '10%'    | 'IO'       | 'CAP CHIP 0.01U 1KV(10%,X7R,1206)MURSELA'                      | 'CHIP1206'     | ''          | ''   | '20230713'
 '0.022UF'  | '50V'   | '10%'     | 'C0402'     | 'X7R'     | 'CH3226K1B08SEL1'(!) = ''              | ''                 | ''       | 'CH3226K1B08SEL1' |'C0402'| '(C0402-0201)'                                                       | '0.022UF'  | '50V'         | '10%'    | 'DISCRETE' | 'CAP CHIP 0.022U 50V(10%,X7R,0402)MURSELA'                     | 'CHIP0402'     | ''          | ''   | '20230713'
 '0.022UF'  | '50V'   | '10%'     | 'C0402'     | 'EMPTY'   | 'CH3226K1B08SEL1'(!) = ''              | ''                 | ''       | 'CH3226K1B08SEL1' |'C0402'| '(C0402-0201)'                                                       | 'NA'       | '50V'         | '10%'    | 'IO'       | 'CAP CHIP 0.022U 50V(10%,X7R,0402)MURSELA'                     | 'CHIP0402'     | ''          | ''   | '20230713'
 '0.047UF'  | '50V'   | '10%'     | 'C0402'     | 'X7R'     | 'CH3476K1B10SEL1'(!) = ''              | ''                 | ''       | 'CH3476K1B10SEL1' |'C0402'| '(C0402-0201)'                                                       | '0.047UF'  | '50V'         | '10%'    | 'DISCRETE' | 'CAP CHIP 0.047U 50V(10%,X7R,0402)MURSELA'                     | 'CHIP0402'     | ''          | ''   | '20230713'
 '0.047UF'  | '50V'   | '10%'     | 'C0402'     | 'EMPTY'   | 'CH3476K1B10SEL1'(!) = ''              | ''                 | ''       | 'CH3476K1B10SEL1' |'C0402'| '(C0402-0201)'                                                       | 'NA'       | '50V'         | '10%'    | 'IO'       | 'CAP CHIP 0.047U 50V(10%,X7R,0402)MURSELA'                     | 'CHIP0402'     | ''          | ''   | '20230713'
 '0.047UF'  | '100V'  | '10%'     | 'C0805'     | 'X7R'     | 'CH3478K1A01SEL1'(!) = ''              | ''                 | ''       | 'CH3478K1A01SEL1' |'C0805_H57'| '(SMC0805AW)'                                                        | '0.047UF'  | '100V'        | '10%'    | 'DISCRETE' | 'CAPCHIP 0.047U 100V(10%,X7R,0805)MURSELA'                     | 'CHIP0805'     | ''          | ''   | '20230713'
 '0.047UF'  | '100V'  | '10%'     | 'C0805'     | 'EMPTY'   | 'CH3478K1A01SEL1'(!) = ''              | ''                 | ''       | 'CH3478K1A01SEL1' |'C0805_H57'| '(SMC0805AW)'                                                        | 'NA'       | '100V'        | '10%'    | 'IO'       | 'CAPCHIP 0.047U 100V(10%,X7R,0805)MURSELA'                     | 'CHIP0805'     | ''          | ''   | '20230713'
 '0.068UF'  | '16V'   | '10%'     | 'C0402'     | 'X7R'     | 'CH3683K1B02SEL1'(!) = ''              | ''                 | ''       | 'CH3683K1B02SEL1' |'C0402'| '(C0402-0201)'                                                       | '0.068UF'  | '16V'         | '10%'    | 'DISCRETE' | 'CAP CHIP 0.068U 16V(10%,X7R 0402)MURSELA'                     | 'CHIP0402'     | ''          | ''   | '20230713'
 '0.068UF'  | '16V'   | '10%'     | 'C0402'     | 'EMPTY'   | 'CH3683K1B02SEL1'(!) = ''              | ''                 | ''       | 'CH3683K1B02SEL1' |'C0402'| '(C0402-0201)'                                                       | 'NA'       | '16V'         | '10%'    | 'IO'       | 'CAP CHIP 0.068U 16V(10%,X7R 0402)MURSELA'                     | 'CHIP0402'     | ''          | ''   | '20230713'
 '0.1UF'    | '6.3V'  | '10%'     | 'C0402'     | 'X7R'     | 'CH4101K1B01SEL1'(!) = ''              | ''                 | ''       | 'CH4101K1B01SEL1' |'C0402'| '(C0402-0201)'                                                       | '0.1UF'    | '6.3V'        | '10%'    | 'DISCRETE' | 'CAP CHIP 0.1UF 6.3V(10%,X7R,0402)MURSELA'                     | 'CHIP0402'     | ''          | ''   | '20230713'
 '0.1UF'    | '6.3V'  | '10%'     | 'C0402'     | 'EMPTY'   | 'CH4101K1B01SEL1'(!) = ''              | ''                 | ''       | 'CH4101K1B01SEL1' |'C0402'| '(C0402-0201)'                                                       | 'NA'       | '6.3V'        | '10%'    | 'IO'       | 'CAP CHIP 0.1UF 6.3V(10%,X7R,0402)MURSELA'                     | 'CHIP0402'     | ''          | ''   | '20230713'
 '0.1UF'    | '6.3V'  | '10%'     | 'C0201'     | 'X6S'     | 'CH4101KEE02SEL1'(!) = ''              | ''                 | ''       | 'CH4101KEE02SEL1' |'C0201'| '(SMC0201AW)'                                                        | '0.1UF'    | '6.3V'        | '10%'    | 'DISCRETE' | 'CAP CHIP 0.1UF 6.3V(10%,X6S,0201)SAMSELA'                     | 'CHIP0201'     | ''          | ''   | '20230713'
 '0.1UF'    | '6.3V'  | '10%'     | 'C0201'     | 'EMPTY'   | 'CH4101KEE02SEL1'(!) = ''              | ''                 | ''       | 'CH4101KEE02SEL1' |'C0201'| '(SMC0201AW)'                                                        | 'NA'       | '6.3V'        | '10%'    | 'IO'       | 'CAP CHIP 0.1UF 6.3V(10%,X6S,0201)SAMSELA'                     | 'CHIP0201'     | ''          | ''   | '20230713'
 '0.1UF'    | '16V'   | '10%'     | 'C0402'     | 'X7R'     | 'CH4103K1B13SEL1'(!) = ''              | ''                 | ''       | 'CH4103K1B13SEL1' |'C0402'| '(C0402-0201)'                                                       | '0.1UF'    | '16V'         | '10%'    | 'DISCRETE' | 'CAP CHIP 0.1U 16V(10%,X7R,0402)MURSELA'                       | 'CHIP0402'     | ''          | ''   | '20230713'
 '0.1UF'    | '16V'   | '10%'     | 'C0402'     | 'EMPTY'   | 'CH4103K1B13SEL1'(!) = ''              | ''                 | ''       | 'CH4103K1B13SEL1' |'C0402'| '(C0402-0201)'                                                       | 'NA'       | '16V'         | '10%'    | 'IO'       | 'CAP CHIP 0.1U 16V(10%,X7R,0402)MURSELA'                       | 'CHIP0402'     | ''          | ''   | '20230713'
 '0.1UF'    | '16V'   | '10%'     | 'C0402'     | 'X7R'     | 'CH4103K1B14SEL1'(!) = ''              | ''                 | ''       | 'CH4103K1B14SEL1' |'C0402'| '(C0402-0201)'                                                       | '0.1UF'    | '16V'         | '10%'    | 'DISCRETE' | 'CAP CHIP 0.1U 16V(10%,X7R,0402)MURSELA'                       | 'CHIP0402'     | ''          | ''   | '20230713'
 '0.1UF'    | '16V'   | '10%'     | 'C0402'     | 'EMPTY'   | 'CH4103K1B14SEL1'(!) = ''              | ''                 | ''       | 'CH4103K1B14SEL1' |'C0402'| '(C0402-0201)'                                                       | 'NA'       | '16V'         | '10%'    | 'IO'       | 'CAP CHIP 0.1U 16V(10%,X7R,0402)MURSELA'                       | 'CHIP0402'     | ''          | ''   | '20230713'
 '0.1UF'    | '16V'   | '10%'     | 'C0402'     | 'X7R'     | 'CH4103K1B19SEL1'(!) = ''              | ''                 | ''       | 'CH4103K1B19SEL1' |'C0402'| '(C0402-0201)'                                                       | '0.1UF'    | '16V'         | '10%'    | 'DISCRETE' | 'CAP CHIP 0.1U 16V(10%,X7R,0402)SAMSELA'                       | 'CHIP0402'     | ''          | ''   | '20230713'
 '0.1UF'    | '16V'   | '10%'     | 'C0402'     | 'EMPTY'   | 'CH4103K1B19SEL1'(!) = ''              | ''                 | ''       | 'CH4103K1B19SEL1' |'C0402'| '(C0402-0201)'                                                       | 'NA'       | '16V'         | '10%'    | 'IO'       | 'CAP CHIP 0.1U 16V(10%,X7R,0402)SAMSELA'                       | 'CHIP0402'     | ''          | ''   | '20230713'
 '0.1UF'    | '16V'   | '10%'     | 'C0201'     | 'X6S'     | 'CH4103KEE03SEL1'(!) = ''              | ''                 | ''       | 'CH4103KEE03SEL1' |'C0201'| '(SMC0201AW)'                                                        | '0.1UF'    | '16V'         | '10%'    | 'DISCRETE' | 'CAP CHIP 0.1UF 16V(10%,X6S,0201)MURSELA'                      | 'CHIP0201'     | ''          | ''   | '20230713'
 '0.1UF'    | '16V'   | '10%'     | 'C0201'     | 'EMPTY'   | 'CH4103KEE03SEL1'(!) = ''              | ''                 | ''       | 'CH4103KEE03SEL1' |'C0201'| '(SMC0201AW)'                                                        | 'NA'       | '16V'         | '10%'    | 'IO'       | 'CAP CHIP 0.1UF 16V(10%,X6S,0201)MURSELA'                      | 'CHIP0201'     | ''          | ''   | '20230713'
 '0.1UF'    | '25V'   | '10%'     | 'C0603'     | 'X7R'     | 'CH4104K1909SEL1'(!) = ''              | ''                 | ''       | 'CH4104K1909SEL1' |'C0603'| '(SMC0603AW)'                                                        | '0.1UF'    | '25V'         | '10%'    | 'DISCRETE' | 'CAP CHIP 0.1UF 25V(10%,X7R,0603)MURSELA'                      | 'CHIP0603'     | ''          | ''   | '20230713'
 '0.1UF'    | '25V'   | '10%'     | 'C0603'     | 'EMPTY'   | 'CH4104K1909SEL1'(!) = ''              | ''                 | ''       | 'CH4104K1909SEL1' |'C0603'| '(SMC0603AW)'                                                        | 'NA'       | '25V'         | '10%'    | 'IO'       | 'CAP CHIP 0.1UF 25V(10%,X7R,0603)MURSELA'                      | 'CHIP0603'     | ''          | ''   | '20230713'
 '0.1UF'    | '25V'   | '10%'     | 'C0402'     | 'X7R'     | 'CH4104K1B03SEL1'(!) = ''              | ''                 | ''       | 'CH4104K1B03SEL1' |'C0402'| '(C0402-0201)'                                                       | '0.1UF'    | '25V'         | '10%'    | 'DISCRETE' | 'CAP CHIP 0.1U 25V(+-10%,X7R,0402)MURSELA'                     | 'CHIP0402'     | ''          | ''   | '20230713'
 '0.1UF'    | '25V'   | '10%'     | 'C0402'     | 'EMPTY'   | 'CH4104K1B03SEL1'(!) = ''              | ''                 | ''       | 'CH4104K1B03SEL1' |'C0402'| '(C0402-0201)'                                                       | 'NA'       | '25V'         | '10%'    | 'IO'       | 'CAP CHIP 0.1U 25V(+-10%,X7R,0402)MURSELA'                     | 'CHIP0402'     | ''          | ''   | '20230713'
 '100NF'    | '50V'   | '10%'     | 'C0402'     | 'X7R'     | 'CH4106K1B20SEL1'(!) = ''              | ''                 | ''       | 'CH4106K1B20SEL1' |'C0402'| '(C0402-0201)'                                                       | '100NF'    | '50V'         | '10%'    | 'DISCRETE' | 'CAP CHIP 100NF 50V(10%,X7R,0402)SAMSELA'                      | 'CHIP0402'     | ''          | ''   | '20230713'
 '100NF'    | '50V'   | '10%'     | 'C0402'     | 'EMPTY'   | 'CH4106K1B20SEL1'(!) = ''              | ''                 | ''       | 'CH4106K1B20SEL1' |'C0402'| '(C0402-0201)'                                                       | 'NA'       | '50V'         | '10%'    | 'IO'       | 'CAP CHIP 100NF 50V(10%,X7R,0402)SAMSELA'                      | 'CHIP0402'     | ''          | ''   | '20230713'
 '0.1UF'    | '100V'  | '10%'     | 'C1206'     | 'X7R'     | 'CH4108K1208SEL1'(!) = ''              | ''                 | ''       | 'CH4108K1208SEL1' |'C1206_H76'| '(SMC1206AW)'                                                        | '0.1UF'    | '100V'        | '10%'    | 'DISCRETE' | 'CAP CHIP 0.1UF 100V(10%,X7R,1206)TAYSELA'                     | 'CHIP1206'     | ''          | ''   | '20230713'
 '0.1UF'    | '100V'  | '10%'     | 'C1206'     | 'EMPTY'   | 'CH4108K1208SEL1'(!) = ''              | ''                 | ''       | 'CH4108K1208SEL1' |'C1206_H76'| '(SMC1206AW)'                                                        | 'NA'       | '100V'        | '10%'    | 'IO'       | 'CAP CHIP 0.1UF 100V(10%,X7R,1206)TAYSELA'                     | 'CHIP1206'     | ''          | ''   | '20230713'
 '0.1UF'    | '100V'  | '10%'     | 'C0805'     | 'X7R'     | 'CH4108K1A01SEL1'(!) = ''              | ''                 | ''       | 'CH4108K1A01SEL1' |'C0805_H61'| '(SMC0805AW)'                                                        | '0.1UF'    | '100V'        | '10%'    | 'DISCRETE' | 'CAP CHIP 0.1UF 100V(10%,X7R,0805)MURSELA'                     | 'CHIP0805'     | ''          | ''   | '20230713'
 '0.1UF'    | '100V'  | '10%'     | 'C0805'     | 'EMPTY'   | 'CH4108K1A01SEL1'(!) = ''              | ''                 | ''       | 'CH4108K1A01SEL1' |'C0805_H61'| '(SMC0805AW)'                                                        | 'NA'       | '100V'        | '10%'    | 'IO'       | 'CAP CHIP 0.1UF 100V(10%,X7R,0805)MURSELA'                     | 'CHIP0805'     | ''          | ''   | '20230713'
 '0.22UF'   | '6.3V'  | '10%'     | 'C0201'     | 'X6S'     | 'CH4221KEE01SEL1'(!) = ''              | ''                 | ''       | 'CH4221KEE01SEL1' |'C0201'| '(SMC0201AW)'                                                        | '0.22UF'   | '6.3V'        | '10%'    | 'DISCRETE' | 'CAP CHIP 0.22U 6.3V(10%,X6S,0201)MURSELA'                     | 'CHIP0201'     | ''          | ''   | '20230713'
 '0.22UF'   | '6.3V'  | '10%'     | 'C0201'     | 'EMPTY'   | 'CH4221KEE01SEL1'(!) = ''              | ''                 | ''       | 'CH4221KEE01SEL1' |'C0201'| '(SMC0201AW)'                                                        | 'NA'       | '6.3V'        | '10%'    | 'IO'       | 'CAP CHIP 0.22U 6.3V(10%,X6S,0201)MURSELA'                     | 'CHIP0201'     | ''          | ''   | '20230713'
 '0.22UF'   | '16V'   | '10%'     | 'C0402'     | 'X7R'     | 'CH4223K1B04SEL1'(!) = ''              | ''                 | ''       | 'CH4223K1B04SEL1' |'C0402'| '(C0402-0201)'                                                       | '0.22UF'   | '16V'         | '10%'    | 'DISCRETE' | 'CAP CHIP 0.22U 16V(10%,X7R,0402)MURSELA'                      | 'CHIP0402'     | ''          | ''   | '20230713'
 '0.22UF'   | '16V'   | '10%'     | 'C0402'     | 'EMPTY'   | 'CH4223K1B04SEL1'(!) = ''              | ''                 | ''       | 'CH4223K1B04SEL1' |'C0402'| '(C0402-0201)'                                                       | 'NA'       | '16V'         | '10%'    | 'IO'       | 'CAP CHIP 0.22U 16V(10%,X7R,0402)MURSELA'                      | 'CHIP0402'     | ''          | ''   | '20230713'
 '0.22UF'   | '25V'   | '10%'     | 'C0402'     | 'X7R'     | 'CH4224K1B03SEL1'(!) = ''              | ''                 | ''       | 'CH4224K1B03SEL1' |'C0402'| '(C0402-0201)'                                                       | '0.22UF'   | '25V'         | '10%'    | 'DISCRETE' | 'CAP CHIP 0.22UF 25V(10%,X7R,0402)MURSELA'                     | 'CHIP0402'     | ''          | ''   | '20230713'
 '0.22UF'   | '25V'   | '10%'     | 'C0402'     | 'EMPTY'   | 'CH4224K1B03SEL1'(!) = ''              | ''                 | ''       | 'CH4224K1B03SEL1' |'C0402'| '(C0402-0201)'                                                       | 'NA'       | '25V'         | '10%'    | 'IO'       | 'CAP CHIP 0.22UF 25V(10%,X7R,0402)MURSELA'                     | 'CHIP0402'     | ''          | ''   | '20230713'
 '0.47UF'   | '16V'   | '10%'     | 'C0603'     | 'X7R'     | 'CH4473K1904SEL1'(!) = ''              | ''                 | ''       | 'CH4473K1904SEL1' |'C0603'| '(SMC0603AW)'                                                        | '0.47UF'   | '16V'         | '10%'    | 'DISCRETE' | 'CAP CHIP 0.47U 16V (10%,X7R,0603)MURSELA'                     | 'CHIP0603'     | ''          | ''   | '20230713'
 '0.47UF'   | '16V'   | '10%'     | 'C0603'     | 'EMPTY'   | 'CH4473K1904SEL1'(!) = ''              | ''                 | ''       | 'CH4473K1904SEL1' |'C0603'| '(SMC0603AW)'                                                        | 'NA'       | '16V'         | '10%'    | 'IO'       | 'CAP CHIP 0.47U 16V (10%,X7R,0603)MURSELA'                     | 'CHIP0603'     | ''          | ''   | '20230713'
 '0.47UF'   | '100V'  | '10%'     | 'C0805'     | 'X7R'     | 'CH4478K1A01SEL1'(!) = ''              | ''                 | ''       | 'CH4478K1A01SEL1' |'C0805_H61'| '(SMC0805AW)'                                                        | '0.47UF'   | '100V'        | '10%'    | 'DISCRETE' | 'CAP CHIP 0.47U 100V(10%,X7R,0805)MURSELA'                     | 'CHIP0805'     | ''          | ''   | '20230713'
 '0.47UF'   | '100V'  | '10%'     | 'C0805'     | 'EMPTY'   | 'CH4478K1A01SEL1'(!) = ''              | ''                 | ''       | 'CH4478K1A01SEL1' |'C0805_H61'| '(SMC0805AW)'                                                        | 'NA'       | '100V'        | '10%'    | 'IO'       | 'CAP CHIP 0.47U 100V(10%,X7R,0805)MURSELA'                     | 'CHIP0805'     | ''          | ''   | '20230713'
 '1UF'      | '6.3V'  | '10%'     | 'C0402'     | 'X7R'     | 'CH5101K1B05SEL1'(!) = ''              | ''                 | ''       | 'CH5101K1B05SEL1' |'C0402'| '(C0402-0201)'                                                       | '1UF'      | '6.3V'        | '10%'    | 'DISCRETE' | 'CAP CHIP 1U,6.3V(+-10%,X7R,0402)MURSELA'                      | 'CHIP0402'     | ''          | ''   | '20230713'
 '1UF'      | '6.3V'  | '10%'     | 'C0402'     | 'EMPTY'   | 'CH5101K1B05SEL1'(!) = ''              | ''                 | ''       | 'CH5101K1B05SEL1' |'C0402'| '(C0402-0201)'                                                       | 'NA'       | '6.3V'        | '10%'    | 'IO'       | 'CAP CHIP 1U,6.3V(+-10%,X7R,0402)MURSELA'                      | 'CHIP0402'     | ''          | ''   | '20230713'
 '1UF'      | '10V'   | '10%'     | 'C0402'     | 'X6S'     | 'CH5102KEB02SEL1'(!) = ''              | ''                 | ''       | 'CH5102KEB02SEL1' |'C0402'| '(C0402-0201)'                                                       | '1UF'      | '10V'         | '10%'    | 'DISCRETE' | 'CAP CHIP 1UF 10V(+-10%,X6S,0402)MURSELA'                      | 'CHIP0402'     | ''          | ''   | '20230713'
 '1UF'      | '10V'   | '10%'     | 'C0402'     | 'EMPTY'   | 'CH5102KEB02SEL1'(!) = ''              | ''                 | ''       | 'CH5102KEB02SEL1' |'C0402'| '(C0402-0201)'                                                       | 'NA'       | '10V'         | '10%'    | 'IO'       | 'CAP CHIP 1UF 10V(+-10%,X6S,0402)MURSELA'                      | 'CHIP0402'     | ''          | ''   | '20230713'
 '1UF'      | '16V'   | '10%'     | 'C0402'     | 'X6S'     | 'CH5103KEB03SEL1'(!) = ''              | ''                 | ''       | 'CH5103KEB03SEL1' |'C0402'| '(C0402-0201)'                                                       | '1UF'      | '16V'         | '10%'    | 'DISCRETE' | 'CAP CHIP 1UF 16V(10%,X6S,0402)MURSELA'                        | 'CHIP0402'     | ''          | ''   | '20230713'
 '1UF'      | '16V'   | '10%'     | 'C0402'     | 'EMPTY'   | 'CH5103KEB03SEL1'(!) = ''              | ''                 | ''       | 'CH5103KEB03SEL1' |'C0402'| '(C0402-0201)'                                                       | 'NA'       | '16V'         | '10%'    | 'IO'       | 'CAP CHIP 1UF 16V(10%,X6S,0402)MURSELA'                        | 'CHIP0402'     | ''          | ''   | '20230713'
 '1UF'      | '25V'   | '10%'     | 'C0603'     | 'X7R'     | 'CH5104K1903SEL1'(!) = ''              | ''                 | ''       | 'CH5104K1903SEL1' |'C0603'| '(SMC0603AW)'                                                        | '1UF'      | '25V'         | '10%'    | 'DISCRETE' | 'CAP CHIP 1U 25V(+-10%.X7R.0603)MURSELA'                       | 'CHIP0603'     | ''          | ''   | '20230713'
 '1UF'      | '25V'   | '10%'     | 'C0603'     | 'EMPTY'   | 'CH5104K1903SEL1'(!) = ''              | ''                 | ''       | 'CH5104K1903SEL1' |'C0603'| '(SMC0603AW)'                                                        | 'NA'       | '25V'         | '10%'    | 'IO'       | 'CAP CHIP 1U 25V(+-10%.X7R.0603)MURSELA'                       | 'CHIP0603'     | ''          | ''   | '20230713'
 '1UF'      | '25V'   | '10%'     | 'C0402'     | 'X6S'     | 'CH5104KEB03SEL1'(!) = ''              | ''                 | ''       | 'CH5104KEB03SEL1' |'C0402'| '(C0402-0201)'                                                       | '1UF'      | '25V'         | '10%'    | 'DISCRETE' | 'CAP CHIP 1UF 25V(+-10%,X6S,0402)MURSELA'                      | 'CHIP0402'     | ''          | ''   | '20230713'
 '1UF'      | '25V'   | '10%'     | 'C0402'     | 'EMPTY'   | 'CH5104KEB03SEL1'(!) = ''              | ''                 | ''       | 'CH5104KEB03SEL1' |'C0402'| '(C0402-0201)'                                                       | 'NA'       | '25V'         | '10%'    | 'IO'       | 'CAP CHIP 1UF 25V(+-10%,X6S,0402)MURSELA'                      | 'CHIP0402'     | ''          | ''   | '20230713'
 '1UF'      | '25V'   | '10%'     | 'C0402'     | 'X6S'     | 'CH5104KEB04SEL1'(!) = ''              | ''                 | ''       | 'CH5104KEB04SEL1' |'C0402'| '(C0402-0201)'                                                       | '1UF'      | '25V'         | '10%'    | 'DISCRETE' | 'CAP CHIP 1UF 25V(+-10%,X6S,0402)SAMSELA'                      | 'CHIP0402'     | ''          | ''   | '20230713'
 '1UF'      | '25V'   | '10%'     | 'C0402'     | 'EMPTY'   | 'CH5104KEB04SEL1'(!) = ''              | ''                 | ''       | 'CH5104KEB04SEL1' |'C0402'| '(C0402-0201)'                                                       | 'NA'       | '25V'         | '10%'    | 'IO'       | 'CAP CHIP 1UF 25V(+-10%,X6S,0402)SAMSELA'                      | 'CHIP0402'     | ''          | ''   | '20230713'
 '1UF'      | '100V'  | '10%'     | 'C1206'     | 'X7R'     | 'CH5108K1201SEL1'(!) = ''              | ''                 | ''       | 'CH5108K1201SEL1' |'C1206_H66'| '(SMC1206AW)'                                                        | '1UF'      | '100V'        | '10%'    | 'DISCRETE' | 'CAP CHIP 1U 100V(10%.1206.X7R)MURSELA'                        | 'CHIP1206'     | ''          | ''   | '20230713'
 '1UF'      | '100V'  | '10%'     | 'C1206'     | 'EMPTY'   | 'CH5108K1201SEL1'(!) = ''              | ''                 | ''       | 'CH5108K1201SEL1' |'C1206_H66'| '(SMC1206AW)'                                                        | 'NA'       | '100V'        | '10%'    | 'IO'       | 'CAP CHIP 1U 100V(10%.1206.X7R)MURSELA'                        | 'CHIP1206'     | ''          | ''   | '20230713'
 '2.2UF'    | '6.3V'  | '20%'     | 'C0402'     | 'X6S'     | 'CH5221MEB03SEL1'(!) = ''              | ''                 | ''       | 'CH5221MEB03SEL1' |'C0402'| '(C0402-0201)'                                                       | '2.2UF'    | '6.3V'        | '20%'    | 'DISCRETE' | 'CAP CHIP 2.2U 6.3V(20%,X6S,0402)MURSELA'                      | 'CHIP0402'     | ''          | ''   | '20230713'
 '2.2UF'    | '6.3V'  | '20%'     | 'C0402'     | 'EMPTY'   | 'CH5221MEB03SEL1'(!) = ''              | ''                 | ''       | 'CH5221MEB03SEL1' |'C0402'| '(C0402-0201)'                                                       | 'NA'       | '6.3V'        | '20%'    | 'IO'       | 'CAP CHIP 2.2U 6.3V(20%,X6S,0402)MURSELA'                      | 'CHIP0402'     | ''          | ''   | '20230713'
 '2.2UF'    | '10V'   | '10%'     | 'C0603'     | 'X7R'     | 'CH5222K1904SEL1'(!) = ''              | ''                 | ''       | 'CH5222K1904SEL1' |'C0603'| '(SMC0603AW)'                                                        | '2.2UF'    | '10V'         | '10%'    | 'DISCRETE' | 'CAP CHIP 2.2UF 10V(10%,X7R,0603)MURSELA'                      | 'CHIP0603'     | ''          | ''   | '20230713'
 '2.2UF'    | '10V'   | '10%'     | 'C0603'     | 'EMPTY'   | 'CH5222K1904SEL1'(!) = ''              | ''                 | ''       | 'CH5222K1904SEL1' |'C0603'| '(SMC0603AW)'                                                        | 'NA'       | '10V'         | '10%'    | 'IO'       | 'CAP CHIP 2.2UF 10V(10%,X7R,0603)MURSELA'                      | 'CHIP0603'     | ''          | ''   | '20230713'
 '2.2UF'    | '10V'   | '10%'     | 'C0402'     | 'X6S'     | 'CH5222KEB02SEL1'(!) = ''              | ''                 | ''       | 'CH5222KEB02SEL1' |'C0402_H28'| '(C0402-0201_H28)'                                                   | '2.2UF'    | '10V'         | '10%'    | 'DISCRETE' | 'CAP CHIP 2.2UF 10V(10%,X6S,0402)MURSELA'                      | 'CHIP0402'     | ''          | ''   | '20230713'
 '2.2UF'    | '10V'   | '10%'     | 'C0402'     | 'EMPTY'   | 'CH5222KEB02SEL1'(!) = ''              | ''                 | ''       | 'CH5222KEB02SEL1' |'C0402_H28'| '(C0402-0201_H28)'                                                   | 'NA'       | '10V'         | '10%'    | 'IO'       | 'CAP CHIP 2.2UF 10V(10%,X6S,0402)MURSELA'                      | 'CHIP0402'     | ''          | ''   | '20230713'
 '2.2UF'    | '16V'   | '20%'     | 'C0402'     | 'X6S'     | 'CH5223MEB01SEL1'(!) = ''              | ''                 | ''       | 'CH5223MEB01SEL1' |'C0402'| '(C0402-0201)'                                                       | '2.2UF'    | '16V'         | '20%'    | 'DISCRETE' | 'CAP CHIP 2.2U 16V(20%,X6S,0402)MURSELASN'                     | 'CHIP0402'     | ''          | ''   | '20230713'
 '2.2UF'    | '16V'   | '20%'     | 'C0402'     | 'EMPTY'   | 'CH5223MEB01SEL1'(!) = ''              | ''                 | ''       | 'CH5223MEB01SEL1' |'C0402'| '(C0402-0201)'                                                       | 'NA'       | '16V'         | '20%'    | 'IO'       | 'CAP CHIP 2.2U 16V(20%,X6S,0402)MURSELASN'                     | 'CHIP0402'     | ''          | ''   | '20230713'
 '2.2UF'    | '100V'  | '10%'     | 'C1206'     | 'X7R'     | 'CH5228K1207SEL1'(!) = ''              | ''                 | ''       | 'CH5228K1207SEL1' |'C1206_H66'| '(SMC1206AW)'                                                        | '2.2UF'    | '100V'        | '10%'    | 'DISCRETE' | 'CAP CHIP 2.2UF 100V(10%,X7R,1206)MURSELA'                     | 'CHIP1206'     | ''          | ''   | '20230713'
 '2.2UF'    | '100V'  | '10%'     | 'C1206'     | 'EMPTY'   | 'CH5228K1207SEL1'(!) = ''              | ''                 | ''       | 'CH5228K1207SEL1' |'C1206_H66'| '(SMC1206AW)'                                                        | 'NA'       | '100V'        | '10%'    | 'IO'       | 'CAP CHIP 2.2UF 100V(10%,X7R,1206)MURSELA'                     | 'CHIP1206'     | ''          | ''   | '20230713'
 '2.2UF'    | '100V'  | '10%'     | 'C1206'     | 'X7R'     | 'CH5228K1208SEL1'(!) = ''              | ''                 | ''       | 'CH5228K1208SEL1' |'C1206_H66'| '(SMC1206AW)'                                                        | '2.2UF'    | '100V'        | '10%'    | 'DISCRETE' | 'CAP CHIP 2.2UF 100V(10%,X7R,1206)SAMSELA'                     | 'CHIP1206'     | ''          | ''   | '20230713'
 '2.2UF'    | '100V'  | '10%'     | 'C1206'     | 'EMPTY'   | 'CH5228K1208SEL1'(!) = ''              | ''                 | ''       | 'CH5228K1208SEL1' |'C1206_H66'| '(SMC1206AW)'                                                        | 'NA'       | '100V'        | '10%'    | 'IO'       | 'CAP CHIP 2.2UF 100V(10%,X7R,1206)SAMSELA'                     | 'CHIP1206'     | ''          | ''   | '20230713'
 '4.7UF'    | '6.3V'  | '20%'     | 'C0402'     | 'X6S'     | 'CH5471MEB02SEL1'(!) = ''              | ''                 | ''       | 'CH5471MEB02SEL1' |'C0402'| '(C0402-0201)'                                                       | '4.7UF'    | '6.3V'        | '20%'    | 'DISCRETE' | 'CAP CHIP 4.7UF 6.3V(20%,X6S,0402)MURSELA'                     | 'CHIP0402'     | ''          | ''   | '20230713'
 '4.7UF'    | '6.3V'  | '20%'     | 'C0402'     | 'EMPTY'   | 'CH5471MEB02SEL1'(!) = ''              | ''                 | ''       | 'CH5471MEB02SEL1' |'C0402'| '(C0402-0201)'                                                       | 'NA'       | '6.3V'        | '20%'    | 'IO'       | 'CAP CHIP 4.7UF 6.3V(20%,X6S,0402)MURSELA'                     | 'CHIP0402'     | ''          | ''   | '20230713'
 '4.7UF'    | '16V'   | '10%'     | 'C0603'     | 'X6S'     | 'CH5473KE903SEL1'(!) = ''              | ''                 | ''       | 'CH5473KE903SEL1' |'C0603_H40'| '(SMC0603AW)'                                                        | '4.7UF'    | '16V'         | '10%'    | 'DISCRETE' | 'CAP CHIP 4.7UF 16V(10%,X6S,0603)MURSELA'                      | 'CHIP0603'     | ''          | ''   | '20230713'
 '4.7UF'    | '16V'   | '10%'     | 'C0603'     | 'EMPTY'   | 'CH5473KE903SEL1'(!) = ''              | ''                 | ''       | 'CH5473KE903SEL1' |'C0603_H40'| '(SMC0603AW)'                                                        | 'NA'       | '16V'         | '10%'    | 'IO'       | 'CAP CHIP 4.7UF 16V(10%,X6S,0603)MURSELA'                      | 'CHIP0603'     | ''          | ''   | '20230713'
 '4.7UF'    | '25V'   | '10%'     | 'C0603'     | 'X6S'     | 'CH5474KE902SEL1'(!) = ''              | ''                 | ''       | 'CH5474KE902SEL1' |'C0603'| '(SMC0603AW)'                                                        | '4.7UF'    | '25V'         | '10%'    | 'DISCRETE' | 'CAP CHIP 4.7UF 25V(10%,X6S,0603)MURSELA'                      | 'CHIP0603'     | ''          | ''   | '20230713'
 '4.7UF'    | '25V'   | '10%'     | 'C0603'     | 'EMPTY'   | 'CH5474KE902SEL1'(!) = ''              | ''                 | ''       | 'CH5474KE902SEL1' |'C0603'| '(SMC0603AW)'                                                        | 'NA'       | '25V'         | '10%'    | 'IO'       | 'CAP CHIP 4.7UF 25V(10%,X6S,0603)MURSELA'                      | 'CHIP0603'     | ''          | ''   | '20230713'
 '10UF'     | '6.3V'  | '20%'     | 'C0603'     | 'X6S'     | 'CH6101ME902SEL1'(!) = ''              | ''                 | ''       | 'CH6101ME902SEL1' |'C0603'| '(SMC0603AW)'                                                        | '10UF'     | '6.3V'        | '20%'    | 'DISCRETE' | 'CAP CHIP 10U 6.3V(+-20%,X6S,0603)MURSELA'                     | 'CHIP0603'     | ''          | ''   | '20230713'
 '10UF'     | '6.3V'  | '20%'     | 'C0603'     | 'EMPTY'   | 'CH6101ME902SEL1'(!) = ''              | ''                 | ''       | 'CH6101ME902SEL1' |'C0603'| '(SMC0603AW)'                                                        | 'NA'       | '6.3V'        | '20%'    | 'IO'       | 'CAP CHIP 10U 6.3V(+-20%,X6S,0603)MURSELA'                     | 'CHIP0603'     | ''          | ''   | '20230713'
 '10UF'     | '6.3V'  | '20%'     | 'C0402'     | 'X6S'     | 'CH6101MEB03SEL1'(!) = ''              | ''                 | ''       | 'CH6101MEB03SEL1' |'C0402'| '(C0402-0201)'                                                       | '10UF'     | '6.3V'        | '20%'    | 'DISCRETE' | 'CAP CHIP 10UF 6.3V(20%,X6S,0402)MURSELA'                      | 'CHIP0402'     | ''          | ''   | '20230713'
 '10UF'     | '6.3V'  | '20%'     | 'C0402'     | 'EMPTY'   | 'CH6101MEB03SEL1'(!) = ''              | ''                 | ''       | 'CH6101MEB03SEL1' |'C0402'| '(C0402-0201)'                                                       | 'NA'       | '6.3V'        | '20%'    | 'IO'       | 'CAP CHIP 10UF 6.3V(20%,X6S,0402)MURSELA'                      | 'CHIP0402'     | ''          | ''   | '20230713'
 '10UF'     | '6.3V'  | '20%'     | 'C0402'     | 'X6S'     | 'CH6101MEB08SEL1'(!) = ''              | ''                 | ''       | 'CH6101MEB08SEL1' |'C0402_H28'| '(C0402-0201_H28)'                                                   | '10UF'     | '6.3V'        | '20%'    | 'DISCRETE' | 'CAP CHIP 10UF 6.3V(20%,X6S,0402)SAMSELA'                      | 'CHIP0402'     | ''          | ''   | '20230713'
 '10UF'     | '6.3V'  | '20%'     | 'C0402'     | 'EMPTY'   | 'CH6101MEB08SEL1'(!) = ''              | ''                 | ''       | 'CH6101MEB08SEL1' |'C0402_H28'| '(C0402-0201_H28)'                                                   | 'NA'       | '6.3V'        | '20%'    | 'IO'       | 'CAP CHIP 10UF 6.3V(20%,X6S,0402)SAMSELA'                      | 'CHIP0402'     | ''          | ''   | '20230713'
 '10UF'     | '16V'   | '10%'     | 'C0805'     | 'X7R'     | 'CH6103K1A01SEL1'(!) = ''              | ''                 | ''       | 'CH6103K1A01SEL1' |'C0805_H61'| '(SMC0805AW)'                                                        | '10UF'     | '16V'         | '10%'    | 'DISCRETE' | 'CAP CHIP 10UF 16V(+-10%,X7R,0805)SAMSELA'                     | 'CHIP0805'     | ''          | ''   | '20230713'
 '10UF'     | '16V'   | '10%'     | 'C0805'     | 'EMPTY'   | 'CH6103K1A01SEL1'(!) = ''              | ''                 | ''       | 'CH6103K1A01SEL1' |'C0805_H61'| '(SMC0805AW)'                                                        | 'NA'       | '16V'         | '10%'    | 'IO'       | 'CAP CHIP 10UF 16V(+-10%,X7R,0805)SAMSELA'                     | 'CHIP0805'     | ''          | ''   | '20230713'
 '10UF'     | '16V'   | '10%'     | 'C0805'     | 'X6S'     | 'CH6103KEA01SEL1'(!) = ''              | ''                 | ''       | 'CH6103KEA01SEL1' |'C0805_H57'| '(SMC0805AW)'                                                        | '10UF'     | '16V'         | '10%'    | 'DISCRETE' | 'CAP CHIP 10UF 16V(+-10%,X6S,0805)MURSELA'                     | 'CHIP0805'     | ''          | ''   | '20230713'
 '10UF'     | '16V'   | '10%'     | 'C0805'     | 'EMPTY'   | 'CH6103KEA01SEL1'(!) = ''              | ''                 | ''       | 'CH6103KEA01SEL1' |'C0805_H57'| '(SMC0805AW)'                                                        | 'NA'       | '16V'         | '10%'    | 'IO'       | 'CAP CHIP 10UF 16V(+-10%,X6S,0805)MURSELA'                     | 'CHIP0805'     | ''          | ''   | '20230713'
 '10UF'     | '16V'   | '20%'     | 'C0603'     | 'X6S'     | 'CH6103ME904SEL1'(!) = ''              | ''                 | ''       | 'CH6103ME904SEL1' |'C0603'| '(SMC0603AW)'                                                        | '10UF'     | '16V'         | '20%'    | 'DISCRETE' | 'CAP CHIP 10UF 16V(20%,X6S,0603)MURSELASN'                     | 'CHIP0603'     | ''          | ''   | '20230713'
 '10UF'     | '16V'   | '20%'     | 'C0603'     | 'EMPTY'   | 'CH6103ME904SEL1'(!) = ''              | ''                 | ''       | 'CH6103ME904SEL1' |'C0603'| '(SMC0603AW)'                                                        | 'NA'       | '16V'         | '20%'    | 'IO'       | 'CAP CHIP 10UF 16V(20%,X6S,0603)MURSELASN'                     | 'CHIP0603'     | ''          | ''   | '20230713'
 '10UF'     | '25V'   | '10%'     | 'C0805'     | 'X6S'     | 'CH6104KEA03SEL1'(!) = ''              | ''                 | ''       | 'CH6104KEA03SEL1' |'C0805_H61'| '(SMC0805AW)'                                                        | '10UF'     | '25V'         | '10%'    | 'DISCRETE' | 'CAP CHIP 10U 25V(10%,X6S,0805)MURSELASN'                      | 'CHIP0805'     | ''          | ''   | '20230713'
 '10UF'     | '25V'   | '10%'     | 'C0805'     | 'EMPTY'   | 'CH6104KEA03SEL1'(!) = ''              | ''                 | ''       | 'CH6104KEA03SEL1' |'C0805_H61'| '(SMC0805AW)'                                                        | 'NA'       | '25V'         | '10%'    | 'IO'       | 'CAP CHIP 10U 25V(10%,X6S,0805)MURSELASN'                      | 'CHIP0805'     | ''          | ''   | '20230713'
 '10UF'     | '25V'   | '10%'     | 'C0805'     | 'X6S'     | 'CH6104KEA08SEL1'(!) = ''              | ''                 | ''       | 'CH6104KEA08SEL1' |'C0805_H57'| '(SMC0805AW)'                                                        | '10UF'     | '25V'         | '10%'    | 'DISCRETE' | 'CAP CHIP 10U 25V(10%,X6S,0805)TAYSELASN'                      | 'CHIP0805'     | ''          | ''   | '20230713'
 '10UF'     | '25V'   | '10%'     | 'C0805'     | 'EMPTY'   | 'CH6104KEA08SEL1'(!) = ''              | ''                 | ''       | 'CH6104KEA08SEL1' |'C0805_H57'| '(SMC0805AW)'                                                        | 'NA'       | '25V'         | '10%'    | 'IO'       | 'CAP CHIP 10U 25V(10%,X6S,0805)TAYSELASN'                      | 'CHIP0805'     | ''          | ''   | '20230713'
 '10UF'     | '50V'   | '10%'     | 'C1210'     | 'X7R'     | 'CH6106K1303SEL1'(!) = ''              | ''                 | ''       | 'CH6106K1303SEL1' |'C1210_GRM32E'| '(SMC1210AW)'                                                        | '10UF'     | '50V'         | '10%'    | 'DISCRETE' | 'CAP CHIP 10U 50V(10%,X7R,1210)MURSELASN'                      | 'CHIP1210'     | ''          | ''   | '20230713'
 '10UF'     | '50V'   | '10%'     | 'C1210'     | 'EMPTY'   | 'CH6106K1303SEL1'(!) = ''              | ''                 | ''       | 'CH6106K1303SEL1' |'C1210_GRM32E'| '(SMC1210AW)'                                                        | 'NA'       | '50V'         | '10%'    | 'IO'       | 'CAP CHIP 10U 50V(10%,X7R,1210)MURSELASN'                      | 'CHIP1210'     | ''          | ''   | '20230713'
 '10UF'     | '100V'  | '10%'     | 'C1210'     | 'X7S'     | 'CH6108K6300SEL1'(!) = ''              | ''                 | ''       | 'CH6108K6300SEL1' |'C1210_GRM32E'| '(SMC1210AW)'                                                        | '10UF'     | '100V'        | '10%'    | 'DISCRETE' | 'CAP CHIP 10UF 100V(10%,X7S,1210)MURSELA'                      | 'CHIP1210'     | ''          | ''   | '20230713'
 '10UF'     | '100V'  | '10%'     | 'C1210'     | 'EMPTY'   | 'CH6108K6300SEL1'(!) = ''              | ''                 | ''       | 'CH6108K6300SEL1' |'C1210_GRM32E'| '(SMC1210AW)'                                                        | 'NA'       | '100V'        | '10%'    | 'IO'       | 'CAP CHIP 10UF 100V(10%,X7S,1210)MURSELA'                      | 'CHIP1210'     | ''          | ''   | '20230713'
 '22UF'     | '6.3V'  | '20%'     | 'C0603'     | 'X6S'     | 'CH6221ME901SEL1'(!) = ''              | ''                 | ''       | 'CH6221ME901SEL1' |'C0603'| '(SMC0603AW)'                                                        | '22UF'     | '6.3V'        | '20%'    | 'DISCRETE' | 'CAP CHIP 22U 6.3V(20%,X6S,0603)MURSELASN'                     | 'CHIP0603'     | ''          | ''   | '20230713'
 '22UF'     | '6.3V'  | '20%'     | 'C0603'     | 'EMPTY'   | 'CH6221ME901SEL1'(!) = ''              | ''                 | ''       | 'CH6221ME901SEL1' |'C0603'| '(SMC0603AW)'                                                        | 'NA'       | '6.3V'        | '20%'    | 'IO'       | 'CAP CHIP 22U 6.3V(20%,X6S,0603)MURSELASN'                     | 'CHIP0603'     | ''          | ''   | '20230713'
 '22UF'     | '6.3V'  | '20%'     | 'C0603'     | 'X6S'     | 'CH6221ME907SEL1'(!) = ''              | ''                 | ''       | 'CH6221ME907SEL1' |'C0603_H40'| '(SMC0603AW)'                                                        | '22UF'     | '6.3V'        | '20%'    | 'DISCRETE' | 'CAP CHIP 22U 6.3V(20%,X6S,0603)SAMSELASN'                     | 'CHIP0603'     | ''          | ''   | '20230713'
 '22UF'     | '6.3V'  | '20%'     | 'C0603'     | 'EMPTY'   | 'CH6221ME907SEL1'(!) = ''              | ''                 | ''       | 'CH6221ME907SEL1' |'C0603_H40'| '(SMC0603AW)'                                                        | 'NA'       | '6.3V'        | '20%'    | 'IO'       | 'CAP CHIP 22U 6.3V(20%,X6S,0603)SAMSELASN'                     | 'CHIP0603'     | ''          | ''   | '20230713'
 '22UF'     | '6.3V'  | '20%'     | 'C0805'     | 'X6S'     | 'CH6221MEA04SEL1'(!) = ''              | ''                 | ''       | 'CH6221MEA04SEL1' |'C0805_H61'| '(SMC0805AW)'                                                        | '22UF'     | '6.3V'        | '20%'    | 'DISCRETE' | 'CAP CHIP 22U 6.3V(+-20%,X6S,0805)MURSELA'                     | 'CHIP0805'     | ''          | ''   | '20230713'
 '22UF'     | '6.3V'  | '20%'     | 'C0805'     | 'EMPTY'   | 'CH6221MEA04SEL1'(!) = ''              | ''                 | ''       | 'CH6221MEA04SEL1' |'C0805_H61'| '(SMC0805AW)'                                                        | 'NA'       | '6.3V'        | '20%'    | 'IO'       | 'CAP CHIP 22U 6.3V(+-20%,X6S,0805)MURSELA'                     | 'CHIP0805'     | ''          | ''   | '20230713'
 '22UF'     | '6.3V'  | '20%'     | 'C0805'     | 'X6S'     | 'CH6221MEA06SEL1'(!) = ''              | ''                 | ''       | 'CH6221MEA06SEL1' |'C0805_H57'| '(SMC0805AW)'                                                        | '22UF'     | '6.3V'        | '20%'    | 'DISCRETE' | 'CAP CHIP 22U 6.3V(+-20%,X6S,0805)SAMSELA'                     | 'CHIP0805'     | ''          | ''   | '20230713'
 '22UF'     | '6.3V'  | '20%'     | 'C0805'     | 'EMPTY'   | 'CH6221MEA06SEL1'(!) = ''              | ''                 | ''       | 'CH6221MEA06SEL1' |'C0805_H57'| '(SMC0805AW)'                                                        | 'NA'       | '6.3V'        | '20%'    | 'IO'       | 'CAP CHIP 22U 6.3V(+-20%,X6S,0805)SAMSELA'                     | 'CHIP0805'     | ''          | ''   | '20230713'
 '22UF'     | '10V'   | '20%'     | 'C0805'     | 'X6S'     | 'CH6222MEA01SEL1'(!) = ''              | ''                 | ''       | 'CH6222MEA01SEL1' |'C0805_H61'| '(SMC0805AW)'                                                        | '22UF'     | '10V'         | '20%'    | 'DISCRETE' | 'CAP CHIP 22U 10V(20%,X6S,0805)MURSELASN'                      | 'CHIP0805'     | ''          | ''   | '20230713'
 '22UF'     | '10V'   | '20%'     | 'C0805'     | 'EMPTY'   | 'CH6222MEA01SEL1'(!) = ''              | ''                 | ''       | 'CH6222MEA01SEL1' |'C0805_H61'| '(SMC0805AW)'                                                        | 'NA'       | '10V'         | '20%'    | 'IO'       | 'CAP CHIP 22U 10V(20%,X6S,0805)MURSELASN'                      | 'CHIP0805'     | ''          | ''   | '20230713'
 '22UF'     | '16V'   | '20%'     | 'C0805'     | 'X6S'     | 'CH6223MEA01SEL1'(!) = ''              | ''                 | ''       | 'CH6223MEA01SEL1' |'C0805_H57'| '(SMC0805AW)'                                                        | '22UF'     | '16V'         | '20%'    | 'DISCRETE' | 'CAP CHIP 22UF 16V(+-20%,X6S,0805)MURSELA'                     | 'CHIP0805'     | ''          | ''   | '20230713'
 '22UF'     | '16V'   | '20%'     | 'C0805'     | 'EMPTY'   | 'CH6223MEA01SEL1'(!) = ''              | ''                 | ''       | 'CH6223MEA01SEL1' |'C0805_H57'| '(SMC0805AW)'                                                        | 'NA'       | '16V'         | '20%'    | 'IO'       | 'CAP CHIP 22UF 16V(+-20%,X6S,0805)MURSELA'                     | 'CHIP0805'     | ''          | ''   | '20230713'
 '22UF'     | '25V'   | '20%'     | 'C0805'     | 'X5R'     | 'CH6224M9A05SEL1'(!) = ''              | ''                 | ''       | 'CH6224M9A05SEL1' |'C0805_H57'| '(SMC0805AW)'                                                        | '22UF'     | '25V'         | '20%'    | 'DISCRETE' | 'CAP CHIP 22U 25V(20%,X5R,0805)MURSELASN'                      | 'CHIP0805'     | ''          | ''   | '20230713'
 '22UF'     | '25V'   | '20%'     | 'C0805'     | 'EMPTY'   | 'CH6224M9A05SEL1'(!) = ''              | ''                 | ''       | 'CH6224M9A05SEL1' |'C0805_H57'| '(SMC0805AW)'                                                        | 'NA'       | '25V'         | '20%'    | 'IO'       | 'CAP CHIP 22U 25V(20%,X5R,0805)MURSELASN'                      | 'CHIP0805'     | ''          | ''   | '20230713'
 '22UF'     | '4V'    | '20%'     | 'C0603'     | 'X6S'     | 'CH622KME905SEL1'(!) = ''              | ''                 | ''       | 'CH622KME905SEL1' |'C0603'| '(SMC0603AW)'                                                        | '22UF'     | '4V'          | '20%'    | 'DISCRETE' | 'CAP CHIP 22UF 4V(+-20%,X6S,0603)MURSELA'                      | 'CHIP0603'     | ''          | ''   | '20230713'
 '22UF'     | '4V'    | '20%'     | 'C0603'     | 'EMPTY'   | 'CH622KME905SEL1'(!) = ''              | ''                 | ''       | 'CH622KME905SEL1' |'C0603'| '(SMC0603AW)'                                                        | 'NA'       | '4V'          | '20%'    | 'IO'       | 'CAP CHIP 22UF 4V(+-20%,X6S,0603)MURSELA'                      | 'CHIP0603'     | ''          | ''   | '20230713'
 '22UF'     | '4V'    | '20%'     | 'C0805'     | 'X6S'     | 'CH622KMEA03SEL1'(!) = ''              | ''                 | ''       | 'CH622KMEA03SEL1' |'C0805_H61'| '(SMC0805AW)'                                                        | '22UF'     | '4V'          | '20%'    | 'DISCRETE' | 'CAP CHIP 22U 4V(+-20%,X6S,0805)MURSELA'                       | 'CHIP0805'     | ''          | ''   | '20230713'
 '22UF'     | '4V'    | '20%'     | 'C0805'     | 'EMPTY'   | 'CH622KMEA03SEL1'(!) = ''              | ''                 | ''       | 'CH622KMEA03SEL1' |'C0805_H61'| '(SMC0805AW)'                                                        | 'NA'       | '4V'          | '20%'    | 'IO'       | 'CAP CHIP 22U 4V(+-20%,X6S,0805)MURSELA'                       | 'CHIP0805'     | ''          | ''   | '20230713'
 '22UF'     | '4V'    | '20%'     | 'C0805'     | 'X6S'     | 'CH622KMEA04SEL1'(!) = ''              | ''                 | ''       | 'CH622KMEA04SEL1' |'C0805_H57'| '(SMC0805AW)'                                                        | '22UF'     | '4V'          | '20%'    | 'DISCRETE' | 'CAP CHIP 22U 4V(+-20%,X6S,0805)SAMSELA'                       | 'CHIP0805'     | ''          | ''   | '20230713'
 '22UF'     | '4V'    | '20%'     | 'C0805'     | 'EMPTY'   | 'CH622KMEA04SEL1'(!) = ''              | ''                 | ''       | 'CH622KMEA04SEL1' |'C0805_H57'| '(SMC0805AW)'                                                        | 'NA'       | '4V'          | '20%'    | 'IO'       | 'CAP CHIP 22U 4V(+-20%,X6S,0805)SAMSELA'                       | 'CHIP0805'     | ''          | ''   | '20230713'
 '22UF'     | '4V'    | '20%'     | 'C0402'     | 'X6S'     | 'CH622KMEB01SEL1'(!) = ''              | ''                 | ''       | 'CH622KMEB01SEL1' |'C0402_H32'| '(C0402-0201_H32)'                                                   | '22UF'     | '4V'          | '20%'    | 'DISCRETE' | 'CAP CHIP 22UF 4V(+-20%,X6S,0402)MURSELA'                      | 'CHIP0402'     | ''          | ''   | '20230713'
 '22UF'     | '4V'    | '20%'     | 'C0402'     | 'EMPTY'   | 'CH622KMEB01SEL1'(!) = ''              | ''                 | ''       | 'CH622KMEB01SEL1' |'C0402_H32'| '(C0402-0201_H32)'                                                   | 'NA'       | '4V'          | '20%'    | 'IO'       | 'CAP CHIP 22UF 4V(+-20%,X6S,0402)MURSELA'                      | 'CHIP0402'     | ''          | ''   | '20230713'
 '47UF'     | '6.3V'  | '20%'     | 'C0805'     | 'X5R'     | 'CH6471M9A08SEL1'(!) = ''              | ''                 | ''       | 'CH6471M9A08SEL1' |'C0805_H57'| '(SMC0805AW)'                                                        | '47UF'     | '6.3V'        | '20%'    | 'DISCRETE' | 'CAP CHIP 47U 6.3V(20%,X5R,0805)MURSELASN'                     | 'CHIP0805'     | ''          | ''   | '20230713'
 '47UF'     | '6.3V'  | '20%'     | 'C0805'     | 'EMPTY'   | 'CH6471M9A08SEL1'(!) = ''              | ''                 | ''       | 'CH6471M9A08SEL1' |'C0805_H57'| '(SMC0805AW)'                                                        | 'NA'       | '6.3V'        | '20%'    | 'IO'       | 'CAP CHIP 47U 6.3V(20%,X5R,0805)MURSELASN'                     | 'CHIP0805'     | ''          | ''   | '20230713'
 '47UF'     | '4V'    | '20%'     | 'C0805'     | 'X6S'     | 'CH647KMEA04SEL1'(!) = ''              | ''                 | ''       | 'CH647KMEA04SEL1' |'C0805_H57'| '(SMC0805AW)'                                                        | '47UF'     | '4V'          | '20%'    | 'DISCRETE' | 'CAP CHIP 47U 4V(+-20%,X6S,0805)MURSELA'                       | 'CHIP0805'     | ''          | ''   | '20230713'
 '47UF'     | '4V'    | '20%'     | 'C0805'     | 'EMPTY'   | 'CH647KMEA04SEL1'(!) = ''              | ''                 | ''       | 'CH647KMEA04SEL1' |'C0805_H57'| '(SMC0805AW)'                                                        | 'NA'       | '4V'          | '20%'    | 'IO'       | 'CAP CHIP 47U 4V(+-20%,X6S,0805)MURSELA'                       | 'CHIP0805'     | ''          | ''   | '20230713'
 '47UF'     | '2.5V'  | '20%'     | 'C0603'     | 'X6S'     | 'CH647LME900SEL1'(!) = ''              | ''                 | ''       | 'CH647LME900SEL1' |'C0603'| '(SMC0603AW)'                                                        | '47UF'     | '2.5V'        | '20%'    | 'DISCRETE' | 'CAP CHIP 47U 2.5V(20%,X6S,0603)MURSELASN'                     | 'CHIP0603'     | ''          | ''   | '20230713'
 '47UF'     | '2.5V'  | '20%'     | 'C0603'     | 'EMPTY'   | 'CH647LME900SEL1'(!) = ''              | ''                 | ''       | 'CH647LME900SEL1' |'C0603'| '(SMC0603AW)'                                                        | 'NA'       | '2.5V'        | '20%'    | 'IO'       | 'CAP CHIP 47U 2.5V(20%,X6S,0603)MURSELASN'                     | 'CHIP0603'     | ''          | ''   | '20230713'
 '100UF'    | '4V'    | '20%'     | 'C0805'     | 'X6S'     | 'CH710KMEA01SEL1'(!) = ''              | ''                 | ''       | 'CH710KMEA01SEL1' |'C0805_H61'| '(SMC0805AW)'                                                        | '100UF'    | '4V'          | '20%'    | 'DISCRETE' | 'CAP CHIP 100U 4V(20%,X6S,0805)MURSELASN'                      | 'CHIP0805'     | ''          | ''   | '20230713'
 '100UF'    | '4V'    | '20%'     | 'C0805'     | 'EMPTY'   | 'CH710KMEA01SEL1'(!) = ''              | ''                 | ''       | 'CH710KMEA01SEL1' |'C0805_H61'| '(SMC0805AW)'                                                        | 'NA'       | '4V'          | '20%'    | 'IO'       | 'CAP CHIP 100U 4V(20%,X6S,0805)MURSELASN'                      | 'CHIP0805'     | ''          | ''   | '20230713'
 '4.7UF'    | '2.5V'  | '20%'     | 'C0201'     | 'X6S'     | 'CH547LMEE00'(!)   = ''              | ''                 | ''       | 'CH547LMEE00'     |'C0201_H16'| '(SMC0201AW)'                                                        | '4.7UF'    | '2.5V'        | '20%'    | 'DISCRETE' | 'CAP CHIP 4.7U 2.5V(+-20%,X6S,0201)'                           | 'CHIP0201'     | ''          | ''   | '20230801'
 '4.7UF'    | '2.5V'  | '20%'     | 'C0201'     | 'EMPTY'   | 'CH547LMEE00'(!)   = ''              | ''                 | ''       | 'CH547LMEE00'     |'C0201_H16'| '(SMC0201AW)'                                                        | 'NA'       | '2.5V'        | '20%'    | 'IO'       | 'CAP CHIP 4.7U 2.5V(+-20%,X6S,0201)'                           | 'CHIP0201'     | ''          | ''   | '20230801'
 '180PF'    | '50V'   | '5%'      | 'C0402'     | 'NPO'     | 'CH1186J0B17'(!)   = ''              | ''                 | ''       | 'CH1186J0B17'     |'C0402'| '(C0402-0201)'                                                       | '180PF'    | '50V'         | '5%'     | 'DISCRETE' | 'CAP CHIP 180P 50V(+-5%,NPO,0402)YGO'                          | 'CHIP0402'     | ''          | ''   | '20230801'
 '180PF'    | '50V'   | '5%'      | 'C0402'     | 'EMPTY'   | 'CH1186J0B17'(!)   = ''              | ''                 | ''       | 'CH1186J0B17'     |'C0402'| '(C0402-0201)'                                                       | 'NA'       | '50V'         | '5%'     | 'IO'       | 'CAP CHIP 180P 50V(+-5%,NPO,0402)YGO'                          | 'CHIP0402'     | ''          | ''   | '20230801'
 '2700PF'   | '50V'   | '10%'     | 'C0402'     | 'X7R'     | 'CH2276K1B10'(!)   = ''              | ''                 | ''       | 'CH2276K1B10'     |'C0402'| '(C0402-0201)'                                                       | '2700PF'   | '50V'         | '10%'    | 'DISCRETE' | 'CAP CHIP 2700P 50V(+-10%,X7R,0402)YGO'                        | 'CHIP0402'     | ''          | ''   | '20230802'
 '2700PF'   | '50V'   | '10%'     | 'C0402'     | 'EMPTY'   | 'CH2276K1B10'(!)   = ''              | ''                 | ''       | 'CH2276K1B10'     |'C0402'| '(C0402-0201)'                                                       | 'NA'       | '50V'         | '10%'    | 'IO'       | 'CAP CHIP 2700P 50V(+-10%,X7R,0402)YGO'                        | 'CHIP0402'     | ''          | ''   | '20230802'
 '4.7UF'    | '2.5V'  | '20%'     | 'C0201'     | 'X6S'     | 'CH547LMEE01'(!)   = ''              | ''                 | ''       | 'CH547LMEE01'     |'C0201_H22'| '(SMC0201AW)'                                                        | '4.7UF'    | '2.5V'        | '20%'    | 'DISCRETE' | 'CAP CHIP 4.7U 2.5V(+-20%,X6S,0201,H0.55)'                     | 'CHIP0201'     | ''          | ''   | '20230816'
 '4.7UF'    | '2.5V'  | '20%'     | 'C0201'     | 'EMPTY'   | 'CH547LMEE01'(!)   = ''              | ''                 | ''       | 'CH547LMEE01'     |'C0201_H22'| '(SMC0201AW)'                                                        | 'NA'       | '2.5V'        | '20%'    | 'IO'       | 'CAP CHIP 4.7U 2.5V(+-20%,X6S,0201,H0.55)'                     | 'CHIP0201'     | ''          | ''   | '20230816'
 '0.068UF'  | '16V'   | '10%'     | 'C0402'     | 'X7R'     | 'CH3683K1B04'(!)   = ''              | ''               | ''       | 'CH3683K1B04'     |'C0402'| '(C0402-0201)'                                                       | '0.068UF'  | '16V'         | '10%'    | 'DISCRETE' | 'CAP CHIP 0.068UF 16V(+-10%,X7R 0402)SAM'                      | 'CHIP0402'     | ''          | ''   | '20230824'
 '0.068UF'  | '16V'   | '10%'     | 'C0402'     | 'EMPTY'   | 'CH3683K1B04'(!)   = ''              | ''               | ''       | 'CH3683K1B04'     |'C0402'| '(C0402-0201)'                                                       | 'NA'       | '16V'         | '10%'    | 'IO'       | 'CAP CHIP 0.068UF 16V(+-10%,X7R 0402)SAM'                      | 'CHIP0402'     | ''          | ''   | '20230824'
 '0.068UF'  | '16V'   | '10%'     | 'C0402'     | 'X7R'     | 'CH3683K1B04SEL1'(!) = ''              | ''               | ''       | 'CH3683K1B04SEL1' |'C0402'| '(C0402-0201)'                                                       | '0.068UF'  | '16V'         | '10%'    | 'DISCRETE' | 'CAP CHIP 0.068U 16V(10%,X7R 0402)SAMSELA'                     | 'CHIP0402'     | ''          | ''   | '20230824'
 '0.068UF'  | '16V'   | '10%'     | 'C0402'     | 'EMPTY'   | 'CH3683K1B04SEL1'(!) = ''              | ''               | ''       | 'CH3683K1B04SEL1' |'C0402'| '(C0402-0201)'                                                       | 'NA'       | '16V'         | '10%'    | 'IO'       | 'CAP CHIP 0.068U 16V(10%,X7R 0402)SAMSELA'                     | 'CHIP0402'     | ''          | ''   | '20230824'
 '1UF'      | '10V'   | '10%'     | 'C0402'     | 'X6S'     | 'CH5102KEB03'(!)   = ''              | ''               | ''       | 'CH5102KEB03'     |'C0402'| '(C0402-0201)'                                                       | '1UF'      | '10V'         | '10%'    | 'DISCRETE' | 'CAP CHIP 1UF 10V(+-10%,X6S,0402)SAM'                          | 'CHIP0402'     | ''          | ''   | '20230824'
 '1UF'      | '10V'   | '10%'     | 'C0402'     | 'EMPTY'   | 'CH5102KEB03'(!)   = ''              | ''               | ''       | 'CH5102KEB03'     |'C0402'| '(C0402-0201)'                                                       | 'NA'       | '10V'         | '10%'    | 'IO'       | 'CAP CHIP 1UF 10V(+-10%,X6S,0402)SAM'                          | 'CHIP0402'     | ''          | ''   | '20230824'
 '1UF'      | '10V'   | '10%'     | 'C0402'     | 'X6S'     | 'CH5102KEB03SEL1'(!) = ''              | ''               | ''       | 'CH5102KEB03SEL1' |'C0402'| '(C0402-0201)'                                                       | '1UF'      | '10V'         | '10%'    | 'DISCRETE' | 'CAP CHIP 1UF 10V(+-10%,X6S,0402)SAMSELA'                      | 'CHIP0402'     | ''          | ''   | '20230824'
 '1UF'      | '10V'   | '10%'     | 'C0402'     | 'EMPTY'   | 'CH5102KEB03SEL1'(!) = ''              | ''               | ''       | 'CH5102KEB03SEL1' |'C0402'| '(C0402-0201)'                                                       | 'NA'       | '10V'         | '10%'    | 'IO'       | 'CAP CHIP 1UF 10V(+-10%,X6S,0402)SAMSELA'                      | 'CHIP0402'     | ''          | ''   | '20230824'
 '0.01UF'   | '25V'   | '5%'      | 'C0402'     | 'X7R'     | 'CH3104J1B04'(!)   = ''               | ''               | ''       | 'CH3104J1B04'     |'C0402'| '(C0402-0201)'                                                       | '0.01UF'   | '25V'         | '5%'     | 'DISCRETE' | 'CAP CHIP 0.01U 25V (+-5%,X7R,0402)WTC'                        | 'CHIP0402'     | ''          | ''   | '20230824'
 '0.01UF'   | '25V'   | '5%'      | 'C0402'     | 'EMPTY'   | 'CH3104J1B04'(!)   = ''               | ''               | ''       | 'CH3104J1B04'     |'C0402'| '(C0402-0201)'                                                       | 'NA'       | '25V'         | '5%'     | 'IO'       | 'CAP CHIP 0.01U 25V (+-5%,X7R,0402)WTC'                        | 'CHIP0402'     | ''          | ''   | '20230824'

END_PART

END.

